(kicad_pcb
	(version 20260206)
	(generator "pcbnew")
	(generator_version "10.0")
	(general
		(thickness 1.6)
		(legacy_teardrops no)
	)
	(paper "A4")
	(layers
		(0 "F.Cu" signal "TOP")
		(4 "In1.Cu" signal "L2GND")
		(6 "In2.Cu" signal "L3")
		(8 "In3.Cu" signal "L4VCC")
		(10 "In4.Cu" signal "L5VCC")
		(12 "In5.Cu" signal "L6")
		(14 "In6.Cu" signal "L7GND")
		(2 "B.Cu" signal "BOTTOM")
		(9 "F.Adhes" user "F.Adhesive")
		(11 "B.Adhes" user "B.Adhesive")
		(13 "F.Paste" user "Package Geometry/Pastemask Top")
		(15 "B.Paste" user "Package Geometry/Pastemask Bottom")
		(5 "F.SilkS" user "Ref Des/Silkscreen Top")
		(7 "B.SilkS" user "Ref Des/Silkscreen Bottom")
		(1 "F.Mask" user "Board Geometry/Soldermask Top")
		(3 "B.Mask" user "Board Geometry/Soldermask Bottom")
		(17 "Dwgs.User" user "User.Drawings")
		(19 "Cmts.User" user "User.Comments")
		(21 "Eco1.User" user "User.Eco1")
		(23 "Eco2.User" user "User.Eco2")
		(25 "Edge.Cuts" user "Board Geometry/Outline")
		(27 "Margin" user)
		(31 "F.CrtYd" user "Package Geometry/Place Bound Top")
		(29 "B.CrtYd" user "Package Geometry/Place Bound Bottom")
		(35 "F.Fab" user "Ref Des/Assembly Top")
		(33 "B.Fab" user "Ref Des/Assembly Bottom")
	)
	(setup
		(pad_to_mask_clearance 0)
		(allow_soldermask_bridges_in_footprints no)
		(tenting
			(front yes)
			(back yes)
		)
		(covering
			(front no)
			(back no)
		)
		(plugging
			(front no)
			(back no)
		)
		(capping no)
		(filling no)
		(pcbplotparams
			(layerselection 0x00000000_00000000_55555555_5755f5ff)
			(plot_on_all_layers_selection 0x00000000_00000000_00000000_00000000)
			(disableapertmacros no)
			(usegerberextensions no)
			(usegerberattributes yes)
			(usegerberadvancedattributes yes)
			(creategerberjobfile yes)
			(dashed_line_dash_ratio 12)
			(dashed_line_gap_ratio 3)
			(svgprecision 4)
			(plotframeref no)
			(mode 1)
			(useauxorigin no)
			(pdf_front_fp_property_popups yes)
			(pdf_back_fp_property_popups yes)
			(pdf_metadata yes)
			(pdf_single_document no)
			(dxfpolygonmode yes)
			(dxfimperialunits yes)
			(dxfusepcbnewfont yes)
			(psnegative no)
			(psa4output no)
			(plot_black_and_white yes)
			(sketchpadsonfab no)
			(plotpadnumbers no)
			(hidednponfab no)
			(sketchdnponfab yes)
			(crossoutdnponfab yes)
			(subtractmaskfromsilk no)
			(outputformat 1)
			(mirror no)
			(drillshape 1)
			(scaleselection 1)
			(outputdirectory "")
		)
	)
	(footprint ""
		(layer "F.Cu")
		(at 55.117746 -175.7807)
		(property "Reference" "C238"
			(at 0 0 0)
			(layer "F.SilkS")
			(hide yes)
			(effects
				(font
					(size 1.27 1.27)
				)
			)
		)
		(property "Value" "SCD01U50V2KX-1GP"
			(at 1.1811 -2.7051 0)
			(unlocked yes)
			(layer "F.Fab")
			(hide yes)
			(effects
				(font
					(size 1.016 1.016)
					(thickness 0.1524)
				)
			)
		)
		(property "Device Type" "C402H22"
			(at 1.1811 -4.2291 0)
			(unlocked yes)
			(layer "F.Fab")
			(hide yes)
			(effects
				(font
					(size 1.016 1.016)
					(thickness 0.1524)
				)
			)
		)
		(duplicate_pad_numbers_are_jumpers no)
		(fp_rect
			(start -0.4318 0.9525)
			(end 0.4318 -0.9525)
			(stroke
				(width 0)
				(type default)
			)
			(fill no)
			(layer "F.CrtYd")
		)
		(fp_rect
			(start -0.4318 0.9525)
			(end 0.4318 -0.9525)
			(stroke
				(width 0)
				(type default)
			)
			(fill no)
			(layer "F.Fab")
		)
		(pad "1" smd custom
			(at 0 -0.4445)
			(size 0.1524 0.1524)
			(layers "F.Cu" "F.Mask" "F.Paste")
			(net "HDD_PRSNT_NET8")
			(options
				(clearance outline)
				(anchor circle)
			)
			(primitives
				(gr_poly
					(pts
						(arc
							(start 0.3048 -0.2032)
							(mid 0.275042 -0.275042)
							(end 0.2032 -0.3048)
						)
						(arc
							(start -0.2032 -0.3048)
							(mid -0.275042 -0.275042)
							(end -0.3048 -0.2032)
						)
						(arc
							(start -0.3048 0.2032)
							(mid -0.275042 0.275042)
							(end -0.2032 0.3048)
						)
						(arc
							(start 0.2032 0.3048)
							(mid 0.275042 0.275042)
							(end 0.3048 0.2032)
						)
					)
					(width 0)
					(fill yes)
				)
			)
		)
		(pad "2" smd custom
			(at 0 0.4445)
			(size 0.1524 0.1524)
			(layers "F.Cu" "F.Mask" "F.Paste")
			(net "GND")
			(options
				(clearance outline)
				(anchor circle)
			)
			(primitives
				(gr_poly
					(pts
						(arc
							(start 0.3048 -0.2032)
							(mid 0.275042 -0.275042)
							(end 0.2032 -0.3048)
						)
						(arc
							(start -0.2032 -0.3048)
							(mid -0.275042 -0.275042)
							(end -0.3048 -0.2032)
						)
						(arc
							(start -0.3048 0.2032)
							(mid -0.275042 0.275042)
							(end -0.2032 0.3048)
						)
						(arc
							(start 0.2032 0.3048)
							(mid 0.275042 0.275042)
							(end 0.3048 0.2032)
						)
					)
					(width 0)
					(fill yes)
				)
			)
		)
	)
	(footprint ""
		(layer "F.Cu")
		(at 80.898746 -399.6817)
		(property "Reference" "Q14"
			(at 0 0 0)
			(layer "F.SilkS")
			(hide yes)
			(effects
				(font
					(size 1.27 1.27)
				)
			)
		)
		(property "Value" "2N7002DW-7F-GP"
			(at -2.3622 -8.2042 0)
			(unlocked yes)
			(layer "F.Fab")
			(hide yes)
			(effects
				(font
					(size 1.016 1.016)
					(thickness 0.1524)
				)
			)
		)
		(property "Device Type" "SOT-363H44"
			(at -2.3622 -10.1092 0)
			(unlocked yes)
			(layer "F.Fab")
			(hide yes)
			(effects
				(font
					(size 1.016 1.016)
					(thickness 0.1524)
				)
			)
		)
		(duplicate_pad_numbers_are_jumpers no)
		(fp_line
			(start -1.4478 -1.7018)
			(end -1.4478 1.7018)
			(stroke
				(width 0.1524)
				(type default)
			)
			(layer "F.SilkS")
		)
		(fp_line
			(start -1.4478 1.7018)
			(end 1.4478 1.7018)
			(stroke
				(width 0.1524)
				(type default)
			)
			(layer "F.SilkS")
		)
		(fp_line
			(start -1.27 1.524)
			(end -1.27 0.6604)
			(stroke
				(width 0.4826)
				(type default)
			)
			(layer "F.SilkS")
		)
		(fp_line
			(start 1.4478 -1.7018)
			(end -1.4478 -1.7018)
			(stroke
				(width 0.1524)
				(type default)
			)
			(layer "F.SilkS")
		)
		(fp_line
			(start 1.4478 1.7018)
			(end 1.4478 -1.7018)
			(stroke
				(width 0.1524)
				(type default)
			)
			(layer "F.SilkS")
		)
		(fp_poly
			(pts
				(xy -1.524 -1.778) (xy 1.524 -1.778) (xy 1.524 1.778) (xy -1.524 1.778)
			)
			(stroke
				(width 0)
				(type default)
			)
			(fill no)
			(layer "F.CrtYd")
		)
		(fp_poly
			(pts
				(xy -1.524 -1.778) (xy 1.524 -1.778) (xy 1.524 1.778) (xy -1.524 1.778)
			)
			(stroke
				(width 0)
				(type default)
			)
			(fill no)
			(layer "F.Fab")
		)
		(pad "1" smd rect
			(at -0.65024 0.9398)
			(size 0.4064 1.016)
			(layers "F.Cu" "F.Mask" "F.Paste")
			(net "GND")
		)
		(pad "2" smd rect
			(at 0 0.9398)
			(size 0.4064 1.016)
			(layers "F.Cu" "F.Mask" "F.Paste")
			(net "SW_PWR_R_HDD6")
		)
		(pad "3" smd rect
			(at 0.65024 0.9398)
			(size 0.4064 1.016)
			(layers "F.Cu" "F.Mask" "F.Paste")
			(net "SW_HDD6_P")
		)
		(pad "4" smd rect
			(at 0.65024 -0.9398)
			(size 0.4064 1.016)
			(layers "F.Cu" "F.Mask" "F.Paste")
			(net "GND")
		)
		(pad "5" smd rect
			(at 0 -0.9398)
			(size 0.4064 1.016)
			(layers "F.Cu" "F.Mask" "F.Paste")
			(net "SW_HDD6_G")
		)
		(pad "6" smd rect
			(at -0.65024 -0.9398)
			(size 0.4064 1.016)
			(layers "F.Cu" "F.Mask" "F.Paste")
			(net "SW_HDD6_R")
		)
	)
	(footprint ""
		(layer "F.Cu")
		(at 32.257746 -284.2387)
		(property "Reference" "TP32"
			(at 0 0 0)
			(layer "F.SilkS")
			(hide yes)
			(effects
				(font
					(size 1.27 1.27)
				)
			)
		)
		(property "Value" "TPAD32-GP"
			(at 0 -3.166364 0)
			(unlocked yes)
			(layer "F.Fab")
			(hide yes)
			(effects
				(font
					(size 1.016 1.016)
					(thickness 0.1524)
				)
			)
		)
		(property "Device Type" "TPAD32"
			(at 0 -4.690618 0)
			(unlocked yes)
			(layer "F.Fab")
			(hide yes)
			(effects
				(font
					(size 1.016 1.016)
					(thickness 0.1524)
				)
			)
		)
		(duplicate_pad_numbers_are_jumpers no)
		(fp_poly
			(pts
				(arc
					(start 0.4064 0)
					(mid -0.4064 0)
					(end 0.4064 0)
				)
			)
			(stroke
				(width 0)
				(type default)
			)
			(fill no)
			(layer "F.CrtYd")
		)
		(fp_poly
			(pts
				(arc
					(start 0.7112 0)
					(mid -0.7112 0)
					(end 0.7112 0)
				)
			)
			(stroke
				(width 0)
				(type default)
			)
			(fill no)
			(layer "F.Fab")
		)
		(pad "1" smd circle
			(at 0 0)
			(size 0.8128 0.8128)
			(layers "F.Cu" "F.Mask" "F.Paste")
			(net "ACT_HDD7")
		)
	)
	(footprint ""
		(layer "F.Cu")
		(at 57.911492 -72.926956 -90)
		(property "Reference" "R235"
			(at 0 0 270)
			(layer "F.SilkS")
			(hide yes)
			(effects
				(font
					(size 1.27 1.27)
				)
			)
		)
		(property "Value" "4K7R2J-2-GP"
			(at 0.064008 -3.993896 270)
			(unlocked yes)
			(layer "F.Fab")
			(hide yes)
			(effects
				(font
					(size 1.016 1.016)
					(thickness 0.1524)
				)
			)
		)
		(property "Device Type" "R402H16"
			(at 0.064008 -5.517896 270)
			(unlocked yes)
			(layer "F.Fab")
			(hide yes)
			(effects
				(font
					(size 1.016 1.016)
					(thickness 0.1524)
				)
			)
		)
		(duplicate_pad_numbers_are_jumpers no)
		(fp_line
			(start -0.508 -0.9398)
			(end -0.508 0.9398)
			(stroke
				(width 0.1524)
				(type default)
			)
			(layer "F.SilkS")
		)
		(fp_line
			(start 0.508 -0.9398)
			(end -0.508 -0.9398)
			(stroke
				(width 0.1524)
				(type default)
			)
			(layer "F.SilkS")
		)
		(fp_rect
			(start -0.508 0.9398)
			(end 0.508 -0.9398)
			(stroke
				(width 0)
				(type default)
			)
			(fill no)
			(layer "F.CrtYd")
		)
		(fp_rect
			(start -0.508 0.9398)
			(end 0.508 -0.9398)
			(stroke
				(width 0)
				(type default)
			)
			(fill no)
			(layer "F.Fab")
		)
		(pad "1" smd custom
			(at 0 -0.4445 270)
			(size 0.1397 0.1397)
			(layers "F.Cu" "F.Mask" "F.Paste")
			(net "P3V3")
			(options
				(clearance outline)
				(anchor circle)
			)
			(primitives
				(gr_poly
					(pts
						(arc
							(start -0.1778 -0.2794)
							(mid -0.249642 -0.249642)
							(end -0.2794 -0.1778)
						)
						(arc
							(start -0.2794 0.1778)
							(mid -0.249642 0.249642)
							(end -0.1778 0.2794)
						)
						(arc
							(start 0.1778 0.2794)
							(mid 0.249642 0.249642)
							(end 0.2794 0.1778)
						)
						(arc
							(start 0.2794 -0.1778)
							(mid 0.249642 -0.249642)
							(end 0.1778 -0.2794)
						)
					)
					(width 0)
					(fill yes)
				)
			)
		)
		(pad "2" smd custom
			(at 0 0.4445 270)
			(size 0.1397 0.1397)
			(layers "F.Cu" "F.Mask" "F.Paste")
			(net "HDD_PRSNT_NET9")
			(options
				(clearance outline)
				(anchor circle)
			)
			(primitives
				(gr_poly
					(pts
						(arc
							(start -0.1778 -0.2794)
							(mid -0.249642 -0.249642)
							(end -0.2794 -0.1778)
						)
						(arc
							(start -0.2794 0.1778)
							(mid -0.249642 0.249642)
							(end -0.1778 0.2794)
						)
						(arc
							(start 0.1778 0.2794)
							(mid 0.249642 0.249642)
							(end 0.2794 0.1778)
						)
						(arc
							(start 0.2794 -0.1778)
							(mid 0.249642 -0.249642)
							(end 0.1778 -0.2794)
						)
					)
					(width 0)
					(fill yes)
				)
			)
		)
	)
	(footprint ""
		(layer "F.Cu")
		(at 211.200746 -40.9067 180)
		(property "Reference" "R333"
			(at 0 0 180)
			(layer "F.SilkS")
			(hide yes)
			(effects
				(font
					(size 1.27 1.27)
				)
			)
		)
		(property "Value" "4K7R2J-2-GP"
			(at 0.064008 -3.993896 180)
			(unlocked yes)
			(layer "F.Fab")
			(hide yes)
			(effects
				(font
					(size 1.016 1.016)
					(thickness 0.1524)
				)
			)
		)
		(property "Device Type" "R402H16"
			(at 0.064008 -5.517896 180)
			(unlocked yes)
			(layer "F.Fab")
			(hide yes)
			(effects
				(font
					(size 1.016 1.016)
					(thickness 0.1524)
				)
			)
		)
		(duplicate_pad_numbers_are_jumpers no)
		(fp_line
			(start 0.508 -0.9398)
			(end -0.508 -0.9398)
			(stroke
				(width 0.1524)
				(type default)
			)
			(layer "F.SilkS")
		)
		(fp_line
			(start -0.508 -0.9398)
			(end -0.508 0.9398)
			(stroke
				(width 0.1524)
				(type default)
			)
			(layer "F.SilkS")
		)
		(fp_rect
			(start -0.508 0.9398)
			(end 0.508 -0.9398)
			(stroke
				(width 0)
				(type default)
			)
			(fill no)
			(layer "F.CrtYd")
		)
		(fp_rect
			(start -0.508 0.9398)
			(end 0.508 -0.9398)
			(stroke
				(width 0)
				(type default)
			)
			(fill no)
			(layer "F.Fab")
		)
		(pad "1" smd custom
			(at 0 -0.4445 180)
			(size 0.1397 0.1397)
			(layers "F.Cu" "F.Mask" "F.Paste")
			(net "P3V3")
			(options
				(clearance outline)
				(anchor circle)
			)
			(primitives
				(gr_poly
					(pts
						(arc
							(start -0.1778 -0.2794)
							(mid -0.249642 -0.249642)
							(end -0.2794 -0.1778)
						)
						(arc
							(start -0.2794 0.1778)
							(mid -0.249642 0.249642)
							(end -0.1778 0.2794)
						)
						(arc
							(start 0.1778 0.2794)
							(mid 0.249642 0.249642)
							(end 0.2794 0.1778)
						)
						(arc
							(start 0.2794 -0.1778)
							(mid 0.249642 -0.249642)
							(end 0.1778 -0.2794)
						)
					)
					(width 0)
					(fill yes)
				)
			)
		)
		(pad "2" smd custom
			(at 0 0.4445 180)
			(size 0.1397 0.1397)
			(layers "F.Cu" "F.Mask" "F.Paste")
			(net "I2C_B_TMP4_A0")
			(options
				(clearance outline)
				(anchor circle)
			)
			(primitives
				(gr_poly
					(pts
						(arc
							(start -0.1778 -0.2794)
							(mid -0.249642 -0.249642)
							(end -0.2794 -0.1778)
						)
						(arc
							(start -0.2794 0.1778)
							(mid -0.249642 0.249642)
							(end -0.1778 0.2794)
						)
						(arc
							(start 0.1778 0.2794)
							(mid 0.249642 0.249642)
							(end 0.2794 0.1778)
						)
						(arc
							(start 0.2794 -0.1778)
							(mid 0.249642 -0.249642)
							(end 0.1778 -0.2794)
						)
					)
					(width 0)
					(fill yes)
				)
			)
		)
	)
	(footprint ""
		(layer "F.Cu")
		(at 80.898746 -90.4367)
		(property "Reference" "Q20"
			(at 0 0 0)
			(layer "F.SilkS")
			(hide yes)
			(effects
				(font
					(size 1.27 1.27)
				)
			)
		)
		(property "Value" "2N7002DW-7F-GP"
			(at -2.3622 -8.2042 0)
			(unlocked yes)
			(layer "F.Fab")
			(hide yes)
			(effects
				(font
					(size 1.016 1.016)
					(thickness 0.1524)
				)
			)
		)
		(property "Device Type" "SOT-363H44"
			(at -2.3622 -10.1092 0)
			(unlocked yes)
			(layer "F.Fab")
			(hide yes)
			(effects
				(font
					(size 1.016 1.016)
					(thickness 0.1524)
				)
			)
		)
		(duplicate_pad_numbers_are_jumpers no)
		(fp_line
			(start -1.4478 -1.7018)
			(end -1.4478 1.7018)
			(stroke
				(width 0.1524)
				(type default)
			)
			(layer "F.SilkS")
		)
		(fp_line
			(start -1.4478 1.7018)
			(end 1.4478 1.7018)
			(stroke
				(width 0.1524)
				(type default)
			)
			(layer "F.SilkS")
		)
		(fp_line
			(start -1.27 1.524)
			(end -1.27 0.6604)
			(stroke
				(width 0.4826)
				(type default)
			)
			(layer "F.SilkS")
		)
		(fp_line
			(start 1.4478 -1.7018)
			(end -1.4478 -1.7018)
			(stroke
				(width 0.1524)
				(type default)
			)
			(layer "F.SilkS")
		)
		(fp_line
			(start 1.4478 1.7018)
			(end 1.4478 -1.7018)
			(stroke
				(width 0.1524)
				(type default)
			)
			(layer "F.SilkS")
		)
		(fp_poly
			(pts
				(xy -1.524 -1.778) (xy 1.524 -1.778) (xy 1.524 1.778) (xy -1.524 1.778)
			)
			(stroke
				(width 0)
				(type default)
			)
			(fill no)
			(layer "F.CrtYd")
		)
		(fp_poly
			(pts
				(xy -1.524 -1.778) (xy 1.524 -1.778) (xy 1.524 1.778) (xy -1.524 1.778)
			)
			(stroke
				(width 0)
				(type default)
			)
			(fill no)
			(layer "F.Fab")
		)
		(pad "1" smd rect
			(at -0.65024 0.9398)
			(size 0.4064 1.016)
			(layers "F.Cu" "F.Mask" "F.Paste")
			(net "GND")
		)
		(pad "2" smd rect
			(at 0 0.9398)
			(size 0.4064 1.016)
			(layers "F.Cu" "F.Mask" "F.Paste")
			(net "SW_PWR_R_HDD9")
		)
		(pad "3" smd rect
			(at 0.65024 0.9398)
			(size 0.4064 1.016)
			(layers "F.Cu" "F.Mask" "F.Paste")
			(net "SW_HDD9_P")
		)
		(pad "4" smd rect
			(at 0.65024 -0.9398)
			(size 0.4064 1.016)
			(layers "F.Cu" "F.Mask" "F.Paste")
			(net "GND")
		)
		(pad "5" smd rect
			(at 0 -0.9398)
			(size 0.4064 1.016)
			(layers "F.Cu" "F.Mask" "F.Paste")
			(net "SW_HDD9_G")
		)
		(pad "6" smd rect
			(at -0.65024 -0.9398)
			(size 0.4064 1.016)
			(layers "F.Cu" "F.Mask" "F.Paste")
			(net "SW_HDD9_R")
		)
	)
	(footprint ""
		(layer "F.Cu")
		(at 166.382446 -459.901036)
		(property "Reference" "TP150"
			(at 0 0 0)
			(layer "F.SilkS")
			(hide yes)
			(effects
				(font
					(size 1.27 1.27)
				)
			)
		)
		(property "Value" "TPAD32-GP"
			(at 0 -3.166364 0)
			(unlocked yes)
			(layer "F.Fab")
			(hide yes)
			(effects
				(font
					(size 1.016 1.016)
					(thickness 0.1524)
				)
			)
		)
		(property "Device Type" "TPAD32"
			(at 0 -4.690618 0)
			(unlocked yes)
			(layer "F.Fab")
			(hide yes)
			(effects
				(font
					(size 1.016 1.016)
					(thickness 0.1524)
				)
			)
		)
		(duplicate_pad_numbers_are_jumpers no)
		(fp_poly
			(pts
				(arc
					(start 0.4064 0)
					(mid -0.4064 0)
					(end 0.4064 0)
				)
			)
			(stroke
				(width 0)
				(type default)
			)
			(fill no)
			(layer "F.CrtYd")
		)
		(fp_poly
			(pts
				(arc
					(start 0.7112 0)
					(mid -0.7112 0)
					(end 0.7112 0)
				)
			)
			(stroke
				(width 0)
				(type default)
			)
			(fill no)
			(layer "F.Fab")
		)
		(pad "1" smd circle
			(at 0 0)
			(size 0.8128 0.8128)
			(layers "F.Cu" "F.Mask" "F.Paste")
			(net "VOL_SEN_ALERT")
		)
	)
	(footprint ""
		(layer "F.Cu")
		(at 58.038746 -187.2107 90)
		(property "Reference" "R223"
			(at 0 0 90)
			(layer "F.SilkS")
			(hide yes)
			(effects
				(font
					(size 1.27 1.27)
				)
			)
		)
		(property "Value" "2R2010J-1-GP"
			(at 0.254 -8.0772 90)
			(unlocked yes)
			(layer "F.Fab")
			(hide yes)
			(effects
				(font
					(size 1.016 1.016)
					(thickness 0.1524)
				)
			)
		)
		(property "Device Type" "R2010H28"
			(at 0.254 -9.6774 90)
			(unlocked yes)
			(layer "F.Fab")
			(hide yes)
			(effects
				(font
					(size 1.016 1.016)
					(thickness 0.1524)
				)
			)
		)
		(duplicate_pad_numbers_are_jumpers no)
		(fp_line
			(start 1.651 -3.302)
			(end -1.651 -3.302)
			(stroke
				(width 0.1524)
				(type default)
			)
			(layer "F.SilkS")
		)
		(fp_line
			(start -1.651 -3.302)
			(end -1.651 3.302)
			(stroke
				(width 0.1524)
				(type default)
			)
			(layer "F.SilkS")
		)
		(fp_line
			(start 1.651 3.302)
			(end 1.651 -3.302)
			(stroke
				(width 0.1524)
				(type default)
			)
			(layer "F.SilkS")
		)
		(fp_line
			(start -1.651 3.302)
			(end 1.651 3.302)
			(stroke
				(width 0.1524)
				(type default)
			)
			(layer "F.SilkS")
		)
		(fp_rect
			(start -1.7272 -3.3782)
			(end 1.7272 3.3782)
			(stroke
				(width 0)
				(type default)
			)
			(fill no)
			(layer "F.CrtYd")
		)
		(fp_poly
			(pts
				(xy 1.7272 3.3782) (xy 1.7272 -3.3782) (xy -1.7272 -3.3782) (xy -1.7272 3.3782)
			)
			(stroke
				(width 0)
				(type default)
			)
			(fill no)
			(layer "F.Fab")
		)
		(pad "1" smd rect
			(at 0 -2.3495 90)
			(size 2.794 1.143)
			(layers "F.Cu" "F.Mask" "F.Paste")
			(net "12V_PRE_8")
		)
		(pad "2" smd rect
			(at 0 2.3495 90)
			(size 2.794 1.143)
			(layers "F.Cu" "F.Mask" "F.Paste")
			(net "P12V_HDD8")
		)
	)
	(footprint ""
		(layer "F.Cu")
		(at 59.944 -231.14 180)
		(property "Reference" "C376"
			(at 0 0 180)
			(layer "F.SilkS")
			(hide yes)
			(effects
				(font
					(size 1.27 1.27)
				)
			)
		)
		(property "Value" "SCD033U25V2KX-GP"
			(at 1.1811 -2.7051 180)
			(unlocked yes)
			(layer "F.Fab")
			(hide yes)
			(effects
				(font
					(size 1.016 1.016)
					(thickness 0.1524)
				)
			)
		)
		(property "Device Type" "C402H22"
			(at 1.1811 -4.2291 180)
			(unlocked yes)
			(layer "F.Fab")
			(hide yes)
			(effects
				(font
					(size 1.016 1.016)
					(thickness 0.1524)
				)
			)
		)
		(duplicate_pad_numbers_are_jumpers no)
		(fp_rect
			(start -0.4318 0.9525)
			(end 0.4318 -0.9525)
			(stroke
				(width 0)
				(type default)
			)
			(fill no)
			(layer "F.CrtYd")
		)
		(fp_rect
			(start -0.4318 0.9525)
			(end 0.4318 -0.9525)
			(stroke
				(width 0)
				(type default)
			)
			(fill no)
			(layer "F.Fab")
		)
		(pad "1" smd custom
			(at 0 -0.4445 180)
			(size 0.1524 0.1524)
			(layers "F.Cu" "F.Mask" "F.Paste")
			(net "SW_HDD12_P")
			(options
				(clearance outline)
				(anchor circle)
			)
			(primitives
				(gr_poly
					(pts
						(arc
							(start 0.3048 -0.2032)
							(mid 0.275042 -0.275042)
							(end 0.2032 -0.3048)
						)
						(arc
							(start -0.2032 -0.3048)
							(mid -0.275042 -0.275042)
							(end -0.3048 -0.2032)
						)
						(arc
							(start -0.3048 0.2032)
							(mid -0.275042 0.275042)
							(end -0.2032 0.3048)
						)
						(arc
							(start 0.2032 0.3048)
							(mid 0.275042 0.275042)
							(end 0.3048 0.2032)
						)
					)
					(width 0)
					(fill yes)
				)
			)
		)
		(pad "2" smd custom
			(at 0 0.4445 180)
			(size 0.1524 0.1524)
			(layers "F.Cu" "F.Mask" "F.Paste")
			(net "GND")
			(options
				(clearance outline)
				(anchor circle)
			)
			(primitives
				(gr_poly
					(pts
						(arc
							(start 0.3048 -0.2032)
							(mid 0.275042 -0.275042)
							(end 0.2032 -0.3048)
						)
						(arc
							(start -0.2032 -0.3048)
							(mid -0.275042 -0.275042)
							(end -0.3048 -0.2032)
						)
						(arc
							(start -0.3048 0.2032)
							(mid -0.275042 0.275042)
							(end -0.2032 0.3048)
						)
						(arc
							(start 0.2032 0.3048)
							(mid 0.275042 0.275042)
							(end 0.3048 0.2032)
						)
					)
					(width 0)
					(fill yes)
				)
			)
		)
	)
	(footprint ""
		(layer "F.Cu")
		(at 19.684746 -163.2077 90)
		(property "Reference" "R503"
			(at 0 0 90)
			(layer "F.SilkS")
			(hide yes)
			(effects
				(font
					(size 1.27 1.27)
				)
			)
		)
		(property "Value" "1KR2F-3-GP"
			(at 0.064008 -3.993896 90)
			(unlocked yes)
			(layer "F.Fab")
			(hide yes)
			(effects
				(font
					(size 1.016 1.016)
					(thickness 0.1524)
				)
			)
		)
		(property "Device Type" "R402H16"
			(at 0.064008 -5.517896 90)
			(unlocked yes)
			(layer "F.Fab")
			(hide yes)
			(effects
				(font
					(size 1.016 1.016)
					(thickness 0.1524)
				)
			)
		)
		(duplicate_pad_numbers_are_jumpers no)
		(fp_line
			(start 0.508 -0.9398)
			(end -0.508 -0.9398)
			(stroke
				(width 0.1524)
				(type default)
			)
			(layer "F.SilkS")
		)
		(fp_line
			(start -0.508 -0.9398)
			(end -0.508 0.9398)
			(stroke
				(width 0.1524)
				(type default)
			)
			(layer "F.SilkS")
		)
		(fp_rect
			(start -0.508 0.9398)
			(end 0.508 -0.9398)
			(stroke
				(width 0)
				(type default)
			)
			(fill no)
			(layer "F.CrtYd")
		)
		(fp_rect
			(start -0.508 0.9398)
			(end 0.508 -0.9398)
			(stroke
				(width 0)
				(type default)
			)
			(fill no)
			(layer "F.Fab")
		)
		(pad "1" smd custom
			(at 0 -0.4445 90)
			(size 0.1397 0.1397)
			(layers "F.Cu" "F.Mask" "F.Paste")
			(net "FLT_HDD13_B")
			(options
				(clearance outline)
				(anchor circle)
			)
			(primitives
				(gr_poly
					(pts
						(arc
							(start -0.1778 -0.2794)
							(mid -0.249642 -0.249642)
							(end -0.2794 -0.1778)
						)
						(arc
							(start -0.2794 0.1778)
							(mid -0.249642 0.249642)
							(end -0.1778 0.2794)
						)
						(arc
							(start 0.1778 0.2794)
							(mid 0.249642 0.249642)
							(end 0.2794 0.1778)
						)
						(arc
							(start 0.2794 -0.1778)
							(mid 0.249642 -0.249642)
							(end 0.1778 -0.2794)
						)
					)
					(width 0)
					(fill yes)
				)
			)
		)
		(pad "2" smd custom
			(at 0 0.4445 90)
			(size 0.1397 0.1397)
			(layers "F.Cu" "F.Mask" "F.Paste")
			(net "FLT_HDD13_DRIVE")
			(options
				(clearance outline)
				(anchor circle)
			)
			(primitives
				(gr_poly
					(pts
						(arc
							(start -0.1778 -0.2794)
							(mid -0.249642 -0.249642)
							(end -0.2794 -0.1778)
						)
						(arc
							(start -0.2794 0.1778)
							(mid -0.249642 0.249642)
							(end -0.1778 0.2794)
						)
						(arc
							(start 0.1778 0.2794)
							(mid 0.249642 0.249642)
							(end 0.2794 0.1778)
						)
						(arc
							(start 0.2794 -0.1778)
							(mid 0.249642 -0.249642)
							(end 0.1778 -0.2794)
						)
					)
					(width 0)
					(fill yes)
				)
			)
		)
	)
	(footprint ""
		(layer "F.Cu")
		(at 54.253892 -88.420956 180)
		(property "Reference" "C259"
			(at 0 0 180)
			(layer "F.SilkS")
			(hide yes)
			(effects
				(font
					(size 1.27 1.27)
				)
			)
		)
		(property "Value" "SC1U25V3KX-1-GP"
			(at 0 -2.8194 180)
			(unlocked yes)
			(layer "F.Fab")
			(hide yes)
			(effects
				(font
					(size 1.016 1.016)
					(thickness 0.1524)
				)
			)
		)
		(property "Device Type" "C603H36"
			(at 0 -4.3434 180)
			(unlocked yes)
			(layer "F.Fab")
			(hide yes)
			(effects
				(font
					(size 1.016 1.016)
					(thickness 0.1524)
				)
			)
		)
		(duplicate_pad_numbers_are_jumpers no)
		(fp_line
			(start 0.508 0)
			(end -0.508 0)
			(stroke
				(width 0.2032)
				(type default)
			)
			(layer "F.SilkS")
		)
		(fp_rect
			(start -0.5842 1.3335)
			(end 0.5842 -1.3335)
			(stroke
				(width 0)
				(type default)
			)
			(fill no)
			(layer "F.CrtYd")
		)
		(fp_rect
			(start -0.5842 1.3335)
			(end 0.5842 -1.3335)
			(stroke
				(width 0)
				(type default)
			)
			(fill no)
			(layer "F.Fab")
		)
		(pad "1" smd custom
			(at 0 -0.762 180)
			(size 0.2159 0.2159)
			(layers "F.Cu" "F.Mask" "F.Paste")
			(net "P12V_HDD9")
			(options
				(clearance outline)
				(anchor circle)
			)
			(primitives
				(gr_poly
					(pts
						(arc
							(start -0.3302 -0.4318)
							(mid -0.402042 -0.402042)
							(end -0.4318 -0.3302)
						)
						(arc
							(start -0.4318 0.3302)
							(mid -0.402042 0.402042)
							(end -0.3302 0.4318)
						)
						(arc
							(start 0.3302 0.4318)
							(mid 0.402042 0.402042)
							(end 0.4318 0.3302)
						)
						(arc
							(start 0.4318 -0.3302)
							(mid 0.402042 -0.402042)
							(end 0.3302 -0.4318)
						)
					)
					(width 0)
					(fill yes)
				)
			)
		)
		(pad "2" smd custom
			(at 0 0.762 180)
			(size 0.2159 0.2159)
			(layers "F.Cu" "F.Mask" "F.Paste")
			(net "GND")
			(options
				(clearance outline)
				(anchor circle)
			)
			(primitives
				(gr_poly
					(pts
						(arc
							(start -0.3302 -0.4318)
							(mid -0.402042 -0.402042)
							(end -0.4318 -0.3302)
						)
						(arc
							(start -0.4318 0.3302)
							(mid -0.402042 0.402042)
							(end -0.3302 0.4318)
						)
						(arc
							(start 0.3302 0.4318)
							(mid 0.402042 0.402042)
							(end 0.4318 0.3302)
						)
						(arc
							(start 0.4318 -0.3302)
							(mid 0.402042 -0.402042)
							(end 0.3302 -0.4318)
						)
					)
					(width 0)
					(fill yes)
				)
			)
		)
	)
	(footprint ""
		(layer "F.Cu")
		(at 77.978 -196.342 180)
		(property "Reference" "C387"
			(at 0 0 180)
			(layer "F.SilkS")
			(hide yes)
			(effects
				(font
					(size 1.27 1.27)
				)
			)
		)
		(property "Value" "SCD033U25V2KX-GP"
			(at 1.1811 -2.7051 180)
			(unlocked yes)
			(layer "F.Fab")
			(hide yes)
			(effects
				(font
					(size 1.016 1.016)
					(thickness 0.1524)
				)
			)
		)
		(property "Device Type" "C402H22"
			(at 1.1811 -4.2291 180)
			(unlocked yes)
			(layer "F.Fab")
			(hide yes)
			(effects
				(font
					(size 1.016 1.016)
					(thickness 0.1524)
				)
			)
		)
		(duplicate_pad_numbers_are_jumpers no)
		(fp_rect
			(start -0.4318 0.9525)
			(end 0.4318 -0.9525)
			(stroke
				(width 0)
				(type default)
			)
			(fill no)
			(layer "F.CrtYd")
		)
		(fp_rect
			(start -0.4318 0.9525)
			(end 0.4318 -0.9525)
			(stroke
				(width 0)
				(type default)
			)
			(fill no)
			(layer "F.Fab")
		)
		(pad "1" smd custom
			(at 0 -0.4445 180)
			(size 0.1524 0.1524)
			(layers "F.Cu" "F.Mask" "F.Paste")
			(net "P12V")
			(options
				(clearance outline)
				(anchor circle)
			)
			(primitives
				(gr_poly
					(pts
						(arc
							(start 0.3048 -0.2032)
							(mid 0.275042 -0.275042)
							(end 0.2032 -0.3048)
						)
						(arc
							(start -0.2032 -0.3048)
							(mid -0.275042 -0.275042)
							(end -0.3048 -0.2032)
						)
						(arc
							(start -0.3048 0.2032)
							(mid -0.275042 0.275042)
							(end -0.2032 0.3048)
						)
						(arc
							(start 0.2032 0.3048)
							(mid 0.275042 0.275042)
							(end 0.3048 0.2032)
						)
					)
					(width 0)
					(fill yes)
				)
			)
		)
		(pad "2" smd custom
			(at 0 0.4445 180)
			(size 0.1524 0.1524)
			(layers "F.Cu" "F.Mask" "F.Paste")
			(net "SW_HDD8_N")
			(options
				(clearance outline)
				(anchor circle)
			)
			(primitives
				(gr_poly
					(pts
						(arc
							(start 0.3048 -0.2032)
							(mid 0.275042 -0.275042)
							(end 0.2032 -0.3048)
						)
						(arc
							(start -0.2032 -0.3048)
							(mid -0.275042 -0.275042)
							(end -0.3048 -0.2032)
						)
						(arc
							(start -0.3048 0.2032)
							(mid -0.275042 0.275042)
							(end -0.2032 0.3048)
						)
						(arc
							(start 0.2032 0.3048)
							(mid 0.275042 0.275042)
							(end 0.3048 0.2032)
						)
					)
					(width 0)
					(fill yes)
				)
			)
		)
	)
	(footprint ""
		(layer "F.Cu")
		(at 32.12592 -279.014428 -90)
		(property "Reference" "R450"
			(at 0 0 270)
			(layer "F.SilkS")
			(hide yes)
			(effects
				(font
					(size 1.27 1.27)
				)
			)
		)
		(property "Value" "4K7R2J-2-GP"
			(at 0.064008 -3.993896 270)
			(unlocked yes)
			(layer "F.Fab")
			(hide yes)
			(effects
				(font
					(size 1.016 1.016)
					(thickness 0.1524)
				)
			)
		)
		(property "Device Type" "R402H16"
			(at 0.064008 -5.517896 270)
			(unlocked yes)
			(layer "F.Fab")
			(hide yes)
			(effects
				(font
					(size 1.016 1.016)
					(thickness 0.1524)
				)
			)
		)
		(duplicate_pad_numbers_are_jumpers no)
		(fp_line
			(start -0.508 -0.9398)
			(end -0.508 0.9398)
			(stroke
				(width 0.1524)
				(type default)
			)
			(layer "F.SilkS")
		)
		(fp_line
			(start 0.508 -0.9398)
			(end -0.508 -0.9398)
			(stroke
				(width 0.1524)
				(type default)
			)
			(layer "F.SilkS")
		)
		(fp_rect
			(start -0.508 0.9398)
			(end 0.508 -0.9398)
			(stroke
				(width 0)
				(type default)
			)
			(fill no)
			(layer "F.CrtYd")
		)
		(fp_rect
			(start -0.508 0.9398)
			(end 0.508 -0.9398)
			(stroke
				(width 0)
				(type default)
			)
			(fill no)
			(layer "F.Fab")
		)
		(pad "1" smd custom
			(at 0 -0.4445 270)
			(size 0.1397 0.1397)
			(layers "F.Cu" "F.Mask" "F.Paste")
			(net "P3V3")
			(options
				(clearance outline)
				(anchor circle)
			)
			(primitives
				(gr_poly
					(pts
						(arc
							(start -0.1778 -0.2794)
							(mid -0.249642 -0.249642)
							(end -0.2794 -0.1778)
						)
						(arc
							(start -0.2794 0.1778)
							(mid -0.249642 0.249642)
							(end -0.1778 0.2794)
						)
						(arc
							(start 0.1778 0.2794)
							(mid 0.249642 0.249642)
							(end 0.2794 0.1778)
						)
						(arc
							(start 0.2794 -0.1778)
							(mid 0.249642 -0.249642)
							(end 0.1778 -0.2794)
						)
					)
					(width 0)
					(fill yes)
				)
			)
		)
		(pad "2" smd custom
			(at 0 0.4445 270)
			(size 0.1397 0.1397)
			(layers "F.Cu" "F.Mask" "F.Paste")
			(net "SAS_EXP_A_PWR7")
			(options
				(clearance outline)
				(anchor circle)
			)
			(primitives
				(gr_poly
					(pts
						(arc
							(start -0.1778 -0.2794)
							(mid -0.249642 -0.249642)
							(end -0.2794 -0.1778)
						)
						(arc
							(start -0.2794 0.1778)
							(mid -0.249642 0.249642)
							(end -0.1778 0.2794)
						)
						(arc
							(start 0.1778 0.2794)
							(mid 0.249642 0.249642)
							(end 0.2794 0.1778)
						)
						(arc
							(start 0.2794 -0.1778)
							(mid 0.249642 -0.249642)
							(end 0.1778 -0.2794)
						)
					)
					(width 0)
					(fill yes)
				)
			)
		)
	)
	(footprint ""
		(layer "F.Cu")
		(at 207.137 -483.235)
		(property "Reference" "C364"
			(at 0 0 0)
			(layer "F.SilkS")
			(hide yes)
			(effects
				(font
					(size 1.27 1.27)
				)
			)
		)
		(property "Value" "SCD033U25V2KX-GP"
			(at 1.1811 -2.7051 0)
			(unlocked yes)
			(layer "F.Fab")
			(hide yes)
			(effects
				(font
					(size 1.016 1.016)
					(thickness 0.1524)
				)
			)
		)
		(property "Device Type" "C402H22"
			(at 1.1811 -4.2291 0)
			(unlocked yes)
			(layer "F.Fab")
			(hide yes)
			(effects
				(font
					(size 1.016 1.016)
					(thickness 0.1524)
				)
			)
		)
		(duplicate_pad_numbers_are_jumpers no)
		(fp_rect
			(start -0.4318 0.9525)
			(end 0.4318 -0.9525)
			(stroke
				(width 0)
				(type default)
			)
			(fill no)
			(layer "F.CrtYd")
		)
		(fp_rect
			(start -0.4318 0.9525)
			(end 0.4318 -0.9525)
			(stroke
				(width 0)
				(type default)
			)
			(fill no)
			(layer "F.Fab")
		)
		(pad "1" smd custom
			(at 0 -0.4445)
			(size 0.1524 0.1524)
			(layers "F.Cu" "F.Mask" "F.Paste")
			(net "SW_HDD0_P")
			(options
				(clearance outline)
				(anchor circle)
			)
			(primitives
				(gr_poly
					(pts
						(arc
							(start 0.3048 -0.2032)
							(mid 0.275042 -0.275042)
							(end 0.2032 -0.3048)
						)
						(arc
							(start -0.2032 -0.3048)
							(mid -0.275042 -0.275042)
							(end -0.3048 -0.2032)
						)
						(arc
							(start -0.3048 0.2032)
							(mid -0.275042 0.275042)
							(end -0.2032 0.3048)
						)
						(arc
							(start 0.2032 0.3048)
							(mid 0.275042 0.275042)
							(end 0.3048 0.2032)
						)
					)
					(width 0)
					(fill yes)
				)
			)
		)
		(pad "2" smd custom
			(at 0 0.4445)
			(size 0.1524 0.1524)
			(layers "F.Cu" "F.Mask" "F.Paste")
			(net "GND")
			(options
				(clearance outline)
				(anchor circle)
			)
			(primitives
				(gr_poly
					(pts
						(arc
							(start 0.3048 -0.2032)
							(mid 0.275042 -0.275042)
							(end 0.2032 -0.3048)
						)
						(arc
							(start -0.2032 -0.3048)
							(mid -0.275042 -0.275042)
							(end -0.3048 -0.2032)
						)
						(arc
							(start -0.3048 0.2032)
							(mid -0.275042 0.275042)
							(end -0.2032 0.3048)
						)
						(arc
							(start 0.2032 0.3048)
							(mid 0.275042 0.275042)
							(end 0.3048 0.2032)
						)
					)
					(width 0)
					(fill yes)
				)
			)
		)
	)
	(footprint ""
		(layer "F.Cu")
		(at 18.940272 -500.446548 180)
		(property "Reference" "PC31"
			(at 0 0 180)
			(layer "F.SilkS")
			(hide yes)
			(effects
				(font
					(size 1.27 1.27)
				)
			)
		)
		(property "Value" "SC22U25V5MX-GP"
			(at -0.0762 -6.1214 180)
			(unlocked yes)
			(layer "F.Fab")
			(hide yes)
			(effects
				(font
					(size 1.016 1.016)
					(thickness 0.1524)
				)
			)
		)
		(property "Device Type" "C805H58"
			(at -0.0762 -8.1534 180)
			(unlocked yes)
			(layer "F.Fab")
			(hide yes)
			(effects
				(font
					(size 1.016 1.016)
					(thickness 0.1524)
				)
			)
		)
		(duplicate_pad_numbers_are_jumpers no)
		(fp_line
			(start 0.635 0)
			(end -0.635 0)
			(stroke
				(width 0.508)
				(type default)
			)
			(layer "F.SilkS")
		)
		(fp_rect
			(start -0.9652 1.778)
			(end 0.9652 -1.778)
			(stroke
				(width 0)
				(type default)
			)
			(fill no)
			(layer "F.CrtYd")
		)
		(fp_poly
			(pts
				(xy -0.9652 -1.778) (xy 0.9652 -1.778) (xy 0.9652 1.778) (xy -0.9652 1.778)
			)
			(stroke
				(width 0)
				(type default)
			)
			(fill no)
			(layer "F.Fab")
		)
		(pad "1" smd rect
			(at 0 -0.9652 180)
			(size 1.397 1.143)
			(layers "F.Cu" "F.Mask" "F.Paste")
			(net "P5VC_12VIN")
		)
		(pad "2" smd rect
			(at 0 0.9652 180)
			(size 1.397 1.143)
			(layers "F.Cu" "F.Mask" "F.Paste")
			(net "GND")
		)
	)
	(footprint ""
		(layer "F.Cu")
		(at 5.079746 -494.8047 -90)
		(property "Reference" "PR43"
			(at 0 0 270)
			(layer "F.SilkS")
			(hide yes)
			(effects
				(font
					(size 1.27 1.27)
				)
			)
		)
		(property "Value" "10KR2D-GP"
			(at 0.064008 -3.993896 270)
			(unlocked yes)
			(layer "F.Fab")
			(hide yes)
			(effects
				(font
					(size 1.016 1.016)
					(thickness 0.1524)
				)
			)
		)
		(property "Device Type" "R402H16"
			(at 0.064008 -5.517896 270)
			(unlocked yes)
			(layer "F.Fab")
			(hide yes)
			(effects
				(font
					(size 1.016 1.016)
					(thickness 0.1524)
				)
			)
		)
		(duplicate_pad_numbers_are_jumpers no)
		(fp_line
			(start -0.508 -0.9398)
			(end -0.508 0.9398)
			(stroke
				(width 0.1524)
				(type default)
			)
			(layer "F.SilkS")
		)
		(fp_line
			(start 0.508 -0.9398)
			(end -0.508 -0.9398)
			(stroke
				(width 0.1524)
				(type default)
			)
			(layer "F.SilkS")
		)
		(fp_rect
			(start -0.508 0.9398)
			(end 0.508 -0.9398)
			(stroke
				(width 0)
				(type default)
			)
			(fill no)
			(layer "F.CrtYd")
		)
		(fp_rect
			(start -0.508 0.9398)
			(end 0.508 -0.9398)
			(stroke
				(width 0)
				(type default)
			)
			(fill no)
			(layer "F.Fab")
		)
		(pad "1" smd custom
			(at 0 -0.4445 270)
			(size 0.1397 0.1397)
			(layers "F.Cu" "F.Mask" "F.Paste")
			(net "P5VC_VFB")
			(options
				(clearance outline)
				(anchor circle)
			)
			(primitives
				(gr_poly
					(pts
						(arc
							(start -0.1778 -0.2794)
							(mid -0.249642 -0.249642)
							(end -0.2794 -0.1778)
						)
						(arc
							(start -0.2794 0.1778)
							(mid -0.249642 0.249642)
							(end -0.1778 0.2794)
						)
						(arc
							(start 0.1778 0.2794)
							(mid 0.249642 0.249642)
							(end 0.2794 0.1778)
						)
						(arc
							(start 0.2794 -0.1778)
							(mid 0.249642 -0.249642)
							(end 0.1778 -0.2794)
						)
					)
					(width 0)
					(fill yes)
				)
			)
		)
		(pad "2" smd custom
			(at 0 0.4445 270)
			(size 0.1397 0.1397)
			(layers "F.Cu" "F.Mask" "F.Paste")
			(net "P5VC_AGND")
			(options
				(clearance outline)
				(anchor circle)
			)
			(primitives
				(gr_poly
					(pts
						(arc
							(start -0.1778 -0.2794)
							(mid -0.249642 -0.249642)
							(end -0.2794 -0.1778)
						)
						(arc
							(start -0.2794 0.1778)
							(mid -0.249642 0.249642)
							(end -0.1778 0.2794)
						)
						(arc
							(start 0.1778 0.2794)
							(mid 0.249642 0.249642)
							(end 0.2794 0.1778)
						)
						(arc
							(start 0.2794 -0.1778)
							(mid 0.249642 -0.249642)
							(end 0.1778 -0.2794)
						)
					)
					(width 0)
					(fill yes)
				)
			)
		)
	)
	(footprint ""
		(layer "F.Cu")
		(at 32.86506 -372.298214 -90)
		(property "Reference" "C200"
			(at 0 0 270)
			(layer "F.SilkS")
			(hide yes)
			(effects
				(font
					(size 1.27 1.27)
				)
			)
		)
		(property "Value" "SCD01U50V2KX-1GP"
			(at 1.1811 -2.7051 270)
			(unlocked yes)
			(layer "F.Fab")
			(hide yes)
			(effects
				(font
					(size 1.016 1.016)
					(thickness 0.1524)
				)
			)
		)
		(property "Device Type" "C402H22"
			(at 1.1811 -4.2291 270)
			(unlocked yes)
			(layer "F.Fab")
			(hide yes)
			(effects
				(font
					(size 1.016 1.016)
					(thickness 0.1524)
				)
			)
		)
		(duplicate_pad_numbers_are_jumpers no)
		(fp_rect
			(start -0.4318 0.9525)
			(end 0.4318 -0.9525)
			(stroke
				(width 0)
				(type default)
			)
			(fill no)
			(layer "F.CrtYd")
		)
		(fp_rect
			(start -0.4318 0.9525)
			(end 0.4318 -0.9525)
			(stroke
				(width 0)
				(type default)
			)
			(fill no)
			(layer "F.Fab")
		)
		(pad "1" smd custom
			(at 0 -0.4445 270)
			(size 0.1524 0.1524)
			(layers "F.Cu" "F.Mask" "F.Paste")
			(net "SAS2X28_DRIVE_RX_N_B6")
			(options
				(clearance outline)
				(anchor circle)
			)
			(primitives
				(gr_poly
					(pts
						(arc
							(start 0.3048 -0.2032)
							(mid 0.275042 -0.275042)
							(end 0.2032 -0.3048)
						)
						(arc
							(start -0.2032 -0.3048)
							(mid -0.275042 -0.275042)
							(end -0.3048 -0.2032)
						)
						(arc
							(start -0.3048 0.2032)
							(mid -0.275042 0.275042)
							(end -0.2032 0.3048)
						)
						(arc
							(start 0.2032 0.3048)
							(mid 0.275042 0.275042)
							(end 0.3048 0.2032)
						)
					)
					(width 0)
					(fill yes)
				)
			)
		)
		(pad "2" smd custom
			(at 0 0.4445 270)
			(size 0.1524 0.1524)
			(layers "F.Cu" "F.Mask" "F.Paste")
			(net "SAS2X28_B_HDD6_RX_-")
			(options
				(clearance outline)
				(anchor circle)
			)
			(primitives
				(gr_poly
					(pts
						(arc
							(start 0.3048 -0.2032)
							(mid 0.275042 -0.275042)
							(end 0.2032 -0.3048)
						)
						(arc
							(start -0.2032 -0.3048)
							(mid -0.275042 -0.275042)
							(end -0.3048 -0.2032)
						)
						(arc
							(start -0.3048 0.2032)
							(mid -0.275042 0.275042)
							(end -0.2032 0.3048)
						)
						(arc
							(start 0.2032 0.3048)
							(mid 0.275042 0.275042)
							(end 0.3048 0.2032)
						)
					)
					(width 0)
					(fill yes)
				)
			)
		)
	)
	(footprint ""
		(layer "F.Cu")
		(at 218.265756 -481.739702)
		(property "Reference" "C108"
			(at 0 0 0)
			(layer "F.SilkS")
			(hide yes)
			(effects
				(font
					(size 1.27 1.27)
				)
			)
		)
		(property "Value" "SCD01U50V2KX-1GP"
			(at 1.1811 -2.7051 0)
			(unlocked yes)
			(layer "F.Fab")
			(hide yes)
			(effects
				(font
					(size 1.016 1.016)
					(thickness 0.1524)
				)
			)
		)
		(property "Device Type" "C402H22"
			(at 1.1811 -4.2291 0)
			(unlocked yes)
			(layer "F.Fab")
			(hide yes)
			(effects
				(font
					(size 1.016 1.016)
					(thickness 0.1524)
				)
			)
		)
		(duplicate_pad_numbers_are_jumpers no)
		(fp_rect
			(start -0.4318 0.9525)
			(end 0.4318 -0.9525)
			(stroke
				(width 0)
				(type default)
			)
			(fill no)
			(layer "F.CrtYd")
		)
		(fp_rect
			(start -0.4318 0.9525)
			(end 0.4318 -0.9525)
			(stroke
				(width 0)
				(type default)
			)
			(fill no)
			(layer "F.Fab")
		)
		(pad "1" smd custom
			(at 0 -0.4445)
			(size 0.1524 0.1524)
			(layers "F.Cu" "F.Mask" "F.Paste")
			(net "HDD_PRSNT_NET0")
			(options
				(clearance outline)
				(anchor circle)
			)
			(primitives
				(gr_poly
					(pts
						(arc
							(start 0.3048 -0.2032)
							(mid 0.275042 -0.275042)
							(end 0.2032 -0.3048)
						)
						(arc
							(start -0.2032 -0.3048)
							(mid -0.275042 -0.275042)
							(end -0.3048 -0.2032)
						)
						(arc
							(start -0.3048 0.2032)
							(mid -0.275042 0.275042)
							(end -0.2032 0.3048)
						)
						(arc
							(start 0.2032 0.3048)
							(mid 0.275042 0.275042)
							(end 0.3048 0.2032)
						)
					)
					(width 0)
					(fill yes)
				)
			)
		)
		(pad "2" smd custom
			(at 0 0.4445)
			(size 0.1524 0.1524)
			(layers "F.Cu" "F.Mask" "F.Paste")
			(net "GND")
			(options
				(clearance outline)
				(anchor circle)
			)
			(primitives
				(gr_poly
					(pts
						(arc
							(start 0.3048 -0.2032)
							(mid 0.275042 -0.275042)
							(end 0.2032 -0.3048)
						)
						(arc
							(start -0.2032 -0.3048)
							(mid -0.275042 -0.275042)
							(end -0.3048 -0.2032)
						)
						(arc
							(start -0.3048 0.2032)
							(mid -0.275042 0.275042)
							(end -0.2032 0.3048)
						)
						(arc
							(start 0.2032 0.3048)
							(mid 0.275042 0.275042)
							(end 0.3048 0.2032)
						)
					)
					(width 0)
					(fill yes)
				)
			)
		)
	)
	(footprint ""
		(layer "F.Cu")
		(at 14.922246 -165.731698 90)
		(property "Reference" "R284"
			(at 0 0 90)
			(layer "F.SilkS")
			(hide yes)
			(effects
				(font
					(size 1.27 1.27)
				)
			)
		)
		(property "Value" "0R2J-2-GP"
			(at 0.064008 -3.993896 90)
			(unlocked yes)
			(layer "F.Fab")
			(hide yes)
			(effects
				(font
					(size 1.016 1.016)
					(thickness 0.1524)
				)
			)
		)
		(property "Device Type" "R402H16"
			(at 0.064008 -5.517896 90)
			(unlocked yes)
			(layer "F.Fab")
			(hide yes)
			(effects
				(font
					(size 1.016 1.016)
					(thickness 0.1524)
				)
			)
		)
		(duplicate_pad_numbers_are_jumpers no)
		(fp_line
			(start 0.508 -0.9398)
			(end -0.508 -0.9398)
			(stroke
				(width 0.1524)
				(type default)
			)
			(layer "F.SilkS")
		)
		(fp_line
			(start -0.508 -0.9398)
			(end -0.508 0.9398)
			(stroke
				(width 0.1524)
				(type default)
			)
			(layer "F.SilkS")
		)
		(fp_rect
			(start -0.508 0.9398)
			(end 0.508 -0.9398)
			(stroke
				(width 0)
				(type default)
			)
			(fill no)
			(layer "F.CrtYd")
		)
		(fp_rect
			(start -0.508 0.9398)
			(end 0.508 -0.9398)
			(stroke
				(width 0)
				(type default)
			)
			(fill no)
			(layer "F.Fab")
		)
		(pad "1" smd custom
			(at 0 -0.4445 90)
			(size 0.1397 0.1397)
			(layers "F.Cu" "F.Mask" "F.Paste")
			(net "DRV_ACT_NET13")
			(options
				(clearance outline)
				(anchor circle)
			)
			(primitives
				(gr_poly
					(pts
						(arc
							(start -0.1778 -0.2794)
							(mid -0.249642 -0.249642)
							(end -0.2794 -0.1778)
						)
						(arc
							(start -0.2794 0.1778)
							(mid -0.249642 0.249642)
							(end -0.1778 0.2794)
						)
						(arc
							(start 0.1778 0.2794)
							(mid 0.249642 0.249642)
							(end 0.2794 0.1778)
						)
						(arc
							(start 0.2794 -0.1778)
							(mid 0.249642 -0.249642)
							(end 0.1778 -0.2794)
						)
					)
					(width 0)
					(fill yes)
				)
			)
		)
		(pad "2" smd custom
			(at 0 0.4445 90)
			(size 0.1397 0.1397)
			(layers "F.Cu" "F.Mask" "F.Paste")
			(net "DRIVE_ACT_13")
			(options
				(clearance outline)
				(anchor circle)
			)
			(primitives
				(gr_poly
					(pts
						(arc
							(start -0.1778 -0.2794)
							(mid -0.249642 -0.249642)
							(end -0.2794 -0.1778)
						)
						(arc
							(start -0.2794 0.1778)
							(mid -0.249642 0.249642)
							(end -0.1778 0.2794)
						)
						(arc
							(start 0.1778 0.2794)
							(mid 0.249642 0.249642)
							(end 0.2794 0.1778)
						)
						(arc
							(start 0.2794 -0.1778)
							(mid 0.249642 -0.249642)
							(end 0.1778 -0.2794)
						)
					)
					(width 0)
					(fill yes)
				)
			)
		)
	)
	(footprint ""
		(layer "F.Cu")
		(at 33.1216 -106.4514)
		(property "Reference" "C315"
			(at 0 0 0)
			(layer "F.SilkS")
			(hide yes)
			(effects
				(font
					(size 1.27 1.27)
				)
			)
		)
		(property "Value" "SCD1U10V2KX-5GP"
			(at 1.1811 -2.7051 0)
			(unlocked yes)
			(layer "F.Fab")
			(hide yes)
			(effects
				(font
					(size 1.016 1.016)
					(thickness 0.1524)
				)
			)
		)
		(property "Device Type" "C402H22"
			(at 1.1811 -4.2291 0)
			(unlocked yes)
			(layer "F.Fab")
			(hide yes)
			(effects
				(font
					(size 1.016 1.016)
					(thickness 0.1524)
				)
			)
		)
		(duplicate_pad_numbers_are_jumpers no)
		(fp_rect
			(start -0.4318 0.9525)
			(end 0.4318 -0.9525)
			(stroke
				(width 0)
				(type default)
			)
			(fill no)
			(layer "F.CrtYd")
		)
		(fp_rect
			(start -0.4318 0.9525)
			(end 0.4318 -0.9525)
			(stroke
				(width 0)
				(type default)
			)
			(fill no)
			(layer "F.Fab")
		)
		(pad "1" smd custom
			(at 0 -0.4445)
			(size 0.1524 0.1524)
			(layers "F.Cu" "F.Mask" "F.Paste")
			(net "P3V3")
			(options
				(clearance outline)
				(anchor circle)
			)
			(primitives
				(gr_poly
					(pts
						(arc
							(start 0.3048 -0.2032)
							(mid 0.275042 -0.275042)
							(end 0.2032 -0.3048)
						)
						(arc
							(start -0.2032 -0.3048)
							(mid -0.275042 -0.275042)
							(end -0.3048 -0.2032)
						)
						(arc
							(start -0.3048 0.2032)
							(mid -0.275042 0.275042)
							(end -0.2032 0.3048)
						)
						(arc
							(start 0.2032 0.3048)
							(mid 0.275042 0.275042)
							(end 0.3048 0.2032)
						)
					)
					(width 0)
					(fill yes)
				)
			)
		)
		(pad "2" smd custom
			(at 0 0.4445)
			(size 0.1524 0.1524)
			(layers "F.Cu" "F.Mask" "F.Paste")
			(net "GND")
			(options
				(clearance outline)
				(anchor circle)
			)
			(primitives
				(gr_poly
					(pts
						(arc
							(start 0.3048 -0.2032)
							(mid 0.275042 -0.275042)
							(end 0.2032 -0.3048)
						)
						(arc
							(start -0.2032 -0.3048)
							(mid -0.275042 -0.275042)
							(end -0.3048 -0.2032)
						)
						(arc
							(start -0.3048 0.2032)
							(mid -0.275042 0.275042)
							(end -0.2032 0.3048)
						)
						(arc
							(start 0.2032 0.3048)
							(mid 0.275042 0.275042)
							(end 0.3048 0.2032)
						)
					)
					(width 0)
					(fill yes)
				)
			)
		)
	)
	(footprint ""
		(layer "F.Cu")
		(at 193.978784 -184.755028 -90)
		(property "Reference" "U12"
			(at 0 0 270)
			(layer "F.SilkS")
			(hide yes)
			(effects
				(font
					(size 1.27 1.27)
				)
			)
		)
		(property "Value" "74LVC1G08GW-1-GP"
			(at -2.3368 -8.6868 270)
			(unlocked yes)
			(layer "F.Fab")
			(hide yes)
			(effects
				(font
					(size 1.016 1.016)
					(thickness 0.1524)
				)
			)
		)
		(property "Device Type" "SC70-5H44"
			(at -2.3114 -10.414 270)
			(unlocked yes)
			(layer "F.Fab")
			(hide yes)
			(effects
				(font
					(size 1.016 1.016)
					(thickness 0.1524)
				)
			)
		)
		(duplicate_pad_numbers_are_jumpers no)
		(fp_line
			(start -1.27 1.7018)
			(end -1.27 -1.7018)
			(stroke
				(width 0.1524)
				(type default)
			)
			(layer "F.SilkS")
		)
		(fp_line
			(start 1.27 1.7018)
			(end -1.27 1.7018)
			(stroke
				(width 0.1524)
				(type default)
			)
			(layer "F.SilkS")
		)
		(fp_line
			(start -1.27 -1.7018)
			(end 1.27 -1.7018)
			(stroke
				(width 0.1524)
				(type default)
			)
			(layer "F.SilkS")
		)
		(fp_line
			(start 1.27 -1.7018)
			(end 1.27 1.7018)
			(stroke
				(width 0.1524)
				(type default)
			)
			(layer "F.SilkS")
		)
		(fp_line
			(start 0.6604 -1.8034)
			(end 1.3843 -1.8034)
			(stroke
				(width 0.3302)
				(type default)
			)
			(layer "F.SilkS")
		)
		(fp_line
			(start 1.3843 -1.8034)
			(end 1.3843 -1.1176)
			(stroke
				(width 0.3302)
				(type default)
			)
			(layer "F.SilkS")
		)
		(fp_rect
			(start -1.524 1.9558)
			(end 1.524 -1.9558)
			(stroke
				(width 0)
				(type default)
			)
			(fill no)
			(layer "F.CrtYd")
		)
		(fp_poly
			(pts
				(xy -1.524 -1.9558) (xy 1.524 -1.9558) (xy 1.524 1.9558) (xy -1.524 1.9558)
			)
			(stroke
				(width 0)
				(type default)
			)
			(fill no)
			(layer "F.Fab")
		)
		(pad "1" smd rect
			(at 0.65024 -0.8255 270)
			(size 0.4064 1.2192)
			(layers "F.Cu" "F.Mask" "F.Paste")
			(net "SAS_EXP_B_PWR3")
		)
		(pad "2" smd rect
			(at 0 -0.8255 270)
			(size 0.4064 1.2192)
			(layers "F.Cu" "F.Mask" "F.Paste")
			(net "SAS_EXP_A_PWR3")
		)
		(pad "3" smd rect
			(at -0.65024 -0.8255 270)
			(size 0.4064 1.2192)
			(layers "F.Cu" "F.Mask" "F.Paste")
			(net "GND")
		)
		(pad "4" smd rect
			(at -0.65024 0.8255 270)
			(size 0.4064 1.2192)
			(layers "F.Cu" "F.Mask" "F.Paste")
			(net "DRIVE_PWR3")
		)
		(pad "5" smd rect
			(at 0.65024 0.8255 270)
			(size 0.4064 1.2192)
			(layers "F.Cu" "F.Mask" "F.Paste")
			(net "P3V3")
		)
	)
	(footprint ""
		(layer "F.Cu")
		(at 8.889746 -399.4277)
		(property "Reference" "TP15"
			(at 0 0 0)
			(layer "F.SilkS")
			(hide yes)
			(effects
				(font
					(size 1.27 1.27)
				)
			)
		)
		(property "Value" "TPAD32-GP"
			(at 0 -3.166364 0)
			(unlocked yes)
			(layer "F.Fab")
			(hide yes)
			(effects
				(font
					(size 1.016 1.016)
					(thickness 0.1524)
				)
			)
		)
		(property "Device Type" "TPAD32"
			(at 0 -4.690618 0)
			(unlocked yes)
			(layer "F.Fab")
			(hide yes)
			(effects
				(font
					(size 1.016 1.016)
					(thickness 0.1524)
				)
			)
		)
		(duplicate_pad_numbers_are_jumpers no)
		(fp_poly
			(pts
				(arc
					(start 0.4064 0)
					(mid -0.4064 0)
					(end 0.4064 0)
				)
			)
			(stroke
				(width 0)
				(type default)
			)
			(fill no)
			(layer "F.CrtYd")
		)
		(fp_poly
			(pts
				(arc
					(start 0.7112 0)
					(mid -0.7112 0)
					(end 0.7112 0)
				)
			)
			(stroke
				(width 0)
				(type default)
			)
			(fill no)
			(layer "F.Fab")
		)
		(pad "1" smd circle
			(at 0 0)
			(size 0.8128 0.8128)
			(layers "F.Cu" "F.Mask" "F.Paste")
			(net "SAS2X28_A_HDD15_FLT")
		)
	)
	(footprint ""
		(layer "F.Cu")
		(at 215.348058 -379.043184 90)
		(property "Reference" "R123"
			(at 0 0 90)
			(layer "F.SilkS")
			(hide yes)
			(effects
				(font
					(size 1.27 1.27)
				)
			)
		)
		(property "Value" "4K7R2J-2-GP"
			(at 0.064008 -3.993896 90)
			(unlocked yes)
			(layer "F.Fab")
			(hide yes)
			(effects
				(font
					(size 1.016 1.016)
					(thickness 0.1524)
				)
			)
		)
		(property "Device Type" "R402H16"
			(at 0.064008 -5.517896 90)
			(unlocked yes)
			(layer "F.Fab")
			(hide yes)
			(effects
				(font
					(size 1.016 1.016)
					(thickness 0.1524)
				)
			)
		)
		(duplicate_pad_numbers_are_jumpers no)
		(fp_line
			(start 0.508 -0.9398)
			(end -0.508 -0.9398)
			(stroke
				(width 0.1524)
				(type default)
			)
			(layer "F.SilkS")
		)
		(fp_line
			(start -0.508 -0.9398)
			(end -0.508 0.9398)
			(stroke
				(width 0.1524)
				(type default)
			)
			(layer "F.SilkS")
		)
		(fp_rect
			(start -0.508 0.9398)
			(end 0.508 -0.9398)
			(stroke
				(width 0)
				(type default)
			)
			(fill no)
			(layer "F.CrtYd")
		)
		(fp_rect
			(start -0.508 0.9398)
			(end 0.508 -0.9398)
			(stroke
				(width 0)
				(type default)
			)
			(fill no)
			(layer "F.Fab")
		)
		(pad "1" smd custom
			(at 0 -0.4445 90)
			(size 0.1397 0.1397)
			(layers "F.Cu" "F.Mask" "F.Paste")
			(net "P3V3")
			(options
				(clearance outline)
				(anchor circle)
			)
			(primitives
				(gr_poly
					(pts
						(arc
							(start -0.1778 -0.2794)
							(mid -0.249642 -0.249642)
							(end -0.2794 -0.1778)
						)
						(arc
							(start -0.2794 0.1778)
							(mid -0.249642 0.249642)
							(end -0.1778 0.2794)
						)
						(arc
							(start 0.1778 0.2794)
							(mid 0.249642 0.249642)
							(end 0.2794 0.1778)
						)
						(arc
							(start 0.2794 -0.1778)
							(mid 0.249642 -0.249642)
							(end 0.1778 -0.2794)
						)
					)
					(width 0)
					(fill yes)
				)
			)
		)
		(pad "2" smd custom
			(at 0 0.4445 90)
			(size 0.1397 0.1397)
			(layers "F.Cu" "F.Mask" "F.Paste")
			(net "HDD_PRSNT_NET1")
			(options
				(clearance outline)
				(anchor circle)
			)
			(primitives
				(gr_poly
					(pts
						(arc
							(start -0.1778 -0.2794)
							(mid -0.249642 -0.249642)
							(end -0.2794 -0.1778)
						)
						(arc
							(start -0.2794 0.1778)
							(mid -0.249642 0.249642)
							(end -0.1778 0.2794)
						)
						(arc
							(start 0.1778 0.2794)
							(mid 0.249642 0.249642)
							(end 0.2794 0.1778)
						)
						(arc
							(start 0.2794 -0.1778)
							(mid 0.249642 -0.249642)
							(end 0.1778 -0.2794)
						)
					)
					(width 0)
					(fill yes)
				)
			)
		)
	)
	(footprint ""
		(layer "F.Cu")
		(at 38.099746 -120.5357 90)
		(property "Reference" "R292"
			(at 0 0 90)
			(layer "F.SilkS")
			(hide yes)
			(effects
				(font
					(size 1.27 1.27)
				)
			)
		)
		(property "Value" "2R2010J-1-GP"
			(at 0.254 -8.0772 90)
			(unlocked yes)
			(layer "F.Fab")
			(hide yes)
			(effects
				(font
					(size 1.016 1.016)
					(thickness 0.1524)
				)
			)
		)
		(property "Device Type" "R2010H28"
			(at 0.254 -9.6774 90)
			(unlocked yes)
			(layer "F.Fab")
			(hide yes)
			(effects
				(font
					(size 1.016 1.016)
					(thickness 0.1524)
				)
			)
		)
		(duplicate_pad_numbers_are_jumpers no)
		(fp_line
			(start 1.651 -3.302)
			(end -1.651 -3.302)
			(stroke
				(width 0.1524)
				(type default)
			)
			(layer "F.SilkS")
		)
		(fp_line
			(start -1.651 -3.302)
			(end -1.651 3.302)
			(stroke
				(width 0.1524)
				(type default)
			)
			(layer "F.SilkS")
		)
		(fp_line
			(start 1.651 3.302)
			(end 1.651 -3.302)
			(stroke
				(width 0.1524)
				(type default)
			)
			(layer "F.SilkS")
		)
		(fp_line
			(start -1.651 3.302)
			(end 1.651 3.302)
			(stroke
				(width 0.1524)
				(type default)
			)
			(layer "F.SilkS")
		)
		(fp_rect
			(start -1.7272 -3.3782)
			(end 1.7272 3.3782)
			(stroke
				(width 0)
				(type default)
			)
			(fill no)
			(layer "F.CrtYd")
		)
		(fp_poly
			(pts
				(xy 1.7272 3.3782) (xy 1.7272 -3.3782) (xy -1.7272 -3.3782) (xy -1.7272 3.3782)
			)
			(stroke
				(width 0)
				(type default)
			)
			(fill no)
			(layer "F.Fab")
		)
		(pad "1" smd rect
			(at 0 -2.3495 90)
			(size 2.794 1.143)
			(layers "F.Cu" "F.Mask" "F.Paste")
			(net "12V_PRE_13")
		)
		(pad "2" smd rect
			(at 0 2.3495 90)
			(size 2.794 1.143)
			(layers "F.Cu" "F.Mask" "F.Paste")
			(net "P12V_HDD13")
		)
	)
	(footprint ""
		(layer "F.Cu")
		(at 25.79243 -236.598206 90)
		(property "Reference" "C296"
			(at 0 0 90)
			(layer "F.SilkS")
			(hide yes)
			(effects
				(font
					(size 1.27 1.27)
				)
			)
		)
		(property "Value" "SCD01U50V2KX-1GP"
			(at 1.1811 -2.7051 90)
			(unlocked yes)
			(layer "F.Fab")
			(hide yes)
			(effects
				(font
					(size 1.016 1.016)
					(thickness 0.1524)
				)
			)
		)
		(property "Device Type" "C402H22"
			(at 1.1811 -4.2291 90)
			(unlocked yes)
			(layer "F.Fab")
			(hide yes)
			(effects
				(font
					(size 1.016 1.016)
					(thickness 0.1524)
				)
			)
		)
		(duplicate_pad_numbers_are_jumpers no)
		(fp_rect
			(start -0.4318 0.9525)
			(end 0.4318 -0.9525)
			(stroke
				(width 0)
				(type default)
			)
			(fill no)
			(layer "F.CrtYd")
		)
		(fp_rect
			(start -0.4318 0.9525)
			(end 0.4318 -0.9525)
			(stroke
				(width 0)
				(type default)
			)
			(fill no)
			(layer "F.Fab")
		)
		(pad "1" smd custom
			(at 0 -0.4445 90)
			(size 0.1524 0.1524)
			(layers "F.Cu" "F.Mask" "F.Paste")
			(net "SAS2X28_DRIVE_RX_N_B12")
			(options
				(clearance outline)
				(anchor circle)
			)
			(primitives
				(gr_poly
					(pts
						(arc
							(start 0.3048 -0.2032)
							(mid 0.275042 -0.275042)
							(end 0.2032 -0.3048)
						)
						(arc
							(start -0.2032 -0.3048)
							(mid -0.275042 -0.275042)
							(end -0.3048 -0.2032)
						)
						(arc
							(start -0.3048 0.2032)
							(mid -0.275042 0.275042)
							(end -0.2032 0.3048)
						)
						(arc
							(start 0.2032 0.3048)
							(mid 0.275042 0.275042)
							(end 0.3048 0.2032)
						)
					)
					(width 0)
					(fill yes)
				)
			)
		)
		(pad "2" smd custom
			(at 0 0.4445 90)
			(size 0.1524 0.1524)
			(layers "F.Cu" "F.Mask" "F.Paste")
			(net "SAS2X28_B_HDD12_RX_-")
			(options
				(clearance outline)
				(anchor circle)
			)
			(primitives
				(gr_poly
					(pts
						(arc
							(start 0.3048 -0.2032)
							(mid 0.275042 -0.275042)
							(end 0.2032 -0.3048)
						)
						(arc
							(start -0.2032 -0.3048)
							(mid -0.275042 -0.275042)
							(end -0.3048 -0.2032)
						)
						(arc
							(start -0.3048 0.2032)
							(mid -0.275042 0.275042)
							(end -0.2032 0.3048)
						)
						(arc
							(start 0.2032 0.3048)
							(mid 0.275042 0.275042)
							(end 0.3048 0.2032)
						)
					)
					(width 0)
					(fill yes)
				)
			)
		)
	)
	(footprint ""
		(layer "F.Cu")
		(at 5.102098 -501.6373 180)
		(property "Reference" "PG3"
			(at 0 0 180)
			(layer "F.SilkS")
			(hide yes)
			(effects
				(font
					(size 1.27 1.27)
				)
			)
		)
		(property "Value" "COPPER-CLOSE-GP-U"
			(at 0.0762 -2.8702 180)
			(unlocked yes)
			(layer "F.Fab")
			(hide yes)
			(effects
				(font
					(size 1.016 1.016)
					(thickness 0.1524)
				)
			)
		)
		(property "Device Type" "CON2C-U"
			(at 0.0762 -4.3942 180)
			(unlocked yes)
			(layer "F.Fab")
			(hide yes)
			(effects
				(font
					(size 1.016 1.016)
					(thickness 0.1524)
				)
			)
		)
		(duplicate_pad_numbers_are_jumpers no)
		(fp_rect
			(start -0.9398 0.9652)
			(end 0.9398 -0.9652)
			(stroke
				(width 0)
				(type default)
			)
			(fill no)
			(layer "F.CrtYd")
		)
		(fp_rect
			(start -0.9398 0.9652)
			(end 0.9398 -0.9652)
			(stroke
				(width 0)
				(type default)
			)
			(fill no)
			(layer "F.Fab")
		)
		(pad "1" smd custom
			(at 0 -0.5334 180)
			(size 0.17145 0.17145)
			(layers "F.Cu" "F.Mask" "F.Paste")
			(net "P5VC_AGND")
			(options
				(clearance outline)
				(anchor circle)
			)
			(primitives
				(gr_poly
					(pts
						(xy -0.127 0.3429) (xy -0.127 0.1651) (xy -0.635 -0.3429) (xy 0.635 -0.3429) (xy 0.127 0.1651)
						(xy 0.127 0.3429)
					)
					(width 0)
					(fill yes)
				)
			)
		)
		(pad "2" smd custom
			(at 0 0.5334 180)
			(size 0.17145 0.17145)
			(layers "F.Cu" "F.Mask" "F.Paste")
			(net "GND")
			(options
				(clearance outline)
				(anchor circle)
			)
			(primitives
				(gr_poly
					(pts
						(xy -0.635 0.3429) (xy -0.127 -0.1651) (xy -0.127 -0.3429) (xy 0.127 -0.3429) (xy 0.127 -0.1651)
						(xy 0.635 0.3429)
					)
					(width 0)
					(fill yes)
				)
			)
		)
	)
	(footprint ""
		(layer "F.Cu")
		(at 213.4616 -497.713 180)
		(property "Reference" "C111"
			(at 0 0 180)
			(layer "F.SilkS")
			(hide yes)
			(effects
				(font
					(size 1.27 1.27)
				)
			)
		)
		(property "Value" "SC10U25V6KX-1GP"
			(at -0.0762 -5.1308 180)
			(unlocked yes)
			(layer "F.Fab")
			(hide yes)
			(effects
				(font
					(size 1.016 1.016)
					(thickness 0.1524)
				)
			)
		)
		(property "Device Type" "C1206H71"
			(at -0.127 -6.6548 180)
			(unlocked yes)
			(layer "F.Fab")
			(hide yes)
			(effects
				(font
					(size 1.016 1.016)
					(thickness 0.1524)
				)
			)
		)
		(duplicate_pad_numbers_are_jumpers no)
		(fp_line
			(start 1.016 2.2352)
			(end -1.016 2.2352)
			(stroke
				(width 0.1524)
				(type default)
			)
			(layer "F.SilkS")
		)
		(fp_line
			(start 1.016 0.8382)
			(end 1.016 2.2352)
			(stroke
				(width 0.1524)
				(type default)
			)
			(layer "F.SilkS")
		)
		(fp_line
			(start 1.016 -2.2352)
			(end 1.016 -0.8382)
			(stroke
				(width 0.1524)
				(type default)
			)
			(layer "F.SilkS")
		)
		(fp_line
			(start -1.016 2.2352)
			(end -1.016 0.8382)
			(stroke
				(width 0.1524)
				(type default)
			)
			(layer "F.SilkS")
		)
		(fp_line
			(start -1.016 -0.8382)
			(end -1.016 -2.2352)
			(stroke
				(width 0.1524)
				(type default)
			)
			(layer "F.SilkS")
		)
		(fp_line
			(start -1.016 -2.2352)
			(end 1.016 -2.2352)
			(stroke
				(width 0.1524)
				(type default)
			)
			(layer "F.SilkS")
		)
		(fp_rect
			(start -1.0922 2.3114)
			(end 1.0922 -2.3114)
			(stroke
				(width 0)
				(type default)
			)
			(fill no)
			(layer "F.CrtYd")
		)
		(fp_poly
			(pts
				(xy 1.0922 -2.3114) (xy 1.0922 2.3114) (xy -1.0922 2.3114) (xy -1.0922 -2.3114)
			)
			(stroke
				(width 0)
				(type default)
			)
			(fill no)
			(layer "F.Fab")
		)
		(pad "1" smd rect
			(at 0 -1.397 180)
			(size 1.651 1.27)
			(layers "F.Cu" "F.Mask" "F.Paste")
			(net "P12V_HDD0")
		)
		(pad "2" smd rect
			(at 0 1.397 180)
			(size 1.651 1.27)
			(layers "F.Cu" "F.Mask" "F.Paste")
			(net "GND")
		)
	)
	(footprint ""
		(layer "F.Cu")
		(at 39.572946 -137.1727 90)
		(property "Reference" "R314"
			(at 0 0 90)
			(layer "F.SilkS")
			(hide yes)
			(effects
				(font
					(size 1.27 1.27)
				)
			)
		)
		(property "Value" "0R2J-2-GP"
			(at 0.064008 -3.993896 90)
			(unlocked yes)
			(layer "F.Fab")
			(hide yes)
			(effects
				(font
					(size 1.016 1.016)
					(thickness 0.1524)
				)
			)
		)
		(property "Device Type" "R402H16"
			(at 0.064008 -5.517896 90)
			(unlocked yes)
			(layer "F.Fab")
			(hide yes)
			(effects
				(font
					(size 1.016 1.016)
					(thickness 0.1524)
				)
			)
		)
		(duplicate_pad_numbers_are_jumpers no)
		(fp_line
			(start 0.508 -0.9398)
			(end -0.508 -0.9398)
			(stroke
				(width 0.1524)
				(type default)
			)
			(layer "F.SilkS")
		)
		(fp_line
			(start -0.508 -0.9398)
			(end -0.508 0.9398)
			(stroke
				(width 0.1524)
				(type default)
			)
			(layer "F.SilkS")
		)
		(fp_rect
			(start -0.508 0.9398)
			(end 0.508 -0.9398)
			(stroke
				(width 0)
				(type default)
			)
			(fill no)
			(layer "F.CrtYd")
		)
		(fp_rect
			(start -0.508 0.9398)
			(end 0.508 -0.9398)
			(stroke
				(width 0)
				(type default)
			)
			(fill no)
			(layer "F.Fab")
		)
		(pad "1" smd custom
			(at 0 -0.4445 90)
			(size 0.1397 0.1397)
			(layers "F.Cu" "F.Mask" "F.Paste")
			(net "I2C_B_SDA")
			(options
				(clearance outline)
				(anchor circle)
			)
			(primitives
				(gr_poly
					(pts
						(arc
							(start -0.1778 -0.2794)
							(mid -0.249642 -0.249642)
							(end -0.2794 -0.1778)
						)
						(arc
							(start -0.2794 0.1778)
							(mid -0.249642 0.249642)
							(end -0.1778 0.2794)
						)
						(arc
							(start 0.1778 0.2794)
							(mid 0.249642 0.249642)
							(end 0.2794 0.1778)
						)
						(arc
							(start 0.2794 -0.1778)
							(mid 0.249642 -0.249642)
							(end 0.1778 -0.2794)
						)
					)
					(width 0)
					(fill yes)
				)
			)
		)
		(pad "2" smd custom
			(at 0 0.4445 90)
			(size 0.1397 0.1397)
			(layers "F.Cu" "F.Mask" "F.Paste")
			(net "TMP2_SDA")
			(options
				(clearance outline)
				(anchor circle)
			)
			(primitives
				(gr_poly
					(pts
						(arc
							(start -0.1778 -0.2794)
							(mid -0.249642 -0.249642)
							(end -0.2794 -0.1778)
						)
						(arc
							(start -0.2794 0.1778)
							(mid -0.249642 0.249642)
							(end -0.1778 0.2794)
						)
						(arc
							(start 0.1778 0.2794)
							(mid 0.249642 0.249642)
							(end 0.2794 0.1778)
						)
						(arc
							(start 0.2794 -0.1778)
							(mid 0.249642 -0.249642)
							(end 0.1778 -0.2794)
						)
					)
					(width 0)
					(fill yes)
				)
			)
		)
	)
	(footprint ""
		(layer "F.Cu")
		(at 207.264 -277.495)
		(property "Reference" "C366"
			(at 0 0 0)
			(layer "F.SilkS")
			(hide yes)
			(effects
				(font
					(size 1.27 1.27)
				)
			)
		)
		(property "Value" "SCD033U25V2KX-GP"
			(at 1.1811 -2.7051 0)
			(unlocked yes)
			(layer "F.Fab")
			(hide yes)
			(effects
				(font
					(size 1.016 1.016)
					(thickness 0.1524)
				)
			)
		)
		(property "Device Type" "C402H22"
			(at 1.1811 -4.2291 0)
			(unlocked yes)
			(layer "F.Fab")
			(hide yes)
			(effects
				(font
					(size 1.016 1.016)
					(thickness 0.1524)
				)
			)
		)
		(duplicate_pad_numbers_are_jumpers no)
		(fp_rect
			(start -0.4318 0.9525)
			(end 0.4318 -0.9525)
			(stroke
				(width 0)
				(type default)
			)
			(fill no)
			(layer "F.CrtYd")
		)
		(fp_rect
			(start -0.4318 0.9525)
			(end 0.4318 -0.9525)
			(stroke
				(width 0)
				(type default)
			)
			(fill no)
			(layer "F.Fab")
		)
		(pad "1" smd custom
			(at 0 -0.4445)
			(size 0.1524 0.1524)
			(layers "F.Cu" "F.Mask" "F.Paste")
			(net "SW_HDD2_P")
			(options
				(clearance outline)
				(anchor circle)
			)
			(primitives
				(gr_poly
					(pts
						(arc
							(start 0.3048 -0.2032)
							(mid 0.275042 -0.275042)
							(end 0.2032 -0.3048)
						)
						(arc
							(start -0.2032 -0.3048)
							(mid -0.275042 -0.275042)
							(end -0.3048 -0.2032)
						)
						(arc
							(start -0.3048 0.2032)
							(mid -0.275042 0.275042)
							(end -0.2032 0.3048)
						)
						(arc
							(start 0.2032 0.3048)
							(mid 0.275042 0.275042)
							(end 0.3048 0.2032)
						)
					)
					(width 0)
					(fill yes)
				)
			)
		)
		(pad "2" smd custom
			(at 0 0.4445)
			(size 0.1524 0.1524)
			(layers "F.Cu" "F.Mask" "F.Paste")
			(net "GND")
			(options
				(clearance outline)
				(anchor circle)
			)
			(primitives
				(gr_poly
					(pts
						(arc
							(start 0.3048 -0.2032)
							(mid 0.275042 -0.275042)
							(end 0.2032 -0.3048)
						)
						(arc
							(start -0.2032 -0.3048)
							(mid -0.275042 -0.275042)
							(end -0.3048 -0.2032)
						)
						(arc
							(start -0.3048 0.2032)
							(mid -0.275042 0.275042)
							(end -0.2032 0.3048)
						)
						(arc
							(start 0.2032 0.3048)
							(mid 0.275042 0.275042)
							(end 0.3048 0.2032)
						)
					)
					(width 0)
					(fill yes)
				)
			)
		)
	)
	(footprint ""
		(layer "F.Cu")
		(at 46.964346 -142.0622 -90)
		(property "Reference" "R498"
			(at 0 0 270)
			(layer "F.SilkS")
			(hide yes)
			(effects
				(font
					(size 1.27 1.27)
				)
			)
		)
		(property "Value" "1KR2F-3-GP"
			(at 0.064008 -3.993896 270)
			(unlocked yes)
			(layer "F.Fab")
			(hide yes)
			(effects
				(font
					(size 1.016 1.016)
					(thickness 0.1524)
				)
			)
		)
		(property "Device Type" "R402H16"
			(at 0.064008 -5.517896 270)
			(unlocked yes)
			(layer "F.Fab")
			(hide yes)
			(effects
				(font
					(size 1.016 1.016)
					(thickness 0.1524)
				)
			)
		)
		(duplicate_pad_numbers_are_jumpers no)
		(fp_line
			(start -0.508 -0.9398)
			(end -0.508 0.9398)
			(stroke
				(width 0.1524)
				(type default)
			)
			(layer "F.SilkS")
		)
		(fp_line
			(start 0.508 -0.9398)
			(end -0.508 -0.9398)
			(stroke
				(width 0.1524)
				(type default)
			)
			(layer "F.SilkS")
		)
		(fp_rect
			(start -0.508 0.9398)
			(end 0.508 -0.9398)
			(stroke
				(width 0)
				(type default)
			)
			(fill no)
			(layer "F.CrtYd")
		)
		(fp_rect
			(start -0.508 0.9398)
			(end 0.508 -0.9398)
			(stroke
				(width 0)
				(type default)
			)
			(fill no)
			(layer "F.Fab")
		)
		(pad "1" smd custom
			(at 0 -0.4445 270)
			(size 0.1397 0.1397)
			(layers "F.Cu" "F.Mask" "F.Paste")
			(net "FLT_HDD8_B")
			(options
				(clearance outline)
				(anchor circle)
			)
			(primitives
				(gr_poly
					(pts
						(arc
							(start -0.1778 -0.2794)
							(mid -0.249642 -0.249642)
							(end -0.2794 -0.1778)
						)
						(arc
							(start -0.2794 0.1778)
							(mid -0.249642 0.249642)
							(end -0.1778 0.2794)
						)
						(arc
							(start 0.1778 0.2794)
							(mid 0.249642 0.249642)
							(end 0.2794 0.1778)
						)
						(arc
							(start 0.2794 -0.1778)
							(mid 0.249642 -0.249642)
							(end 0.1778 -0.2794)
						)
					)
					(width 0)
					(fill yes)
				)
			)
		)
		(pad "2" smd custom
			(at 0 0.4445 270)
			(size 0.1397 0.1397)
			(layers "F.Cu" "F.Mask" "F.Paste")
			(net "FLT_HDD8_DRIVE")
			(options
				(clearance outline)
				(anchor circle)
			)
			(primitives
				(gr_poly
					(pts
						(arc
							(start -0.1778 -0.2794)
							(mid -0.249642 -0.249642)
							(end -0.2794 -0.1778)
						)
						(arc
							(start -0.2794 0.1778)
							(mid -0.249642 0.249642)
							(end -0.1778 0.2794)
						)
						(arc
							(start 0.1778 0.2794)
							(mid 0.249642 0.249642)
							(end 0.2794 0.1778)
						)
						(arc
							(start 0.2794 -0.1778)
							(mid 0.249642 -0.249642)
							(end 0.1778 -0.2794)
						)
					)
					(width 0)
					(fill yes)
				)
			)
		)
	)
	(footprint ""
		(layer "F.Cu")
		(at 190.880746 -290.0807 180)
		(property "Reference" "R140"
			(at 0 0 180)
			(layer "F.SilkS")
			(hide yes)
			(effects
				(font
					(size 1.27 1.27)
				)
			)
		)
		(property "Value" "0R2J-2-GP"
			(at 0.064008 -3.993896 180)
			(unlocked yes)
			(layer "F.Fab")
			(hide yes)
			(effects
				(font
					(size 1.016 1.016)
					(thickness 0.1524)
				)
			)
		)
		(property "Device Type" "R402H16"
			(at 0.064008 -5.517896 180)
			(unlocked yes)
			(layer "F.Fab")
			(hide yes)
			(effects
				(font
					(size 1.016 1.016)
					(thickness 0.1524)
				)
			)
		)
		(duplicate_pad_numbers_are_jumpers no)
		(fp_line
			(start 0.508 -0.9398)
			(end -0.508 -0.9398)
			(stroke
				(width 0.1524)
				(type default)
			)
			(layer "F.SilkS")
		)
		(fp_line
			(start -0.508 -0.9398)
			(end -0.508 0.9398)
			(stroke
				(width 0.1524)
				(type default)
			)
			(layer "F.SilkS")
		)
		(fp_rect
			(start -0.508 0.9398)
			(end 0.508 -0.9398)
			(stroke
				(width 0)
				(type default)
			)
			(fill no)
			(layer "F.CrtYd")
		)
		(fp_rect
			(start -0.508 0.9398)
			(end 0.508 -0.9398)
			(stroke
				(width 0)
				(type default)
			)
			(fill no)
			(layer "F.Fab")
		)
		(pad "1" smd custom
			(at 0 -0.4445 180)
			(size 0.1397 0.1397)
			(layers "F.Cu" "F.Mask" "F.Paste")
			(net "SW_PWR_HDD2")
			(options
				(clearance outline)
				(anchor circle)
			)
			(primitives
				(gr_poly
					(pts
						(arc
							(start -0.1778 -0.2794)
							(mid -0.249642 -0.249642)
							(end -0.2794 -0.1778)
						)
						(arc
							(start -0.2794 0.1778)
							(mid -0.249642 0.249642)
							(end -0.1778 0.2794)
						)
						(arc
							(start 0.1778 0.2794)
							(mid 0.249642 0.249642)
							(end 0.2794 0.1778)
						)
						(arc
							(start 0.2794 -0.1778)
							(mid 0.249642 -0.249642)
							(end 0.1778 -0.2794)
						)
					)
					(width 0)
					(fill yes)
				)
			)
		)
		(pad "2" smd custom
			(at 0 0.4445 180)
			(size 0.1397 0.1397)
			(layers "F.Cu" "F.Mask" "F.Paste")
			(net "SW_PWR_R_HDD2")
			(options
				(clearance outline)
				(anchor circle)
			)
			(primitives
				(gr_poly
					(pts
						(arc
							(start -0.1778 -0.2794)
							(mid -0.249642 -0.249642)
							(end -0.2794 -0.1778)
						)
						(arc
							(start -0.2794 0.1778)
							(mid -0.249642 0.249642)
							(end -0.1778 0.2794)
						)
						(arc
							(start 0.1778 0.2794)
							(mid 0.249642 0.249642)
							(end 0.2794 0.1778)
						)
						(arc
							(start 0.2794 -0.1778)
							(mid 0.249642 -0.249642)
							(end 0.1778 -0.2794)
						)
					)
					(width 0)
					(fill yes)
				)
			)
		)
	)
	(footprint ""
		(layer "F.Cu")
		(at 35.941 -305.308 90)
		(property "Reference" "R574"
			(at 0 0 90)
			(layer "F.SilkS")
			(hide yes)
			(effects
				(font
					(size 1.27 1.27)
				)
			)
		)
		(property "Value" "300KR2F-GP"
			(at 0.064008 -3.993896 90)
			(unlocked yes)
			(layer "F.Fab")
			(hide yes)
			(effects
				(font
					(size 1.016 1.016)
					(thickness 0.1524)
				)
			)
		)
		(property "Device Type" "R402H16"
			(at 0.064008 -5.517896 90)
			(unlocked yes)
			(layer "F.Fab")
			(hide yes)
			(effects
				(font
					(size 1.016 1.016)
					(thickness 0.1524)
				)
			)
		)
		(duplicate_pad_numbers_are_jumpers no)
		(fp_line
			(start 0.508 -0.9398)
			(end -0.508 -0.9398)
			(stroke
				(width 0.1524)
				(type default)
			)
			(layer "F.SilkS")
		)
		(fp_line
			(start -0.508 -0.9398)
			(end -0.508 0.9398)
			(stroke
				(width 0.1524)
				(type default)
			)
			(layer "F.SilkS")
		)
		(fp_rect
			(start -0.508 0.9398)
			(end 0.508 -0.9398)
			(stroke
				(width 0)
				(type default)
			)
			(fill no)
			(layer "F.CrtYd")
		)
		(fp_rect
			(start -0.508 0.9398)
			(end 0.508 -0.9398)
			(stroke
				(width 0)
				(type default)
			)
			(fill no)
			(layer "F.Fab")
		)
		(pad "1" smd custom
			(at 0 -0.4445 90)
			(size 0.1397 0.1397)
			(layers "F.Cu" "F.Mask" "F.Paste")
			(net "SW_HDD11_N")
			(options
				(clearance outline)
				(anchor circle)
			)
			(primitives
				(gr_poly
					(pts
						(arc
							(start -0.1778 -0.2794)
							(mid -0.249642 -0.249642)
							(end -0.2794 -0.1778)
						)
						(arc
							(start -0.2794 0.1778)
							(mid -0.249642 0.249642)
							(end -0.1778 0.2794)
						)
						(arc
							(start 0.1778 0.2794)
							(mid 0.249642 0.249642)
							(end 0.2794 0.1778)
						)
						(arc
							(start 0.2794 -0.1778)
							(mid 0.249642 -0.249642)
							(end 0.1778 -0.2794)
						)
					)
					(width 0)
					(fill yes)
				)
			)
		)
		(pad "2" smd custom
			(at 0 0.4445 90)
			(size 0.1397 0.1397)
			(layers "F.Cu" "F.Mask" "F.Paste")
			(net "P12V")
			(options
				(clearance outline)
				(anchor circle)
			)
			(primitives
				(gr_poly
					(pts
						(arc
							(start -0.1778 -0.2794)
							(mid -0.249642 -0.249642)
							(end -0.2794 -0.1778)
						)
						(arc
							(start -0.2794 0.1778)
							(mid -0.249642 0.249642)
							(end -0.1778 0.2794)
						)
						(arc
							(start 0.1778 0.2794)
							(mid 0.249642 0.249642)
							(end 0.2794 0.1778)
						)
						(arc
							(start 0.2794 -0.1778)
							(mid 0.249642 -0.249642)
							(end 0.1778 -0.2794)
						)
					)
					(width 0)
					(fill yes)
				)
			)
		)
	)
	(footprint ""
		(layer "F.Cu")
		(at 202.864974 -494.891822 -90)
		(property "Reference" "R423"
			(at 0 0 270)
			(layer "F.SilkS")
			(hide yes)
			(effects
				(font
					(size 1.27 1.27)
				)
			)
		)
		(property "Value" "4K7R2J-2-GP"
			(at 0.064008 -3.993896 270)
			(unlocked yes)
			(layer "F.Fab")
			(hide yes)
			(effects
				(font
					(size 1.016 1.016)
					(thickness 0.1524)
				)
			)
		)
		(property "Device Type" "R402H16"
			(at 0.064008 -5.517896 270)
			(unlocked yes)
			(layer "F.Fab")
			(hide yes)
			(effects
				(font
					(size 1.016 1.016)
					(thickness 0.1524)
				)
			)
		)
		(duplicate_pad_numbers_are_jumpers no)
		(fp_line
			(start -0.508 -0.9398)
			(end -0.508 0.9398)
			(stroke
				(width 0.1524)
				(type default)
			)
			(layer "F.SilkS")
		)
		(fp_line
			(start 0.508 -0.9398)
			(end -0.508 -0.9398)
			(stroke
				(width 0.1524)
				(type default)
			)
			(layer "F.SilkS")
		)
		(fp_rect
			(start -0.508 0.9398)
			(end 0.508 -0.9398)
			(stroke
				(width 0)
				(type default)
			)
			(fill no)
			(layer "F.CrtYd")
		)
		(fp_rect
			(start -0.508 0.9398)
			(end 0.508 -0.9398)
			(stroke
				(width 0)
				(type default)
			)
			(fill no)
			(layer "F.Fab")
		)
		(pad "1" smd custom
			(at 0 -0.4445 270)
			(size 0.1397 0.1397)
			(layers "F.Cu" "F.Mask" "F.Paste")
			(net "P3V3")
			(options
				(clearance outline)
				(anchor circle)
			)
			(primitives
				(gr_poly
					(pts
						(arc
							(start -0.1778 -0.2794)
							(mid -0.249642 -0.249642)
							(end -0.2794 -0.1778)
						)
						(arc
							(start -0.2794 0.1778)
							(mid -0.249642 0.249642)
							(end -0.1778 0.2794)
						)
						(arc
							(start 0.1778 0.2794)
							(mid 0.249642 0.249642)
							(end 0.2794 0.1778)
						)
						(arc
							(start 0.2794 -0.1778)
							(mid 0.249642 -0.249642)
							(end 0.1778 -0.2794)
						)
					)
					(width 0)
					(fill yes)
				)
			)
		)
		(pad "2" smd custom
			(at 0 0.4445 270)
			(size 0.1397 0.1397)
			(layers "F.Cu" "F.Mask" "F.Paste")
			(net "SAS2X28_A_HDD0_FLT")
			(options
				(clearance outline)
				(anchor circle)
			)
			(primitives
				(gr_poly
					(pts
						(arc
							(start -0.1778 -0.2794)
							(mid -0.249642 -0.249642)
							(end -0.2794 -0.1778)
						)
						(arc
							(start -0.2794 0.1778)
							(mid -0.249642 0.249642)
							(end -0.1778 0.2794)
						)
						(arc
							(start 0.1778 0.2794)
							(mid 0.249642 0.249642)
							(end 0.2794 0.1778)
						)
						(arc
							(start 0.2794 -0.1778)
							(mid 0.249642 -0.249642)
							(end 0.1778 -0.2794)
						)
					)
					(width 0)
					(fill yes)
				)
			)
		)
	)
	(footprint ""
		(layer "F.Cu")
		(at 55.625492 -80.038956 180)
		(property "Reference" "C250"
			(at 0 0 180)
			(layer "F.SilkS")
			(hide yes)
			(effects
				(font
					(size 1.27 1.27)
				)
			)
		)
		(property "Value" "SC1U16V3KX-5GP"
			(at 0 -2.8194 180)
			(unlocked yes)
			(layer "F.Fab")
			(hide yes)
			(effects
				(font
					(size 1.016 1.016)
					(thickness 0.1524)
				)
			)
		)
		(property "Device Type" "C603H36"
			(at 0 -4.3434 180)
			(unlocked yes)
			(layer "F.Fab")
			(hide yes)
			(effects
				(font
					(size 1.016 1.016)
					(thickness 0.1524)
				)
			)
		)
		(duplicate_pad_numbers_are_jumpers no)
		(fp_line
			(start 0.508 0)
			(end -0.508 0)
			(stroke
				(width 0.2032)
				(type default)
			)
			(layer "F.SilkS")
		)
		(fp_rect
			(start -0.5842 1.3335)
			(end 0.5842 -1.3335)
			(stroke
				(width 0)
				(type default)
			)
			(fill no)
			(layer "F.CrtYd")
		)
		(fp_rect
			(start -0.5842 1.3335)
			(end 0.5842 -1.3335)
			(stroke
				(width 0)
				(type default)
			)
			(fill no)
			(layer "F.Fab")
		)
		(pad "1" smd custom
			(at 0 -0.762 180)
			(size 0.2159 0.2159)
			(layers "F.Cu" "F.Mask" "F.Paste")
			(net "P5V_HDD9")
			(options
				(clearance outline)
				(anchor circle)
			)
			(primitives
				(gr_poly
					(pts
						(arc
							(start -0.3302 -0.4318)
							(mid -0.402042 -0.402042)
							(end -0.4318 -0.3302)
						)
						(arc
							(start -0.4318 0.3302)
							(mid -0.402042 0.402042)
							(end -0.3302 0.4318)
						)
						(arc
							(start 0.3302 0.4318)
							(mid 0.402042 0.402042)
							(end 0.4318 0.3302)
						)
						(arc
							(start 0.4318 -0.3302)
							(mid 0.402042 -0.402042)
							(end 0.3302 -0.4318)
						)
					)
					(width 0)
					(fill yes)
				)
			)
		)
		(pad "2" smd custom
			(at 0 0.762 180)
			(size 0.2159 0.2159)
			(layers "F.Cu" "F.Mask" "F.Paste")
			(net "GND")
			(options
				(clearance outline)
				(anchor circle)
			)
			(primitives
				(gr_poly
					(pts
						(arc
							(start -0.3302 -0.4318)
							(mid -0.402042 -0.402042)
							(end -0.4318 -0.3302)
						)
						(arc
							(start -0.4318 0.3302)
							(mid -0.402042 0.402042)
							(end -0.3302 0.4318)
						)
						(arc
							(start 0.3302 0.4318)
							(mid 0.402042 0.402042)
							(end 0.4318 0.3302)
						)
						(arc
							(start 0.4318 -0.3302)
							(mid 0.402042 -0.402042)
							(end 0.3302 -0.4318)
						)
					)
					(width 0)
					(fill yes)
				)
			)
		)
	)
	(footprint ""
		(layer "F.Cu")
		(at 227.499926 -453.159876 180)
		(property "Reference" "LED1"
			(at 0 0 180)
			(layer "F.SilkS")
			(hide yes)
			(effects
				(font
					(size 1.27 1.27)
				)
			)
		)
		(property "Value" "LED-RB-4-GP"
			(at 5.88899 1.80848 180)
			(unlocked yes)
			(layer "F.Fab")
			(hide yes)
			(effects
				(font
					(size 1.016 1.016)
					(thickness 0.1524)
				)
			)
		)
		(property "Device Type" "LED1613-4PH20"
			(at 5.88899 0.28448 180)
			(unlocked yes)
			(layer "F.Fab")
			(hide yes)
			(effects
				(font
					(size 1.016 1.016)
					(thickness 0.1524)
				)
			)
		)
		(duplicate_pad_numbers_are_jumpers no)
		(fp_line
			(start 1.4478 0.9652)
			(end -1.4478 0.9652)
			(stroke
				(width 0.1524)
				(type default)
			)
			(layer "F.SilkS")
		)
		(fp_line
			(start 1.4478 -0.9652)
			(end 1.4478 0.9652)
			(stroke
				(width 0.1524)
				(type default)
			)
			(layer "F.SilkS")
		)
		(fp_line
			(start -1.4478 0.9652)
			(end -1.4478 -0.9652)
			(stroke
				(width 0.1524)
				(type default)
			)
			(layer "F.SilkS")
		)
		(fp_line
			(start -1.4478 0.9652)
			(end -1.4478 -0.9652)
			(stroke
				(width 0.508)
				(type default)
			)
			(layer "F.SilkS")
		)
		(fp_line
			(start -1.4478 -0.9652)
			(end 1.4478 -0.9652)
			(stroke
				(width 0.1524)
				(type default)
			)
			(layer "F.SilkS")
		)
		(fp_rect
			(start -0.8001 0.6477)
			(end 0.8001 -0.6477)
			(stroke
				(width 0)
				(type default)
			)
			(fill no)
			(layer "F.CrtYd")
		)
		(fp_poly
			(pts
				(xy -1.7018 1.2192) (xy -1.7018 -0.06223) (xy -0.8001 -0.06223) (xy -0.8001 0.6477) (xy 0.8001 0.6477)
				(xy 0.8001 -0.6477) (xy -0.8001 -0.6477) (xy -0.8001 -0.0635) (xy -1.7018 -0.0635) (xy -1.7018 -1.2192)
				(xy 1.7018 -1.2192) (xy 1.7018 1.2192)
			)
			(stroke
				(width 0)
				(type default)
			)
			(fill no)
			(layer "F.CrtYd")
		)
		(fp_rect
			(start -1.7018 1.2192)
			(end 1.7018 -1.2192)
			(stroke
				(width 0)
				(type default)
			)
			(fill no)
			(layer "F.Fab")
		)
		(pad "1" smd rect
			(at -0.73025 0.4064 180)
			(size 0.9144 0.6096)
			(layers "F.Cu" "F.Mask" "F.Paste")
			(net "DRV_ACT_NET0")
		)
		(pad "2" smd rect
			(at -0.73025 -0.4064 180)
			(size 0.9144 0.6096)
			(layers "F.Cu" "F.Mask" "F.Paste")
			(net "FLT_NET_HDD0")
		)
		(pad "3" smd rect
			(at 0.73025 -0.4064 180)
			(size 0.9144 0.6096)
			(layers "F.Cu" "F.Mask" "F.Paste")
			(net "FLT_HDD0")
		)
		(pad "4" smd rect
			(at 0.73025 0.4064 180)
			(size 0.9144 0.6096)
			(layers "F.Cu" "F.Mask" "F.Paste")
			(net "DRV_ACT_0")
		)
	)
	(footprint ""
		(layer "F.Cu")
		(at 29.209746 -318.798702 90)
		(property "Reference" "R264"
			(at 0 0 90)
			(layer "F.SilkS")
			(hide yes)
			(effects
				(font
					(size 1.27 1.27)
				)
			)
		)
		(property "Value" "2R2010J-1-GP"
			(at 0.254 -8.0772 90)
			(unlocked yes)
			(layer "F.Fab")
			(hide yes)
			(effects
				(font
					(size 1.016 1.016)
					(thickness 0.1524)
				)
			)
		)
		(property "Device Type" "R2010H28"
			(at 0.254 -9.6774 90)
			(unlocked yes)
			(layer "F.Fab")
			(hide yes)
			(effects
				(font
					(size 1.016 1.016)
					(thickness 0.1524)
				)
			)
		)
		(duplicate_pad_numbers_are_jumpers no)
		(fp_line
			(start 1.651 -3.302)
			(end -1.651 -3.302)
			(stroke
				(width 0.1524)
				(type default)
			)
			(layer "F.SilkS")
		)
		(fp_line
			(start -1.651 -3.302)
			(end -1.651 3.302)
			(stroke
				(width 0.1524)
				(type default)
			)
			(layer "F.SilkS")
		)
		(fp_line
			(start 1.651 3.302)
			(end 1.651 -3.302)
			(stroke
				(width 0.1524)
				(type default)
			)
			(layer "F.SilkS")
		)
		(fp_line
			(start -1.651 3.302)
			(end 1.651 3.302)
			(stroke
				(width 0.1524)
				(type default)
			)
			(layer "F.SilkS")
		)
		(fp_rect
			(start -1.7272 -3.3782)
			(end 1.7272 3.3782)
			(stroke
				(width 0)
				(type default)
			)
			(fill no)
			(layer "F.CrtYd")
		)
		(fp_poly
			(pts
				(xy 1.7272 3.3782) (xy 1.7272 -3.3782) (xy -1.7272 -3.3782) (xy -1.7272 3.3782)
			)
			(stroke
				(width 0)
				(type default)
			)
			(fill no)
			(layer "F.Fab")
		)
		(pad "1" smd rect
			(at 0 -2.3495 90)
			(size 2.794 1.143)
			(layers "F.Cu" "F.Mask" "F.Paste")
			(net "12V_PRE_11")
		)
		(pad "2" smd rect
			(at 0 2.3495 90)
			(size 2.794 1.143)
			(layers "F.Cu" "F.Mask" "F.Paste")
			(net "P12V_HDD11")
		)
	)
	(footprint ""
		(layer "F.Cu")
		(at 25.298146 -274.7518 90)
		(property "Reference" "R495"
			(at 0 0 90)
			(layer "F.SilkS")
			(hide yes)
			(effects
				(font
					(size 1.27 1.27)
				)
			)
		)
		(property "Value" "4K7R2J-2-GP"
			(at 0.064008 -3.993896 90)
			(unlocked yes)
			(layer "F.Fab")
			(hide yes)
			(effects
				(font
					(size 1.016 1.016)
					(thickness 0.1524)
				)
			)
		)
		(property "Device Type" "R402H16"
			(at 0.064008 -5.517896 90)
			(unlocked yes)
			(layer "F.Fab")
			(hide yes)
			(effects
				(font
					(size 1.016 1.016)
					(thickness 0.1524)
				)
			)
		)
		(duplicate_pad_numbers_are_jumpers no)
		(fp_line
			(start 0.508 -0.9398)
			(end -0.508 -0.9398)
			(stroke
				(width 0.1524)
				(type default)
			)
			(layer "F.SilkS")
		)
		(fp_line
			(start -0.508 -0.9398)
			(end -0.508 0.9398)
			(stroke
				(width 0.1524)
				(type default)
			)
			(layer "F.SilkS")
		)
		(fp_rect
			(start -0.508 0.9398)
			(end 0.508 -0.9398)
			(stroke
				(width 0)
				(type default)
			)
			(fill no)
			(layer "F.CrtYd")
		)
		(fp_rect
			(start -0.508 0.9398)
			(end 0.508 -0.9398)
			(stroke
				(width 0)
				(type default)
			)
			(fill no)
			(layer "F.Fab")
		)
		(pad "1" smd custom
			(at 0 -0.4445 90)
			(size 0.1397 0.1397)
			(layers "F.Cu" "F.Mask" "F.Paste")
			(net "P3V3")
			(options
				(clearance outline)
				(anchor circle)
			)
			(primitives
				(gr_poly
					(pts
						(arc
							(start -0.1778 -0.2794)
							(mid -0.249642 -0.249642)
							(end -0.2794 -0.1778)
						)
						(arc
							(start -0.2794 0.1778)
							(mid -0.249642 0.249642)
							(end -0.1778 0.2794)
						)
						(arc
							(start 0.1778 0.2794)
							(mid 0.249642 0.249642)
							(end 0.2794 0.1778)
						)
						(arc
							(start 0.2794 -0.1778)
							(mid 0.249642 -0.249642)
							(end 0.1778 -0.2794)
						)
					)
					(width 0)
					(fill yes)
				)
			)
		)
		(pad "2" smd custom
			(at 0 0.4445 90)
			(size 0.1397 0.1397)
			(layers "F.Cu" "F.Mask" "F.Paste")
			(net "SAS2X28_B_HDD7_FLT")
			(options
				(clearance outline)
				(anchor circle)
			)
			(primitives
				(gr_poly
					(pts
						(arc
							(start -0.1778 -0.2794)
							(mid -0.249642 -0.249642)
							(end -0.2794 -0.1778)
						)
						(arc
							(start -0.2794 0.1778)
							(mid -0.249642 0.249642)
							(end -0.1778 0.2794)
						)
						(arc
							(start 0.1778 0.2794)
							(mid 0.249642 0.249642)
							(end 0.2794 0.1778)
						)
						(arc
							(start 0.2794 -0.1778)
							(mid 0.249642 -0.249642)
							(end 0.1778 -0.2794)
						)
					)
					(width 0)
					(fill yes)
				)
			)
		)
	)
	(footprint ""
		(layer "F.Cu")
		(at 230.631746 -21.9837 180)
		(property "Reference" "PC9"
			(at 0 0 180)
			(layer "F.SilkS")
			(hide yes)
			(effects
				(font
					(size 1.27 1.27)
				)
			)
		)
		(property "Value" "SC2200P50V2KX-2GP"
			(at 1.1811 -2.7051 180)
			(unlocked yes)
			(layer "F.Fab")
			(hide yes)
			(effects
				(font
					(size 1.016 1.016)
					(thickness 0.1524)
				)
			)
		)
		(property "Device Type" "C402H22"
			(at 1.1811 -4.2291 180)
			(unlocked yes)
			(layer "F.Fab")
			(hide yes)
			(effects
				(font
					(size 1.016 1.016)
					(thickness 0.1524)
				)
			)
		)
		(duplicate_pad_numbers_are_jumpers no)
		(fp_rect
			(start -0.4318 0.9525)
			(end 0.4318 -0.9525)
			(stroke
				(width 0)
				(type default)
			)
			(fill no)
			(layer "F.CrtYd")
		)
		(fp_rect
			(start -0.4318 0.9525)
			(end 0.4318 -0.9525)
			(stroke
				(width 0)
				(type default)
			)
			(fill no)
			(layer "F.Fab")
		)
		(pad "1" smd custom
			(at 0 -0.4445 180)
			(size 0.1524 0.1524)
			(layers "F.Cu" "F.Mask" "F.Paste")
			(net "P5VA_LL")
			(options
				(clearance outline)
				(anchor circle)
			)
			(primitives
				(gr_poly
					(pts
						(arc
							(start 0.3048 -0.2032)
							(mid 0.275042 -0.275042)
							(end 0.2032 -0.3048)
						)
						(arc
							(start -0.2032 -0.3048)
							(mid -0.275042 -0.275042)
							(end -0.3048 -0.2032)
						)
						(arc
							(start -0.3048 0.2032)
							(mid -0.275042 0.275042)
							(end -0.2032 0.3048)
						)
						(arc
							(start 0.2032 0.3048)
							(mid 0.275042 0.275042)
							(end 0.3048 0.2032)
						)
					)
					(width 0)
					(fill yes)
				)
			)
		)
		(pad "2" smd custom
			(at 0 0.4445 180)
			(size 0.1524 0.1524)
			(layers "F.Cu" "F.Mask" "F.Paste")
			(net "P5VA_SNB")
			(options
				(clearance outline)
				(anchor circle)
			)
			(primitives
				(gr_poly
					(pts
						(arc
							(start 0.3048 -0.2032)
							(mid 0.275042 -0.275042)
							(end 0.2032 -0.3048)
						)
						(arc
							(start -0.2032 -0.3048)
							(mid -0.275042 -0.275042)
							(end -0.3048 -0.2032)
						)
						(arc
							(start -0.3048 0.2032)
							(mid -0.275042 0.275042)
							(end -0.2032 0.3048)
						)
						(arc
							(start 0.2032 0.3048)
							(mid 0.275042 0.275042)
							(end 0.3048 0.2032)
						)
					)
					(width 0)
					(fill yes)
				)
			)
		)
	)
	(footprint ""
		(layer "F.Cu")
		(at 207.8736 -376.0724 -90)
		(property "Reference" "Q32"
			(at 0 0 270)
			(layer "F.SilkS")
			(hide yes)
			(effects
				(font
					(size 1.27 1.27)
				)
			)
		)
		(property "Value" "2N7002DW-7F-GP"
			(at -2.3622 -8.2042 270)
			(unlocked yes)
			(layer "F.Fab")
			(hide yes)
			(effects
				(font
					(size 1.016 1.016)
					(thickness 0.1524)
				)
			)
		)
		(property "Device Type" "SOT-363H44"
			(at -2.3622 -10.1092 270)
			(unlocked yes)
			(layer "F.Fab")
			(hide yes)
			(effects
				(font
					(size 1.016 1.016)
					(thickness 0.1524)
				)
			)
		)
		(duplicate_pad_numbers_are_jumpers no)
		(fp_line
			(start -1.4478 1.7018)
			(end 1.4478 1.7018)
			(stroke
				(width 0.1524)
				(type default)
			)
			(layer "F.SilkS")
		)
		(fp_line
			(start 1.4478 1.7018)
			(end 1.4478 -1.7018)
			(stroke
				(width 0.1524)
				(type default)
			)
			(layer "F.SilkS")
		)
		(fp_line
			(start -1.27 1.524)
			(end -1.27 0.6604)
			(stroke
				(width 0.4826)
				(type default)
			)
			(layer "F.SilkS")
		)
		(fp_line
			(start -1.4478 -1.7018)
			(end -1.4478 1.7018)
			(stroke
				(width 0.1524)
				(type default)
			)
			(layer "F.SilkS")
		)
		(fp_line
			(start 1.4478 -1.7018)
			(end -1.4478 -1.7018)
			(stroke
				(width 0.1524)
				(type default)
			)
			(layer "F.SilkS")
		)
		(fp_poly
			(pts
				(xy -1.524 -1.778) (xy 1.524 -1.778) (xy 1.524 1.778) (xy -1.524 1.778)
			)
			(stroke
				(width 0)
				(type default)
			)
			(fill no)
			(layer "F.CrtYd")
		)
		(fp_poly
			(pts
				(xy -1.524 -1.778) (xy 1.524 -1.778) (xy 1.524 1.778) (xy -1.524 1.778)
			)
			(stroke
				(width 0)
				(type default)
			)
			(fill no)
			(layer "F.Fab")
		)
		(pad "1" smd rect
			(at -0.65024 0.9398 270)
			(size 0.4064 1.016)
			(layers "F.Cu" "F.Mask" "F.Paste")
			(net "P3V3_HDD1_LED")
		)
		(pad "2" smd rect
			(at 0 0.9398 270)
			(size 0.4064 1.016)
			(layers "F.Cu" "F.Mask" "F.Paste")
			(net "HDD1_LED_G")
		)
		(pad "3" smd rect
			(at 0.65024 0.9398 270)
			(size 0.4064 1.016)
			(layers "F.Cu" "F.Mask" "F.Paste")
			(net "P5VA")
		)
		(pad "4" smd rect
			(at 0.65024 -0.9398 270)
			(size 0.4064 1.016)
			(layers "F.Cu" "F.Mask" "F.Paste")
			(net "P5VA_HDD1_LED")
		)
		(pad "5" smd rect
			(at 0 -0.9398 270)
			(size 0.4064 1.016)
			(layers "F.Cu" "F.Mask" "F.Paste")
			(net "HDD1_LED_G")
		)
		(pad "6" smd rect
			(at -0.65024 -0.9398 270)
			(size 0.4064 1.016)
			(layers "F.Cu" "F.Mask" "F.Paste")
			(net "P3V3")
		)
	)
	(footprint ""
		(layer "F.Cu")
		(at 27.2415 -246.888 -90)
		(property "Reference" "R367"
			(at 0 0 270)
			(layer "F.SilkS")
			(hide yes)
			(effects
				(font
					(size 1.27 1.27)
				)
			)
		)
		(property "Value" "4K7R2J-2-GP"
			(at 0.064008 -3.993896 270)
			(unlocked yes)
			(layer "F.Fab")
			(hide yes)
			(effects
				(font
					(size 1.016 1.016)
					(thickness 0.1524)
				)
			)
		)
		(property "Device Type" "R402H16"
			(at 0.064008 -5.517896 270)
			(unlocked yes)
			(layer "F.Fab")
			(hide yes)
			(effects
				(font
					(size 1.016 1.016)
					(thickness 0.1524)
				)
			)
		)
		(duplicate_pad_numbers_are_jumpers no)
		(fp_line
			(start -0.508 -0.9398)
			(end -0.508 0.9398)
			(stroke
				(width 0.1524)
				(type default)
			)
			(layer "F.SilkS")
		)
		(fp_line
			(start 0.508 -0.9398)
			(end -0.508 -0.9398)
			(stroke
				(width 0.1524)
				(type default)
			)
			(layer "F.SilkS")
		)
		(fp_rect
			(start -0.508 0.9398)
			(end 0.508 -0.9398)
			(stroke
				(width 0)
				(type default)
			)
			(fill no)
			(layer "F.CrtYd")
		)
		(fp_rect
			(start -0.508 0.9398)
			(end 0.508 -0.9398)
			(stroke
				(width 0)
				(type default)
			)
			(fill no)
			(layer "F.Fab")
		)
		(pad "1" smd custom
			(at 0 -0.4445 270)
			(size 0.1397 0.1397)
			(layers "F.Cu" "F.Mask" "F.Paste")
			(net "P3V3")
			(options
				(clearance outline)
				(anchor circle)
			)
			(primitives
				(gr_poly
					(pts
						(arc
							(start -0.1778 -0.2794)
							(mid -0.249642 -0.249642)
							(end -0.2794 -0.1778)
						)
						(arc
							(start -0.2794 0.1778)
							(mid -0.249642 0.249642)
							(end -0.1778 0.2794)
						)
						(arc
							(start 0.1778 0.2794)
							(mid 0.249642 0.249642)
							(end 0.2794 0.1778)
						)
						(arc
							(start 0.2794 -0.1778)
							(mid 0.249642 -0.249642)
							(end 0.1778 -0.2794)
						)
					)
					(width 0)
					(fill yes)
				)
			)
		)
		(pad "2" smd custom
			(at 0 0.4445 270)
			(size 0.1397 0.1397)
			(layers "F.Cu" "F.Mask" "F.Paste")
			(net "I2C_B_SCL")
			(options
				(clearance outline)
				(anchor circle)
			)
			(primitives
				(gr_poly
					(pts
						(arc
							(start -0.1778 -0.2794)
							(mid -0.249642 -0.249642)
							(end -0.2794 -0.1778)
						)
						(arc
							(start -0.2794 0.1778)
							(mid -0.249642 0.249642)
							(end -0.1778 0.2794)
						)
						(arc
							(start 0.1778 0.2794)
							(mid 0.249642 0.249642)
							(end 0.2794 0.1778)
						)
						(arc
							(start 0.2794 -0.1778)
							(mid 0.249642 -0.249642)
							(end 0.1778 -0.2794)
						)
					)
					(width 0)
					(fill yes)
				)
			)
		)
	)
	(footprint ""
		(layer "F.Cu")
		(at 210.2358 -376.5296)
		(property "Reference" "R344"
			(at 0 0 0)
			(layer "F.SilkS")
			(hide yes)
			(effects
				(font
					(size 1.27 1.27)
				)
			)
		)
		(property "Value" "10KR2F-2-GP"
			(at 0.064008 -3.993896 0)
			(unlocked yes)
			(layer "F.Fab")
			(hide yes)
			(effects
				(font
					(size 1.016 1.016)
					(thickness 0.1524)
				)
			)
		)
		(property "Device Type" "R402H16"
			(at 0.064008 -5.517896 0)
			(unlocked yes)
			(layer "F.Fab")
			(hide yes)
			(effects
				(font
					(size 1.016 1.016)
					(thickness 0.1524)
				)
			)
		)
		(duplicate_pad_numbers_are_jumpers no)
		(fp_line
			(start -0.508 -0.9398)
			(end -0.508 0.9398)
			(stroke
				(width 0.1524)
				(type default)
			)
			(layer "F.SilkS")
		)
		(fp_line
			(start 0.508 -0.9398)
			(end -0.508 -0.9398)
			(stroke
				(width 0.1524)
				(type default)
			)
			(layer "F.SilkS")
		)
		(fp_rect
			(start -0.508 0.9398)
			(end 0.508 -0.9398)
			(stroke
				(width 0)
				(type default)
			)
			(fill no)
			(layer "F.CrtYd")
		)
		(fp_rect
			(start -0.508 0.9398)
			(end 0.508 -0.9398)
			(stroke
				(width 0)
				(type default)
			)
			(fill no)
			(layer "F.Fab")
		)
		(pad "1" smd custom
			(at 0 -0.4445)
			(size 0.1397 0.1397)
			(layers "F.Cu" "F.Mask" "F.Paste")
			(net "P12V")
			(options
				(clearance outline)
				(anchor circle)
			)
			(primitives
				(gr_poly
					(pts
						(arc
							(start -0.1778 -0.2794)
							(mid -0.249642 -0.249642)
							(end -0.2794 -0.1778)
						)
						(arc
							(start -0.2794 0.1778)
							(mid -0.249642 0.249642)
							(end -0.1778 0.2794)
						)
						(arc
							(start 0.1778 0.2794)
							(mid 0.249642 0.249642)
							(end 0.2794 0.1778)
						)
						(arc
							(start 0.2794 -0.1778)
							(mid 0.249642 -0.249642)
							(end 0.1778 -0.2794)
						)
					)
					(width 0)
					(fill yes)
				)
			)
		)
		(pad "2" smd custom
			(at 0 0.4445)
			(size 0.1397 0.1397)
			(layers "F.Cu" "F.Mask" "F.Paste")
			(net "HDD1_LED_G")
			(options
				(clearance outline)
				(anchor circle)
			)
			(primitives
				(gr_poly
					(pts
						(arc
							(start -0.1778 -0.2794)
							(mid -0.249642 -0.249642)
							(end -0.2794 -0.1778)
						)
						(arc
							(start -0.2794 0.1778)
							(mid -0.249642 0.249642)
							(end -0.1778 0.2794)
						)
						(arc
							(start 0.1778 0.2794)
							(mid 0.249642 0.249642)
							(end 0.2794 0.1778)
						)
						(arc
							(start 0.2794 -0.1778)
							(mid 0.249642 -0.249642)
							(end 0.1778 -0.2794)
						)
					)
					(width 0)
					(fill yes)
				)
			)
		)
	)
	(footprint ""
		(layer "F.Cu")
		(at 232.384346 -244.3734 -90)
		(property "Reference" "R490"
			(at 0 0 270)
			(layer "F.SilkS")
			(hide yes)
			(effects
				(font
					(size 1.27 1.27)
				)
			)
		)
		(property "Value" "1KR2F-3-GP"
			(at 0.064008 -3.993896 270)
			(unlocked yes)
			(layer "F.Fab")
			(hide yes)
			(effects
				(font
					(size 1.016 1.016)
					(thickness 0.1524)
				)
			)
		)
		(property "Device Type" "R402H16"
			(at 0.064008 -5.517896 270)
			(unlocked yes)
			(layer "F.Fab")
			(hide yes)
			(effects
				(font
					(size 1.016 1.016)
					(thickness 0.1524)
				)
			)
		)
		(duplicate_pad_numbers_are_jumpers no)
		(fp_line
			(start -0.508 -0.9398)
			(end -0.508 0.9398)
			(stroke
				(width 0.1524)
				(type default)
			)
			(layer "F.SilkS")
		)
		(fp_line
			(start 0.508 -0.9398)
			(end -0.508 -0.9398)
			(stroke
				(width 0.1524)
				(type default)
			)
			(layer "F.SilkS")
		)
		(fp_rect
			(start -0.508 0.9398)
			(end 0.508 -0.9398)
			(stroke
				(width 0)
				(type default)
			)
			(fill no)
			(layer "F.CrtYd")
		)
		(fp_rect
			(start -0.508 0.9398)
			(end 0.508 -0.9398)
			(stroke
				(width 0)
				(type default)
			)
			(fill no)
			(layer "F.Fab")
		)
		(pad "1" smd custom
			(at 0 -0.4445 270)
			(size 0.1397 0.1397)
			(layers "F.Cu" "F.Mask" "F.Paste")
			(net "FLT_HDD2_B")
			(options
				(clearance outline)
				(anchor circle)
			)
			(primitives
				(gr_poly
					(pts
						(arc
							(start -0.1778 -0.2794)
							(mid -0.249642 -0.249642)
							(end -0.2794 -0.1778)
						)
						(arc
							(start -0.2794 0.1778)
							(mid -0.249642 0.249642)
							(end -0.1778 0.2794)
						)
						(arc
							(start 0.1778 0.2794)
							(mid 0.249642 0.249642)
							(end 0.2794 0.1778)
						)
						(arc
							(start 0.2794 -0.1778)
							(mid 0.249642 -0.249642)
							(end 0.1778 -0.2794)
						)
					)
					(width 0)
					(fill yes)
				)
			)
		)
		(pad "2" smd custom
			(at 0 0.4445 270)
			(size 0.1397 0.1397)
			(layers "F.Cu" "F.Mask" "F.Paste")
			(net "FLT_HDD2_DRIVE")
			(options
				(clearance outline)
				(anchor circle)
			)
			(primitives
				(gr_poly
					(pts
						(arc
							(start -0.1778 -0.2794)
							(mid -0.249642 -0.249642)
							(end -0.2794 -0.1778)
						)
						(arc
							(start -0.2794 0.1778)
							(mid -0.249642 0.249642)
							(end -0.1778 0.2794)
						)
						(arc
							(start 0.1778 0.2794)
							(mid 0.249642 0.249642)
							(end 0.2794 0.1778)
						)
						(arc
							(start 0.2794 -0.1778)
							(mid 0.249642 -0.249642)
							(end 0.1778 -0.2794)
						)
					)
					(width 0)
					(fill yes)
				)
			)
		)
	)
	(footprint ""
		(layer "F.Cu")
		(at 215.281256 -484.457502 -90)
		(property "Reference" "R100"
			(at 0 0 270)
			(layer "F.SilkS")
			(hide yes)
			(effects
				(font
					(size 1.27 1.27)
				)
			)
		)
		(property "Value" "2R2010J-1-GP"
			(at 0.254 -8.0772 270)
			(unlocked yes)
			(layer "F.Fab")
			(hide yes)
			(effects
				(font
					(size 1.016 1.016)
					(thickness 0.1524)
				)
			)
		)
		(property "Device Type" "R2010H28"
			(at 0.254 -9.6774 270)
			(unlocked yes)
			(layer "F.Fab")
			(hide yes)
			(effects
				(font
					(size 1.016 1.016)
					(thickness 0.1524)
				)
			)
		)
		(duplicate_pad_numbers_are_jumpers no)
		(fp_line
			(start -1.651 3.302)
			(end 1.651 3.302)
			(stroke
				(width 0.1524)
				(type default)
			)
			(layer "F.SilkS")
		)
		(fp_line
			(start 1.651 3.302)
			(end 1.651 -3.302)
			(stroke
				(width 0.1524)
				(type default)
			)
			(layer "F.SilkS")
		)
		(fp_line
			(start -1.651 -3.302)
			(end -1.651 3.302)
			(stroke
				(width 0.1524)
				(type default)
			)
			(layer "F.SilkS")
		)
		(fp_line
			(start 1.651 -3.302)
			(end -1.651 -3.302)
			(stroke
				(width 0.1524)
				(type default)
			)
			(layer "F.SilkS")
		)
		(fp_rect
			(start -1.7272 -3.3782)
			(end 1.7272 3.3782)
			(stroke
				(width 0)
				(type default)
			)
			(fill no)
			(layer "F.CrtYd")
		)
		(fp_poly
			(pts
				(xy 1.7272 3.3782) (xy 1.7272 -3.3782) (xy -1.7272 -3.3782) (xy -1.7272 3.3782)
			)
			(stroke
				(width 0)
				(type default)
			)
			(fill no)
			(layer "F.Fab")
		)
		(pad "1" smd rect
			(at 0 -2.3495 270)
			(size 2.794 1.143)
			(layers "F.Cu" "F.Mask" "F.Paste")
			(net "5V_PRE_0")
		)
		(pad "2" smd rect
			(at 0 2.3495 270)
			(size 2.794 1.143)
			(layers "F.Cu" "F.Mask" "F.Paste")
			(net "P5V_HDD0")
		)
	)
	(footprint ""
		(layer "F.Cu")
		(at 23.114 -394.589 90)
		(property "Reference" "R510"
			(at 0 0 90)
			(layer "F.SilkS")
			(hide yes)
			(effects
				(font
					(size 1.27 1.27)
				)
			)
		)
		(property "Value" "0R2J-2-GP"
			(at 0.064008 -3.993896 90)
			(unlocked yes)
			(layer "F.Fab")
			(hide yes)
			(effects
				(font
					(size 1.016 1.016)
					(thickness 0.1524)
				)
			)
		)
		(property "Device Type" "R402H16"
			(at 0.064008 -5.517896 90)
			(unlocked yes)
			(layer "F.Fab")
			(hide yes)
			(effects
				(font
					(size 1.016 1.016)
					(thickness 0.1524)
				)
			)
		)
		(duplicate_pad_numbers_are_jumpers no)
		(fp_line
			(start 0.508 -0.9398)
			(end -0.508 -0.9398)
			(stroke
				(width 0.1524)
				(type default)
			)
			(layer "F.SilkS")
		)
		(fp_line
			(start -0.508 -0.9398)
			(end -0.508 0.9398)
			(stroke
				(width 0.1524)
				(type default)
			)
			(layer "F.SilkS")
		)
		(fp_rect
			(start -0.508 0.9398)
			(end 0.508 -0.9398)
			(stroke
				(width 0)
				(type default)
			)
			(fill no)
			(layer "F.CrtYd")
		)
		(fp_rect
			(start -0.508 0.9398)
			(end 0.508 -0.9398)
			(stroke
				(width 0)
				(type default)
			)
			(fill no)
			(layer "F.Fab")
		)
		(pad "1" smd custom
			(at 0 -0.4445 90)
			(size 0.1397 0.1397)
			(layers "F.Cu" "F.Mask" "F.Paste")
			(net "I2C_B_SCL_DAMP_A")
			(options
				(clearance outline)
				(anchor circle)
			)
			(primitives
				(gr_poly
					(pts
						(arc
							(start -0.1778 -0.2794)
							(mid -0.249642 -0.249642)
							(end -0.2794 -0.1778)
						)
						(arc
							(start -0.2794 0.1778)
							(mid -0.249642 0.249642)
							(end -0.1778 0.2794)
						)
						(arc
							(start 0.1778 0.2794)
							(mid 0.249642 0.249642)
							(end 0.2794 0.1778)
						)
						(arc
							(start 0.2794 -0.1778)
							(mid 0.249642 -0.249642)
							(end 0.1778 -0.2794)
						)
					)
					(width 0)
					(fill yes)
				)
			)
		)
		(pad "2" smd custom
			(at 0 0.4445 90)
			(size 0.1397 0.1397)
			(layers "F.Cu" "F.Mask" "F.Paste")
			(net "I2C_B_SCL")
			(options
				(clearance outline)
				(anchor circle)
			)
			(primitives
				(gr_poly
					(pts
						(arc
							(start -0.1778 -0.2794)
							(mid -0.249642 -0.249642)
							(end -0.2794 -0.1778)
						)
						(arc
							(start -0.2794 0.1778)
							(mid -0.249642 0.249642)
							(end -0.1778 0.2794)
						)
						(arc
							(start 0.1778 0.2794)
							(mid 0.249642 0.249642)
							(end 0.2794 0.1778)
						)
						(arc
							(start 0.2794 -0.1778)
							(mid 0.249642 -0.249642)
							(end 0.1778 -0.2794)
						)
					)
					(width 0)
					(fill yes)
				)
			)
		)
	)
	(footprint ""
		(layer "F.Cu")
		(at 200.489058 -395.299184 -90)
		(property "Reference" "U5"
			(at 0 0 270)
			(layer "F.SilkS")
			(hide yes)
			(effects
				(font
					(size 1.27 1.27)
				)
			)
		)
		(property "Value" "P2003EVG-GP"
			(at 0 -11.1252 270)
			(unlocked yes)
			(layer "F.Fab")
			(hide yes)
			(effects
				(font
					(size 1.016 1.016)
					(thickness 0.1524)
				)
			)
		)
		(property "Device Type" "SOIC8H79"
			(at 0 -12.6492 270)
			(unlocked yes)
			(layer "F.Fab")
			(hide yes)
			(effects
				(font
					(size 1.016 1.016)
					(thickness 0.1524)
				)
			)
		)
		(duplicate_pad_numbers_are_jumpers no)
		(fp_line
			(start -2.6162 3.429)
			(end -2.6162 1.4732)
			(stroke
				(width 0.4064)
				(type default)
			)
			(layer "F.SilkS")
		)
		(fp_line
			(start -2.7432 1.4224)
			(end 2.1336 1.4224)
			(stroke
				(width 0.1524)
				(type default)
			)
			(layer "F.SilkS")
		)
		(fp_line
			(start 2.1336 1.4224)
			(end 2.1336 -1.4224)
			(stroke
				(width 0.1524)
				(type default)
			)
			(layer "F.SilkS")
		)
		(fp_line
			(start -2.2352 0)
			(end -2.7432 0.508)
			(stroke
				(width 0.1524)
				(type default)
			)
			(layer "F.SilkS")
		)
		(fp_line
			(start -2.7432 -0.508)
			(end -2.2352 0)
			(stroke
				(width 0.1524)
				(type default)
			)
			(layer "F.SilkS")
		)
		(fp_line
			(start -2.7432 -1.4224)
			(end -2.7432 1.4224)
			(stroke
				(width 0.1524)
				(type default)
			)
			(layer "F.SilkS")
		)
		(fp_line
			(start 2.1336 -1.4224)
			(end -2.7432 -1.4224)
			(stroke
				(width 0.1524)
				(type default)
			)
			(layer "F.SilkS")
		)
		(fp_poly
			(pts
				(xy 2.2098 -1.4224) (xy 2.2098 1.4224) (xy -2.2225 1.4224) (xy -2.2225 -1.4224)
			)
			(stroke
				(width 0)
				(type default)
			)
			(fill yes)
			(layer "F.SilkS")
		)
		(fp_rect
			(start -2.4511 2.9972)
			(end 2.4511 -2.9972)
			(stroke
				(width 0)
				(type default)
			)
			(fill no)
			(layer "F.CrtYd")
		)
		(fp_poly
			(pts
				(xy -2.8194 3.6322) (xy -2.8194 -3.6322) (xy 2.8194 -3.6322) (xy 2.8194 -2.2987) (xy 2.4511 -2.2987)
				(xy 2.4511 -2.9972) (xy -2.4511 -2.9972) (xy -2.4511 2.9972) (xy 2.4511 2.9972) (xy 2.4511 -2.286)
				(xy 2.8194 -2.286) (xy 2.8194 3.6322)
			)
			(stroke
				(width 0)
				(type default)
			)
			(fill no)
			(layer "F.CrtYd")
		)
		(fp_rect
			(start -2.8194 3.6322)
			(end 2.8194 -3.6322)
			(stroke
				(width 0)
				(type default)
			)
			(fill no)
			(layer "F.Fab")
		)
		(pad "1" smd rect
			(at -1.905 2.54 270)
			(size 0.635 1.651)
			(layers "F.Cu" "F.Mask" "F.Paste")
			(net "P12V")
		)
		(pad "2" smd rect
			(at -0.635 2.54 270)
			(size 0.635 1.651)
			(layers "F.Cu" "F.Mask" "F.Paste")
			(net "P12V")
		)
		(pad "3" smd rect
			(at 0.635 2.54 270)
			(size 0.635 1.651)
			(layers "F.Cu" "F.Mask" "F.Paste")
			(net "P12V")
		)
		(pad "4" smd rect
			(at 1.905 2.54 270)
			(size 0.635 1.651)
			(layers "F.Cu" "F.Mask" "F.Paste")
			(net "SW_HDD1_N")
		)
		(pad "5" smd rect
			(at 1.905 -2.54 270)
			(size 0.635 1.651)
			(layers "F.Cu" "F.Mask" "F.Paste")
			(net "P12V_HDD1")
		)
		(pad "6" smd rect
			(at 0.635 -2.54 270)
			(size 0.635 1.651)
			(layers "F.Cu" "F.Mask" "F.Paste")
			(net "P12V_HDD1")
		)
		(pad "7" smd rect
			(at -0.635 -2.54 270)
			(size 0.635 1.651)
			(layers "F.Cu" "F.Mask" "F.Paste")
			(net "P12V_HDD1")
		)
		(pad "8" smd rect
			(at -1.905 -2.54 270)
			(size 0.635 1.651)
			(layers "F.Cu" "F.Mask" "F.Paste")
			(net "P12V_HDD1")
		)
	)
	(footprint ""
		(layer "F.Cu")
		(at 41.147746 -233.073702 180)
		(property "Reference" "C303"
			(at 0 0 180)
			(layer "F.SilkS")
			(hide yes)
			(effects
				(font
					(size 1.27 1.27)
				)
			)
		)
		(property "Value" "SCD01U50V2KX-1GP"
			(at 1.1811 -2.7051 180)
			(unlocked yes)
			(layer "F.Fab")
			(hide yes)
			(effects
				(font
					(size 1.016 1.016)
					(thickness 0.1524)
				)
			)
		)
		(property "Device Type" "C402H22"
			(at 1.1811 -4.2291 180)
			(unlocked yes)
			(layer "F.Fab")
			(hide yes)
			(effects
				(font
					(size 1.016 1.016)
					(thickness 0.1524)
				)
			)
		)
		(duplicate_pad_numbers_are_jumpers no)
		(fp_rect
			(start -0.4318 0.9525)
			(end 0.4318 -0.9525)
			(stroke
				(width 0)
				(type default)
			)
			(fill no)
			(layer "F.CrtYd")
		)
		(fp_rect
			(start -0.4318 0.9525)
			(end 0.4318 -0.9525)
			(stroke
				(width 0)
				(type default)
			)
			(fill no)
			(layer "F.Fab")
		)
		(pad "1" smd custom
			(at 0 -0.4445 180)
			(size 0.1524 0.1524)
			(layers "F.Cu" "F.Mask" "F.Paste")
			(net "HDD_PRSNT_NET12")
			(options
				(clearance outline)
				(anchor circle)
			)
			(primitives
				(gr_poly
					(pts
						(arc
							(start 0.3048 -0.2032)
							(mid 0.275042 -0.275042)
							(end 0.2032 -0.3048)
						)
						(arc
							(start -0.2032 -0.3048)
							(mid -0.275042 -0.275042)
							(end -0.3048 -0.2032)
						)
						(arc
							(start -0.3048 0.2032)
							(mid -0.275042 0.275042)
							(end -0.2032 0.3048)
						)
						(arc
							(start 0.2032 0.3048)
							(mid 0.275042 0.275042)
							(end 0.3048 0.2032)
						)
					)
					(width 0)
					(fill yes)
				)
			)
		)
		(pad "2" smd custom
			(at 0 0.4445 180)
			(size 0.1524 0.1524)
			(layers "F.Cu" "F.Mask" "F.Paste")
			(net "GND")
			(options
				(clearance outline)
				(anchor circle)
			)
			(primitives
				(gr_poly
					(pts
						(arc
							(start 0.3048 -0.2032)
							(mid 0.275042 -0.275042)
							(end 0.2032 -0.3048)
						)
						(arc
							(start -0.2032 -0.3048)
							(mid -0.275042 -0.275042)
							(end -0.3048 -0.2032)
						)
						(arc
							(start -0.3048 0.2032)
							(mid -0.275042 0.275042)
							(end -0.2032 0.3048)
						)
						(arc
							(start 0.2032 0.3048)
							(mid 0.275042 0.275042)
							(end 0.3048 0.2032)
						)
					)
					(width 0)
					(fill yes)
				)
			)
		)
	)
	(footprint ""
		(layer "F.Cu")
		(at 55.578756 -488.470702 180)
		(property "Reference" "C188"
			(at 0 0 180)
			(layer "F.SilkS")
			(hide yes)
			(effects
				(font
					(size 1.27 1.27)
				)
			)
		)
		(property "Value" "SC1U16V3KX-5GP"
			(at 0 -2.8194 180)
			(unlocked yes)
			(layer "F.Fab")
			(hide yes)
			(effects
				(font
					(size 1.016 1.016)
					(thickness 0.1524)
				)
			)
		)
		(property "Device Type" "C603H36"
			(at 0 -4.3434 180)
			(unlocked yes)
			(layer "F.Fab")
			(hide yes)
			(effects
				(font
					(size 1.016 1.016)
					(thickness 0.1524)
				)
			)
		)
		(duplicate_pad_numbers_are_jumpers no)
		(fp_line
			(start 0.508 0)
			(end -0.508 0)
			(stroke
				(width 0.2032)
				(type default)
			)
			(layer "F.SilkS")
		)
		(fp_rect
			(start -0.5842 1.3335)
			(end 0.5842 -1.3335)
			(stroke
				(width 0)
				(type default)
			)
			(fill no)
			(layer "F.CrtYd")
		)
		(fp_rect
			(start -0.5842 1.3335)
			(end 0.5842 -1.3335)
			(stroke
				(width 0)
				(type default)
			)
			(fill no)
			(layer "F.Fab")
		)
		(pad "1" smd custom
			(at 0 -0.762 180)
			(size 0.2159 0.2159)
			(layers "F.Cu" "F.Mask" "F.Paste")
			(net "P5V_HDD5")
			(options
				(clearance outline)
				(anchor circle)
			)
			(primitives
				(gr_poly
					(pts
						(arc
							(start -0.3302 -0.4318)
							(mid -0.402042 -0.402042)
							(end -0.4318 -0.3302)
						)
						(arc
							(start -0.4318 0.3302)
							(mid -0.402042 0.402042)
							(end -0.3302 0.4318)
						)
						(arc
							(start 0.3302 0.4318)
							(mid 0.402042 0.402042)
							(end 0.4318 0.3302)
						)
						(arc
							(start 0.4318 -0.3302)
							(mid 0.402042 -0.402042)
							(end 0.3302 -0.4318)
						)
					)
					(width 0)
					(fill yes)
				)
			)
		)
		(pad "2" smd custom
			(at 0 0.762 180)
			(size 0.2159 0.2159)
			(layers "F.Cu" "F.Mask" "F.Paste")
			(net "GND")
			(options
				(clearance outline)
				(anchor circle)
			)
			(primitives
				(gr_poly
					(pts
						(arc
							(start -0.3302 -0.4318)
							(mid -0.402042 -0.402042)
							(end -0.4318 -0.3302)
						)
						(arc
							(start -0.4318 0.3302)
							(mid -0.402042 0.402042)
							(end -0.3302 0.4318)
						)
						(arc
							(start 0.3302 0.4318)
							(mid 0.402042 0.402042)
							(end 0.4318 0.3302)
						)
						(arc
							(start 0.4318 -0.3302)
							(mid 0.402042 -0.402042)
							(end 0.3302 -0.4318)
						)
					)
					(width 0)
					(fill yes)
				)
			)
		)
	)
	(footprint ""
		(layer "F.Cu")
		(at 68.999608 -67.999864)
		(property "Reference" "H9"
			(at 0 0 0)
			(layer "F.SilkS")
			(hide yes)
			(effects
				(font
					(size 1.27 1.27)
				)
			)
		)
		(property "Value" "HOLE315R140"
			(at 0 -7.5692 0)
			(unlocked yes)
			(layer "F.Fab")
			(hide yes)
			(effects
				(font
					(size 1.016 1.016)
					(thickness 0.1524)
				)
			)
		)
		(property "Device Type" "HOLE315R140"
			(at 0 -9.0932 0)
			(unlocked yes)
			(layer "F.Fab")
			(hide yes)
			(effects
				(font
					(size 1.016 1.016)
					(thickness 0.1524)
				)
			)
		)
		(duplicate_pad_numbers_are_jumpers no)
		(fp_poly
			(pts
				(arc
					(start 4.3053 0)
					(mid -4.3053 0)
					(end 4.3053 0)
				)
			)
			(stroke
				(width 0)
				(type default)
			)
			(fill no)
			(layer "F.CrtYd")
		)
		(fp_poly
			(pts
				(arc
					(start 4.3053 0)
					(mid -4.3053 0)
					(end 4.3053 0)
				)
			)
			(stroke
				(width 0)
				(type default)
			)
			(fill no)
			(layer "F.Fab")
		)
		(pad "1" thru_hole circle
			(at 0.00127 0.00127)
			(size 8.001 8.001)
			(drill 3.556)
			(layers "*.Cu" "*.Mask")
			(remove_unused_layers no)
			(net "GND")
			(clearance -1.7145)
			(thermal_gap 0.3048)
			(padstack
				(mode front_inner_back)
				(layer "Inner"
					(shape circle)
					(size 3.9624 3.9624)
					(clearance 0.3048)
				)
				(layer "B.Cu"
					(shape circle)
					(size 8.001 8.001)
					(clearance -1.7145)
				)
			)
		)
	)
	(footprint ""
		(layer "F.Cu")
		(at 234.568746 -11.3157)
		(property "Reference" "PL1"
			(at 0 0 0)
			(layer "F.SilkS")
			(hide yes)
			(effects
				(font
					(size 1.27 1.27)
				)
			)
		)
		(property "Value" "BLM41PG600-GP"
			(at -3.690874 -7.441184 0)
			(unlocked yes)
			(layer "F.Fab")
			(hide yes)
			(effects
				(font
					(size 1.016 1.016)
					(thickness 0.1524)
				)
			)
		)
		(property "Device Type" "L451616H71"
			(at -3.690874 -5.917184 0)
			(unlocked yes)
			(layer "F.Fab")
			(hide yes)
			(effects
				(font
					(size 1.016 1.016)
					(thickness 0.1524)
				)
			)
		)
		(duplicate_pad_numbers_are_jumpers no)
		(fp_line
			(start -2.8702 -1.2954)
			(end -2.8702 1.2954)
			(stroke
				(width 0.1524)
				(type default)
			)
			(layer "F.SilkS")
		)
		(fp_line
			(start -2.8702 -1.2954)
			(end -2.8702 1.2954)
			(stroke
				(width 0.1524)
				(type default)
			)
			(layer "F.SilkS")
		)
		(fp_line
			(start -2.8702 1.2954)
			(end 2.8702 1.2954)
			(stroke
				(width 0.1524)
				(type default)
			)
			(layer "F.SilkS")
		)
		(fp_line
			(start -2.8702 1.2954)
			(end 2.8702 1.2954)
			(stroke
				(width 0.1524)
				(type default)
			)
			(layer "F.SilkS")
		)
		(fp_line
			(start 2.8702 -1.2954)
			(end -2.8702 -1.2954)
			(stroke
				(width 0.1524)
				(type default)
			)
			(layer "F.SilkS")
		)
		(fp_line
			(start 2.8702 -1.2954)
			(end -2.8702 -1.2954)
			(stroke
				(width 0.1524)
				(type default)
			)
			(layer "F.SilkS")
		)
		(fp_line
			(start 2.8702 1.2954)
			(end 2.8702 -1.2954)
			(stroke
				(width 0.1524)
				(type default)
			)
			(layer "F.SilkS")
		)
		(fp_line
			(start 2.8702 1.2954)
			(end 2.8702 -1.2954)
			(stroke
				(width 0.1524)
				(type default)
			)
			(layer "F.SilkS")
		)
		(fp_poly
			(pts
				(xy -2.8702 1.2954) (xy 2.8702 1.2954) (xy 2.8702 -1.2954) (xy -2.8702 -1.2954)
			)
			(stroke
				(width 0)
				(type default)
			)
			(fill no)
			(layer "F.CrtYd")
		)
		(fp_poly
			(pts
				(xy -2.8702 1.2954) (xy 2.8702 1.2954) (xy 2.8702 -1.2954) (xy -2.8702 -1.2954)
			)
			(stroke
				(width 0)
				(type default)
			)
			(fill no)
			(layer "F.Fab")
		)
		(pad "1" smd rect
			(at -1.9685 0)
			(size 1.3716 1.8796)
			(layers "F.Cu" "F.Mask" "F.Paste")
			(net "P12V")
		)
		(pad "2" smd rect
			(at 1.9685 0)
			(size 1.3716 1.8796)
			(layers "F.Cu" "F.Mask" "F.Paste")
			(net "P5VA_12VIN")
		)
	)
	(footprint ""
		(layer "F.Cu")
		(at 26.14803 -132.711952 90)
		(property "Reference" "C313"
			(at 0 0 90)
			(layer "F.SilkS")
			(hide yes)
			(effects
				(font
					(size 1.27 1.27)
				)
			)
		)
		(property "Value" "SCD01U50V2KX-1GP"
			(at 1.1811 -2.7051 90)
			(unlocked yes)
			(layer "F.Fab")
			(hide yes)
			(effects
				(font
					(size 1.016 1.016)
					(thickness 0.1524)
				)
			)
		)
		(property "Device Type" "C402H22"
			(at 1.1811 -4.2291 90)
			(unlocked yes)
			(layer "F.Fab")
			(hide yes)
			(effects
				(font
					(size 1.016 1.016)
					(thickness 0.1524)
				)
			)
		)
		(duplicate_pad_numbers_are_jumpers no)
		(fp_rect
			(start -0.4318 0.9525)
			(end 0.4318 -0.9525)
			(stroke
				(width 0)
				(type default)
			)
			(fill no)
			(layer "F.CrtYd")
		)
		(fp_rect
			(start -0.4318 0.9525)
			(end 0.4318 -0.9525)
			(stroke
				(width 0)
				(type default)
			)
			(fill no)
			(layer "F.Fab")
		)
		(pad "1" smd custom
			(at 0 -0.4445 90)
			(size 0.1524 0.1524)
			(layers "F.Cu" "F.Mask" "F.Paste")
			(net "SAS2X28_DRIVE_RX_P_B13")
			(options
				(clearance outline)
				(anchor circle)
			)
			(primitives
				(gr_poly
					(pts
						(arc
							(start 0.3048 -0.2032)
							(mid 0.275042 -0.275042)
							(end 0.2032 -0.3048)
						)
						(arc
							(start -0.2032 -0.3048)
							(mid -0.275042 -0.275042)
							(end -0.3048 -0.2032)
						)
						(arc
							(start -0.3048 0.2032)
							(mid -0.275042 0.275042)
							(end -0.2032 0.3048)
						)
						(arc
							(start 0.2032 0.3048)
							(mid 0.275042 0.275042)
							(end 0.3048 0.2032)
						)
					)
					(width 0)
					(fill yes)
				)
			)
		)
		(pad "2" smd custom
			(at 0 0.4445 90)
			(size 0.1524 0.1524)
			(layers "F.Cu" "F.Mask" "F.Paste")
			(net "SAS2X28_B_HDD13_RX_+")
			(options
				(clearance outline)
				(anchor circle)
			)
			(primitives
				(gr_poly
					(pts
						(arc
							(start 0.3048 -0.2032)
							(mid 0.275042 -0.275042)
							(end 0.2032 -0.3048)
						)
						(arc
							(start -0.2032 -0.3048)
							(mid -0.275042 -0.275042)
							(end -0.3048 -0.2032)
						)
						(arc
							(start -0.3048 0.2032)
							(mid -0.275042 0.275042)
							(end -0.2032 0.3048)
						)
						(arc
							(start 0.2032 0.3048)
							(mid 0.275042 0.275042)
							(end 0.3048 0.2032)
						)
					)
					(width 0)
					(fill yes)
				)
			)
		)
	)
	(footprint ""
		(layer "F.Cu")
		(at 76.453746 -15.522702)
		(property "Reference" "C331"
			(at 0 0 0)
			(layer "F.SilkS")
			(hide yes)
			(effects
				(font
					(size 1.27 1.27)
				)
			)
		)
		(property "Value" "SC10U16V6KX-2GP"
			(at -0.0762 -5.1308 0)
			(unlocked yes)
			(layer "F.Fab")
			(hide yes)
			(effects
				(font
					(size 1.016 1.016)
					(thickness 0.1524)
				)
			)
		)
		(property "Device Type" "C1206H71"
			(at -0.127 -6.6548 0)
			(unlocked yes)
			(layer "F.Fab")
			(hide yes)
			(effects
				(font
					(size 1.016 1.016)
					(thickness 0.1524)
				)
			)
		)
		(duplicate_pad_numbers_are_jumpers no)
		(fp_line
			(start -1.016 -2.2352)
			(end 1.016 -2.2352)
			(stroke
				(width 0.1524)
				(type default)
			)
			(layer "F.SilkS")
		)
		(fp_line
			(start -1.016 -0.8382)
			(end -1.016 -2.2352)
			(stroke
				(width 0.1524)
				(type default)
			)
			(layer "F.SilkS")
		)
		(fp_line
			(start -1.016 2.2352)
			(end -1.016 0.8382)
			(stroke
				(width 0.1524)
				(type default)
			)
			(layer "F.SilkS")
		)
		(fp_line
			(start 1.016 -2.2352)
			(end 1.016 -0.8382)
			(stroke
				(width 0.1524)
				(type default)
			)
			(layer "F.SilkS")
		)
		(fp_line
			(start 1.016 0.8382)
			(end 1.016 2.2352)
			(stroke
				(width 0.1524)
				(type default)
			)
			(layer "F.SilkS")
		)
		(fp_line
			(start 1.016 2.2352)
			(end -1.016 2.2352)
			(stroke
				(width 0.1524)
				(type default)
			)
			(layer "F.SilkS")
		)
		(fp_rect
			(start -1.0922 2.3114)
			(end 1.0922 -2.3114)
			(stroke
				(width 0)
				(type default)
			)
			(fill no)
			(layer "F.CrtYd")
		)
		(fp_poly
			(pts
				(xy 1.0922 -2.3114) (xy 1.0922 2.3114) (xy -1.0922 2.3114) (xy -1.0922 -2.3114)
			)
			(stroke
				(width 0)
				(type default)
			)
			(fill no)
			(layer "F.Fab")
		)
		(pad "1" smd rect
			(at 0 -1.397)
			(size 1.651 1.27)
			(layers "F.Cu" "F.Mask" "F.Paste")
			(net "P5V_HDD14")
		)
		(pad "2" smd rect
			(at 0 1.397)
			(size 1.651 1.27)
			(layers "F.Cu" "F.Mask" "F.Paste")
			(net "GND")
		)
	)
	(footprint ""
		(layer "F.Cu")
		(at 19.176746 -469.6587 -90)
		(property "Reference" "R244"
			(at 0 0 270)
			(layer "F.SilkS")
			(hide yes)
			(effects
				(font
					(size 1.27 1.27)
				)
			)
		)
		(property "Value" "0R2J-2-GP"
			(at 0.064008 -3.993896 270)
			(unlocked yes)
			(layer "F.Fab")
			(hide yes)
			(effects
				(font
					(size 1.016 1.016)
					(thickness 0.1524)
				)
			)
		)
		(property "Device Type" "R402H16"
			(at 0.064008 -5.517896 270)
			(unlocked yes)
			(layer "F.Fab")
			(hide yes)
			(effects
				(font
					(size 1.016 1.016)
					(thickness 0.1524)
				)
			)
		)
		(duplicate_pad_numbers_are_jumpers no)
		(fp_line
			(start -0.508 -0.9398)
			(end -0.508 0.9398)
			(stroke
				(width 0.1524)
				(type default)
			)
			(layer "F.SilkS")
		)
		(fp_line
			(start 0.508 -0.9398)
			(end -0.508 -0.9398)
			(stroke
				(width 0.1524)
				(type default)
			)
			(layer "F.SilkS")
		)
		(fp_rect
			(start -0.508 0.9398)
			(end 0.508 -0.9398)
			(stroke
				(width 0)
				(type default)
			)
			(fill no)
			(layer "F.CrtYd")
		)
		(fp_rect
			(start -0.508 0.9398)
			(end 0.508 -0.9398)
			(stroke
				(width 0)
				(type default)
			)
			(fill no)
			(layer "F.Fab")
		)
		(pad "1" smd custom
			(at 0 -0.4445 270)
			(size 0.1397 0.1397)
			(layers "F.Cu" "F.Mask" "F.Paste")
			(net "FLT_NET_HDD10")
			(options
				(clearance outline)
				(anchor circle)
			)
			(primitives
				(gr_poly
					(pts
						(arc
							(start -0.1778 -0.2794)
							(mid -0.249642 -0.249642)
							(end -0.2794 -0.1778)
						)
						(arc
							(start -0.2794 0.1778)
							(mid -0.249642 0.249642)
							(end -0.1778 0.2794)
						)
						(arc
							(start 0.1778 0.2794)
							(mid 0.249642 0.249642)
							(end 0.2794 0.1778)
						)
						(arc
							(start 0.2794 -0.1778)
							(mid 0.249642 -0.249642)
							(end 0.1778 -0.2794)
						)
					)
					(width 0)
					(fill yes)
				)
			)
		)
		(pad "2" smd custom
			(at 0 0.4445 270)
			(size 0.1397 0.1397)
			(layers "F.Cu" "F.Mask" "F.Paste")
			(net "FLT_HDD10_DRIVE")
			(options
				(clearance outline)
				(anchor circle)
			)
			(primitives
				(gr_poly
					(pts
						(arc
							(start -0.1778 -0.2794)
							(mid -0.249642 -0.249642)
							(end -0.2794 -0.1778)
						)
						(arc
							(start -0.2794 0.1778)
							(mid -0.249642 0.249642)
							(end -0.1778 0.2794)
						)
						(arc
							(start 0.1778 0.2794)
							(mid 0.249642 0.249642)
							(end 0.2794 0.1778)
						)
						(arc
							(start 0.2794 -0.1778)
							(mid 0.249642 -0.249642)
							(end 0.1778 -0.2794)
						)
					)
					(width 0)
					(fill yes)
				)
			)
		)
	)
	(footprint ""
		(layer "F.Cu")
		(at 191.092582 -287.373568 -90)
		(property "Reference" "R141"
			(at 0 0 270)
			(layer "F.SilkS")
			(hide yes)
			(effects
				(font
					(size 1.27 1.27)
				)
			)
		)
		(property "Value" "0R2J-2-GP"
			(at 0.064008 -3.993896 270)
			(unlocked yes)
			(layer "F.Fab")
			(hide yes)
			(effects
				(font
					(size 1.016 1.016)
					(thickness 0.1524)
				)
			)
		)
		(property "Device Type" "R402H16"
			(at 0.064008 -5.517896 270)
			(unlocked yes)
			(layer "F.Fab")
			(hide yes)
			(effects
				(font
					(size 1.016 1.016)
					(thickness 0.1524)
				)
			)
		)
		(duplicate_pad_numbers_are_jumpers no)
		(fp_line
			(start -0.508 -0.9398)
			(end -0.508 0.9398)
			(stroke
				(width 0.1524)
				(type default)
			)
			(layer "F.SilkS")
		)
		(fp_line
			(start 0.508 -0.9398)
			(end -0.508 -0.9398)
			(stroke
				(width 0.1524)
				(type default)
			)
			(layer "F.SilkS")
		)
		(fp_rect
			(start -0.508 0.9398)
			(end 0.508 -0.9398)
			(stroke
				(width 0)
				(type default)
			)
			(fill no)
			(layer "F.CrtYd")
		)
		(fp_rect
			(start -0.508 0.9398)
			(end 0.508 -0.9398)
			(stroke
				(width 0)
				(type default)
			)
			(fill no)
			(layer "F.Fab")
		)
		(pad "1" smd custom
			(at 0 -0.4445 270)
			(size 0.1397 0.1397)
			(layers "F.Cu" "F.Mask" "F.Paste")
			(net "DRIVE_PWR2")
			(options
				(clearance outline)
				(anchor circle)
			)
			(primitives
				(gr_poly
					(pts
						(arc
							(start -0.1778 -0.2794)
							(mid -0.249642 -0.249642)
							(end -0.2794 -0.1778)
						)
						(arc
							(start -0.2794 0.1778)
							(mid -0.249642 0.249642)
							(end -0.1778 0.2794)
						)
						(arc
							(start 0.1778 0.2794)
							(mid 0.249642 0.249642)
							(end 0.2794 0.1778)
						)
						(arc
							(start 0.2794 -0.1778)
							(mid 0.249642 -0.249642)
							(end 0.1778 -0.2794)
						)
					)
					(width 0)
					(fill yes)
				)
			)
		)
		(pad "2" smd custom
			(at 0 0.4445 270)
			(size 0.1397 0.1397)
			(layers "F.Cu" "F.Mask" "F.Paste")
			(net "SW_PWR_HDD2")
			(options
				(clearance outline)
				(anchor circle)
			)
			(primitives
				(gr_poly
					(pts
						(arc
							(start -0.1778 -0.2794)
							(mid -0.249642 -0.249642)
							(end -0.2794 -0.1778)
						)
						(arc
							(start -0.2794 0.1778)
							(mid -0.249642 0.249642)
							(end -0.1778 0.2794)
						)
						(arc
							(start 0.1778 0.2794)
							(mid 0.249642 0.249642)
							(end 0.2794 0.1778)
						)
						(arc
							(start 0.2794 -0.1778)
							(mid 0.249642 -0.249642)
							(end 0.1778 -0.2794)
						)
					)
					(width 0)
					(fill yes)
				)
			)
		)
	)
	(footprint ""
		(layer "F.Cu")
		(at 39.743634 -452.858886 90)
		(property "Reference" "R173"
			(at 0 0 90)
			(layer "F.SilkS")
			(hide yes)
			(effects
				(font
					(size 1.27 1.27)
				)
			)
		)
		(property "Value" "330R2F-GP"
			(at 0.064008 -3.993896 90)
			(unlocked yes)
			(layer "F.Fab")
			(hide yes)
			(effects
				(font
					(size 1.016 1.016)
					(thickness 0.1524)
				)
			)
		)
		(property "Device Type" "R402H16"
			(at 0.064008 -5.517896 90)
			(unlocked yes)
			(layer "F.Fab")
			(hide yes)
			(effects
				(font
					(size 1.016 1.016)
					(thickness 0.1524)
				)
			)
		)
		(duplicate_pad_numbers_are_jumpers no)
		(fp_line
			(start 0.508 -0.9398)
			(end -0.508 -0.9398)
			(stroke
				(width 0.1524)
				(type default)
			)
			(layer "F.SilkS")
		)
		(fp_line
			(start -0.508 -0.9398)
			(end -0.508 0.9398)
			(stroke
				(width 0.1524)
				(type default)
			)
			(layer "F.SilkS")
		)
		(fp_rect
			(start -0.508 0.9398)
			(end 0.508 -0.9398)
			(stroke
				(width 0)
				(type default)
			)
			(fill no)
			(layer "F.CrtYd")
		)
		(fp_rect
			(start -0.508 0.9398)
			(end 0.508 -0.9398)
			(stroke
				(width 0)
				(type default)
			)
			(fill no)
			(layer "F.Fab")
		)
		(pad "1" smd custom
			(at 0 -0.4445 90)
			(size 0.1397 0.1397)
			(layers "F.Cu" "F.Mask" "F.Paste")
			(net "P3V3_HDD5_LED")
			(options
				(clearance outline)
				(anchor circle)
			)
			(primitives
				(gr_poly
					(pts
						(arc
							(start -0.1778 -0.2794)
							(mid -0.249642 -0.249642)
							(end -0.2794 -0.1778)
						)
						(arc
							(start -0.2794 0.1778)
							(mid -0.249642 0.249642)
							(end -0.1778 0.2794)
						)
						(arc
							(start 0.1778 0.2794)
							(mid 0.249642 0.249642)
							(end 0.2794 0.1778)
						)
						(arc
							(start 0.2794 -0.1778)
							(mid 0.249642 -0.249642)
							(end 0.1778 -0.2794)
						)
					)
					(width 0)
					(fill yes)
				)
			)
		)
		(pad "2" smd custom
			(at 0 0.4445 90)
			(size 0.1397 0.1397)
			(layers "F.Cu" "F.Mask" "F.Paste")
			(net "FLT_HDD5")
			(options
				(clearance outline)
				(anchor circle)
			)
			(primitives
				(gr_poly
					(pts
						(arc
							(start -0.1778 -0.2794)
							(mid -0.249642 -0.249642)
							(end -0.2794 -0.1778)
						)
						(arc
							(start -0.2794 0.1778)
							(mid -0.249642 0.249642)
							(end -0.1778 0.2794)
						)
						(arc
							(start 0.1778 0.2794)
							(mid 0.249642 0.249642)
							(end 0.2794 0.1778)
						)
						(arc
							(start 0.2794 -0.1778)
							(mid 0.249642 -0.249642)
							(end 0.1778 -0.2794)
						)
					)
					(width 0)
					(fill yes)
				)
			)
		)
	)
	(footprint ""
		(layer "F.Cu")
		(at 215.979756 -488.597702 180)
		(property "Reference" "C107"
			(at 0 0 180)
			(layer "F.SilkS")
			(hide yes)
			(effects
				(font
					(size 1.27 1.27)
				)
			)
		)
		(property "Value" "SC10U16V6KX-2GP"
			(at -0.0762 -5.1308 180)
			(unlocked yes)
			(layer "F.Fab")
			(hide yes)
			(effects
				(font
					(size 1.016 1.016)
					(thickness 0.1524)
				)
			)
		)
		(property "Device Type" "C1206H71"
			(at -0.127 -6.6548 180)
			(unlocked yes)
			(layer "F.Fab")
			(hide yes)
			(effects
				(font
					(size 1.016 1.016)
					(thickness 0.1524)
				)
			)
		)
		(duplicate_pad_numbers_are_jumpers no)
		(fp_line
			(start 1.016 2.2352)
			(end -1.016 2.2352)
			(stroke
				(width 0.1524)
				(type default)
			)
			(layer "F.SilkS")
		)
		(fp_line
			(start 1.016 0.8382)
			(end 1.016 2.2352)
			(stroke
				(width 0.1524)
				(type default)
			)
			(layer "F.SilkS")
		)
		(fp_line
			(start 1.016 -2.2352)
			(end 1.016 -0.8382)
			(stroke
				(width 0.1524)
				(type default)
			)
			(layer "F.SilkS")
		)
		(fp_line
			(start -1.016 2.2352)
			(end -1.016 0.8382)
			(stroke
				(width 0.1524)
				(type default)
			)
			(layer "F.SilkS")
		)
		(fp_line
			(start -1.016 -0.8382)
			(end -1.016 -2.2352)
			(stroke
				(width 0.1524)
				(type default)
			)
			(layer "F.SilkS")
		)
		(fp_line
			(start -1.016 -2.2352)
			(end 1.016 -2.2352)
			(stroke
				(width 0.1524)
				(type default)
			)
			(layer "F.SilkS")
		)
		(fp_rect
			(start -1.0922 2.3114)
			(end 1.0922 -2.3114)
			(stroke
				(width 0)
				(type default)
			)
			(fill no)
			(layer "F.CrtYd")
		)
		(fp_poly
			(pts
				(xy 1.0922 -2.3114) (xy 1.0922 2.3114) (xy -1.0922 2.3114) (xy -1.0922 -2.3114)
			)
			(stroke
				(width 0)
				(type default)
			)
			(fill no)
			(layer "F.Fab")
		)
		(pad "1" smd rect
			(at 0 -1.397 180)
			(size 1.651 1.27)
			(layers "F.Cu" "F.Mask" "F.Paste")
			(net "P5V_HDD0")
		)
		(pad "2" smd rect
			(at 0 1.397 180)
			(size 1.651 1.27)
			(layers "F.Cu" "F.Mask" "F.Paste")
			(net "GND")
		)
	)
	(footprint ""
		(layer "F.Cu")
		(at 44.068746 -221.770702 90)
		(property "Reference" "R276"
			(at 0 0 90)
			(layer "F.SilkS")
			(hide yes)
			(effects
				(font
					(size 1.27 1.27)
				)
			)
		)
		(property "Value" "2R2010J-1-GP"
			(at 0.254 -8.0772 90)
			(unlocked yes)
			(layer "F.Fab")
			(hide yes)
			(effects
				(font
					(size 1.016 1.016)
					(thickness 0.1524)
				)
			)
		)
		(property "Device Type" "R2010H28"
			(at 0.254 -9.6774 90)
			(unlocked yes)
			(layer "F.Fab")
			(hide yes)
			(effects
				(font
					(size 1.016 1.016)
					(thickness 0.1524)
				)
			)
		)
		(duplicate_pad_numbers_are_jumpers no)
		(fp_line
			(start 1.651 -3.302)
			(end -1.651 -3.302)
			(stroke
				(width 0.1524)
				(type default)
			)
			(layer "F.SilkS")
		)
		(fp_line
			(start -1.651 -3.302)
			(end -1.651 3.302)
			(stroke
				(width 0.1524)
				(type default)
			)
			(layer "F.SilkS")
		)
		(fp_line
			(start 1.651 3.302)
			(end 1.651 -3.302)
			(stroke
				(width 0.1524)
				(type default)
			)
			(layer "F.SilkS")
		)
		(fp_line
			(start -1.651 3.302)
			(end 1.651 3.302)
			(stroke
				(width 0.1524)
				(type default)
			)
			(layer "F.SilkS")
		)
		(fp_rect
			(start -1.7272 -3.3782)
			(end 1.7272 3.3782)
			(stroke
				(width 0)
				(type default)
			)
			(fill no)
			(layer "F.CrtYd")
		)
		(fp_poly
			(pts
				(xy 1.7272 3.3782) (xy 1.7272 -3.3782) (xy -1.7272 -3.3782) (xy -1.7272 3.3782)
			)
			(stroke
				(width 0)
				(type default)
			)
			(fill no)
			(layer "F.Fab")
		)
		(pad "1" smd rect
			(at 0 -2.3495 90)
			(size 2.794 1.143)
			(layers "F.Cu" "F.Mask" "F.Paste")
			(net "12V_PRE_12")
		)
		(pad "2" smd rect
			(at 0 2.3495 90)
			(size 2.794 1.143)
			(layers "F.Cu" "F.Mask" "F.Paste")
			(net "P12V_HDD12")
		)
	)
	(footprint ""
		(layer "F.Cu")
		(at 70.738746 -396.5067)
		(property "Reference" "R446"
			(at 0 0 0)
			(layer "F.SilkS")
			(hide yes)
			(effects
				(font
					(size 1.27 1.27)
				)
			)
		)
		(property "Value" "4K7R2J-2-GP"
			(at 0.064008 -3.993896 0)
			(unlocked yes)
			(layer "F.Fab")
			(hide yes)
			(effects
				(font
					(size 1.016 1.016)
					(thickness 0.1524)
				)
			)
		)
		(property "Device Type" "R402H16"
			(at 0.064008 -5.517896 0)
			(unlocked yes)
			(layer "F.Fab")
			(hide yes)
			(effects
				(font
					(size 1.016 1.016)
					(thickness 0.1524)
				)
			)
		)
		(duplicate_pad_numbers_are_jumpers no)
		(fp_line
			(start -0.508 -0.9398)
			(end -0.508 0.9398)
			(stroke
				(width 0.1524)
				(type default)
			)
			(layer "F.SilkS")
		)
		(fp_line
			(start 0.508 -0.9398)
			(end -0.508 -0.9398)
			(stroke
				(width 0.1524)
				(type default)
			)
			(layer "F.SilkS")
		)
		(fp_rect
			(start -0.508 0.9398)
			(end 0.508 -0.9398)
			(stroke
				(width 0)
				(type default)
			)
			(fill no)
			(layer "F.CrtYd")
		)
		(fp_rect
			(start -0.508 0.9398)
			(end 0.508 -0.9398)
			(stroke
				(width 0)
				(type default)
			)
			(fill no)
			(layer "F.Fab")
		)
		(pad "1" smd custom
			(at 0 -0.4445)
			(size 0.1397 0.1397)
			(layers "F.Cu" "F.Mask" "F.Paste")
			(net "P3V3")
			(options
				(clearance outline)
				(anchor circle)
			)
			(primitives
				(gr_poly
					(pts
						(arc
							(start -0.1778 -0.2794)
							(mid -0.249642 -0.249642)
							(end -0.2794 -0.1778)
						)
						(arc
							(start -0.2794 0.1778)
							(mid -0.249642 0.249642)
							(end -0.1778 0.2794)
						)
						(arc
							(start 0.1778 0.2794)
							(mid 0.249642 0.249642)
							(end 0.2794 0.1778)
						)
						(arc
							(start 0.2794 -0.1778)
							(mid 0.249642 -0.249642)
							(end 0.1778 -0.2794)
						)
					)
					(width 0)
					(fill yes)
				)
			)
		)
		(pad "2" smd custom
			(at 0 0.4445)
			(size 0.1397 0.1397)
			(layers "F.Cu" "F.Mask" "F.Paste")
			(net "SAS2X28_A_HDD6_FLT")
			(options
				(clearance outline)
				(anchor circle)
			)
			(primitives
				(gr_poly
					(pts
						(arc
							(start -0.1778 -0.2794)
							(mid -0.249642 -0.249642)
							(end -0.2794 -0.1778)
						)
						(arc
							(start -0.2794 0.1778)
							(mid -0.249642 0.249642)
							(end -0.1778 0.2794)
						)
						(arc
							(start 0.1778 0.2794)
							(mid 0.249642 0.249642)
							(end 0.2794 0.1778)
						)
						(arc
							(start 0.2794 -0.1778)
							(mid 0.249642 -0.249642)
							(end 0.1778 -0.2794)
						)
					)
					(width 0)
					(fill yes)
				)
			)
		)
	)
	(footprint ""
		(layer "F.Cu")
		(at 26.880312 -345.935808 90)
		(property "Reference" "C278"
			(at 0 0 90)
			(layer "F.SilkS")
			(hide yes)
			(effects
				(font
					(size 1.27 1.27)
				)
			)
		)
		(property "Value" "SCD01U50V2KX-1GP"
			(at 1.1811 -2.7051 90)
			(unlocked yes)
			(layer "F.Fab")
			(hide yes)
			(effects
				(font
					(size 1.016 1.016)
					(thickness 0.1524)
				)
			)
		)
		(property "Device Type" "C402H22"
			(at 1.1811 -4.2291 90)
			(unlocked yes)
			(layer "F.Fab")
			(hide yes)
			(effects
				(font
					(size 1.016 1.016)
					(thickness 0.1524)
				)
			)
		)
		(duplicate_pad_numbers_are_jumpers no)
		(fp_rect
			(start -0.4318 0.9525)
			(end 0.4318 -0.9525)
			(stroke
				(width 0)
				(type default)
			)
			(fill no)
			(layer "F.CrtYd")
		)
		(fp_rect
			(start -0.4318 0.9525)
			(end 0.4318 -0.9525)
			(stroke
				(width 0)
				(type default)
			)
			(fill no)
			(layer "F.Fab")
		)
		(pad "1" smd custom
			(at 0 -0.4445 90)
			(size 0.1524 0.1524)
			(layers "F.Cu" "F.Mask" "F.Paste")
			(net "SAS2X28_DRIVE_RX_N_A11")
			(options
				(clearance outline)
				(anchor circle)
			)
			(primitives
				(gr_poly
					(pts
						(arc
							(start 0.3048 -0.2032)
							(mid 0.275042 -0.275042)
							(end 0.2032 -0.3048)
						)
						(arc
							(start -0.2032 -0.3048)
							(mid -0.275042 -0.275042)
							(end -0.3048 -0.2032)
						)
						(arc
							(start -0.3048 0.2032)
							(mid -0.275042 0.275042)
							(end -0.2032 0.3048)
						)
						(arc
							(start 0.2032 0.3048)
							(mid 0.275042 0.275042)
							(end 0.3048 0.2032)
						)
					)
					(width 0)
					(fill yes)
				)
			)
		)
		(pad "2" smd custom
			(at 0 0.4445 90)
			(size 0.1524 0.1524)
			(layers "F.Cu" "F.Mask" "F.Paste")
			(net "SAS2X28_A_HDD11_RX_-")
			(options
				(clearance outline)
				(anchor circle)
			)
			(primitives
				(gr_poly
					(pts
						(arc
							(start 0.3048 -0.2032)
							(mid 0.275042 -0.275042)
							(end 0.2032 -0.3048)
						)
						(arc
							(start -0.2032 -0.3048)
							(mid -0.275042 -0.275042)
							(end -0.3048 -0.2032)
						)
						(arc
							(start -0.3048 0.2032)
							(mid -0.275042 0.275042)
							(end -0.2032 0.3048)
						)
						(arc
							(start 0.2032 0.3048)
							(mid 0.275042 0.275042)
							(end 0.3048 0.2032)
						)
					)
					(width 0)
					(fill yes)
				)
			)
		)
	)
	(footprint ""
		(layer "F.Cu")
		(at 59.2074 -490.1692)
		(property "Reference" "TP30"
			(at 0 0 0)
			(layer "F.SilkS")
			(hide yes)
			(effects
				(font
					(size 1.27 1.27)
				)
			)
		)
		(property "Value" "TPAD32-GP"
			(at 0 -3.166364 0)
			(unlocked yes)
			(layer "F.Fab")
			(hide yes)
			(effects
				(font
					(size 1.016 1.016)
					(thickness 0.1524)
				)
			)
		)
		(property "Device Type" "TPAD32"
			(at 0 -4.690618 0)
			(unlocked yes)
			(layer "F.Fab")
			(hide yes)
			(effects
				(font
					(size 1.016 1.016)
					(thickness 0.1524)
				)
			)
		)
		(duplicate_pad_numbers_are_jumpers no)
		(fp_poly
			(pts
				(arc
					(start 0.4064 0)
					(mid -0.4064 0)
					(end 0.4064 0)
				)
			)
			(stroke
				(width 0)
				(type default)
			)
			(fill no)
			(layer "F.CrtYd")
		)
		(fp_poly
			(pts
				(arc
					(start 0.7112 0)
					(mid -0.7112 0)
					(end 0.7112 0)
				)
			)
			(stroke
				(width 0)
				(type default)
			)
			(fill no)
			(layer "F.Fab")
		)
		(pad "1" smd circle
			(at 0 0)
			(size 0.8128 0.8128)
			(layers "F.Cu" "F.Mask" "F.Paste")
			(net "ACT_HDD5")
		)
	)
	(footprint ""
		(layer "F.Cu")
		(at 213.741 -181.102)
		(property "Reference" "TP28"
			(at 0 0 0)
			(layer "F.SilkS")
			(hide yes)
			(effects
				(font
					(size 1.27 1.27)
				)
			)
		)
		(property "Value" "TPAD32-GP"
			(at 0 -3.166364 0)
			(unlocked yes)
			(layer "F.Fab")
			(hide yes)
			(effects
				(font
					(size 1.016 1.016)
					(thickness 0.1524)
				)
			)
		)
		(property "Device Type" "TPAD32"
			(at 0 -4.690618 0)
			(unlocked yes)
			(layer "F.Fab")
			(hide yes)
			(effects
				(font
					(size 1.016 1.016)
					(thickness 0.1524)
				)
			)
		)
		(duplicate_pad_numbers_are_jumpers no)
		(fp_poly
			(pts
				(arc
					(start 0.4064 0)
					(mid -0.4064 0)
					(end 0.4064 0)
				)
			)
			(stroke
				(width 0)
				(type default)
			)
			(fill no)
			(layer "F.CrtYd")
		)
		(fp_poly
			(pts
				(arc
					(start 0.7112 0)
					(mid -0.7112 0)
					(end 0.7112 0)
				)
			)
			(stroke
				(width 0)
				(type default)
			)
			(fill no)
			(layer "F.Fab")
		)
		(pad "1" smd circle
			(at 0 0)
			(size 0.8128 0.8128)
			(layers "F.Cu" "F.Mask" "F.Paste")
			(net "ACT_HDD3")
		)
	)
	(footprint ""
		(layer "F.Cu")
		(at 4.445 -280.035 90)
		(property "Reference" "C124"
			(at 0 0 90)
			(layer "F.SilkS")
			(hide yes)
			(effects
				(font
					(size 1.27 1.27)
				)
			)
		)
		(property "Value" "SC1U25V3KX-1-GP"
			(at 0 -2.8194 90)
			(unlocked yes)
			(layer "F.Fab")
			(hide yes)
			(effects
				(font
					(size 1.016 1.016)
					(thickness 0.1524)
				)
			)
		)
		(property "Device Type" "C603H36"
			(at 0 -4.3434 90)
			(unlocked yes)
			(layer "F.Fab")
			(hide yes)
			(effects
				(font
					(size 1.016 1.016)
					(thickness 0.1524)
				)
			)
		)
		(duplicate_pad_numbers_are_jumpers no)
		(fp_line
			(start 0.508 0)
			(end -0.508 0)
			(stroke
				(width 0.2032)
				(type default)
			)
			(layer "F.SilkS")
		)
		(fp_rect
			(start -0.5842 1.3335)
			(end 0.5842 -1.3335)
			(stroke
				(width 0)
				(type default)
			)
			(fill no)
			(layer "F.CrtYd")
		)
		(fp_rect
			(start -0.5842 1.3335)
			(end 0.5842 -1.3335)
			(stroke
				(width 0)
				(type default)
			)
			(fill no)
			(layer "F.Fab")
		)
		(pad "1" smd custom
			(at 0 -0.762 90)
			(size 0.2159 0.2159)
			(layers "F.Cu" "F.Mask" "F.Paste")
			(net "P12V")
			(options
				(clearance outline)
				(anchor circle)
			)
			(primitives
				(gr_poly
					(pts
						(arc
							(start -0.3302 -0.4318)
							(mid -0.402042 -0.402042)
							(end -0.4318 -0.3302)
						)
						(arc
							(start -0.4318 0.3302)
							(mid -0.402042 0.402042)
							(end -0.3302 0.4318)
						)
						(arc
							(start 0.3302 0.4318)
							(mid 0.402042 0.402042)
							(end 0.4318 0.3302)
						)
						(arc
							(start 0.4318 -0.3302)
							(mid 0.402042 -0.402042)
							(end 0.3302 -0.4318)
						)
					)
					(width 0)
					(fill yes)
				)
			)
		)
		(pad "2" smd custom
			(at 0 0.762 90)
			(size 0.2159 0.2159)
			(layers "F.Cu" "F.Mask" "F.Paste")
			(net "GND")
			(options
				(clearance outline)
				(anchor circle)
			)
			(primitives
				(gr_poly
					(pts
						(arc
							(start -0.3302 -0.4318)
							(mid -0.402042 -0.402042)
							(end -0.4318 -0.3302)
						)
						(arc
							(start -0.4318 0.3302)
							(mid -0.402042 0.402042)
							(end -0.3302 0.4318)
						)
						(arc
							(start 0.3302 0.4318)
							(mid 0.402042 0.402042)
							(end 0.4318 0.3302)
						)
						(arc
							(start 0.4318 -0.3302)
							(mid 0.402042 -0.402042)
							(end 0.3302 -0.4318)
						)
					)
					(width 0)
					(fill yes)
				)
			)
		)
	)
	(footprint ""
		(layer "F.Cu")
		(at 53.339746 -228.603302)
		(property "Reference" "R469"
			(at 0 0 0)
			(layer "F.SilkS")
			(hide yes)
			(effects
				(font
					(size 1.27 1.27)
				)
			)
		)
		(property "Value" "4K7R2J-2-GP"
			(at 0.064008 -3.993896 0)
			(unlocked yes)
			(layer "F.Fab")
			(hide yes)
			(effects
				(font
					(size 1.016 1.016)
					(thickness 0.1524)
				)
			)
		)
		(property "Device Type" "R402H16"
			(at 0.064008 -5.517896 0)
			(unlocked yes)
			(layer "F.Fab")
			(hide yes)
			(effects
				(font
					(size 1.016 1.016)
					(thickness 0.1524)
				)
			)
		)
		(duplicate_pad_numbers_are_jumpers no)
		(fp_line
			(start -0.508 -0.9398)
			(end -0.508 0.9398)
			(stroke
				(width 0.1524)
				(type default)
			)
			(layer "F.SilkS")
		)
		(fp_line
			(start 0.508 -0.9398)
			(end -0.508 -0.9398)
			(stroke
				(width 0.1524)
				(type default)
			)
			(layer "F.SilkS")
		)
		(fp_rect
			(start -0.508 0.9398)
			(end 0.508 -0.9398)
			(stroke
				(width 0)
				(type default)
			)
			(fill no)
			(layer "F.CrtYd")
		)
		(fp_rect
			(start -0.508 0.9398)
			(end 0.508 -0.9398)
			(stroke
				(width 0)
				(type default)
			)
			(fill no)
			(layer "F.Fab")
		)
		(pad "1" smd custom
			(at 0 -0.4445)
			(size 0.1397 0.1397)
			(layers "F.Cu" "F.Mask" "F.Paste")
			(net "P3V3")
			(options
				(clearance outline)
				(anchor circle)
			)
			(primitives
				(gr_poly
					(pts
						(arc
							(start -0.1778 -0.2794)
							(mid -0.249642 -0.249642)
							(end -0.2794 -0.1778)
						)
						(arc
							(start -0.2794 0.1778)
							(mid -0.249642 0.249642)
							(end -0.1778 0.2794)
						)
						(arc
							(start 0.1778 0.2794)
							(mid 0.249642 0.249642)
							(end 0.2794 0.1778)
						)
						(arc
							(start 0.2794 -0.1778)
							(mid 0.249642 -0.249642)
							(end 0.1778 -0.2794)
						)
					)
					(width 0)
					(fill yes)
				)
			)
		)
		(pad "2" smd custom
			(at 0 0.4445)
			(size 0.1397 0.1397)
			(layers "F.Cu" "F.Mask" "F.Paste")
			(net "SAS2X28_B_HDD12_FLT")
			(options
				(clearance outline)
				(anchor circle)
			)
			(primitives
				(gr_poly
					(pts
						(arc
							(start -0.1778 -0.2794)
							(mid -0.249642 -0.249642)
							(end -0.2794 -0.1778)
						)
						(arc
							(start -0.2794 0.1778)
							(mid -0.249642 0.249642)
							(end -0.1778 0.2794)
						)
						(arc
							(start 0.1778 0.2794)
							(mid 0.249642 0.249642)
							(end 0.2794 0.1778)
						)
						(arc
							(start 0.2794 -0.1778)
							(mid 0.249642 -0.249642)
							(end 0.1778 -0.2794)
						)
					)
					(width 0)
					(fill yes)
				)
			)
		)
	)
	(footprint ""
		(layer "F.Cu")
		(at 27.812746 -433.225702 180)
		(property "Reference" "R251"
			(at 0 0 180)
			(layer "F.SilkS")
			(hide yes)
			(effects
				(font
					(size 1.27 1.27)
				)
			)
		)
		(property "Value" "220R3F-1-GP"
			(at -0.0254 -2.5146 180)
			(unlocked yes)
			(layer "F.Fab")
			(hide yes)
			(effects
				(font
					(size 1.016 1.016)
					(thickness 0.1524)
				)
			)
		)
		(property "Device Type" "R603H22"
			(at -0.0254 -4.0386 180)
			(unlocked yes)
			(layer "F.Fab")
			(hide yes)
			(effects
				(font
					(size 1.016 1.016)
					(thickness 0.1524)
				)
			)
		)
		(duplicate_pad_numbers_are_jumpers no)
		(fp_line
			(start 0.2032 0)
			(end 0.4826 0)
			(stroke
				(width 0.2032)
				(type default)
			)
			(layer "F.SilkS")
		)
		(fp_line
			(start -0.4826 0)
			(end -0.2032 0)
			(stroke
				(width 0.2032)
				(type default)
			)
			(layer "F.SilkS")
		)
		(fp_rect
			(start -0.5842 1.3335)
			(end 0.5842 -1.3335)
			(stroke
				(width 0)
				(type default)
			)
			(fill no)
			(layer "F.CrtYd")
		)
		(fp_rect
			(start -0.5842 1.3335)
			(end 0.5842 -1.3335)
			(stroke
				(width 0)
				(type default)
			)
			(fill no)
			(layer "F.Fab")
		)
		(pad "1" smd custom
			(at 0 -0.762 180)
			(size 0.2159 0.2159)
			(layers "F.Cu" "F.Mask" "F.Paste")
			(net "HDD_PRSNT_NET10")
			(options
				(clearance outline)
				(anchor circle)
			)
			(primitives
				(gr_poly
					(pts
						(arc
							(start -0.3302 -0.4318)
							(mid -0.402042 -0.402042)
							(end -0.4318 -0.3302)
						)
						(arc
							(start -0.4318 0.3302)
							(mid -0.402042 0.402042)
							(end -0.3302 0.4318)
						)
						(arc
							(start 0.3302 0.4318)
							(mid 0.402042 0.402042)
							(end 0.4318 0.3302)
						)
						(arc
							(start 0.4318 -0.3302)
							(mid 0.402042 -0.402042)
							(end 0.3302 -0.4318)
						)
					)
					(width 0)
					(fill yes)
				)
			)
		)
		(pad "2" smd custom
			(at 0 0.762 180)
			(size 0.2159 0.2159)
			(layers "F.Cu" "F.Mask" "F.Paste")
			(net "HDD_PRSNT10")
			(options
				(clearance outline)
				(anchor circle)
			)
			(primitives
				(gr_poly
					(pts
						(arc
							(start -0.3302 -0.4318)
							(mid -0.402042 -0.402042)
							(end -0.4318 -0.3302)
						)
						(arc
							(start -0.4318 0.3302)
							(mid -0.402042 0.402042)
							(end -0.3302 0.4318)
						)
						(arc
							(start 0.3302 0.4318)
							(mid 0.402042 0.402042)
							(end 0.4318 0.3302)
						)
						(arc
							(start 0.4318 -0.3302)
							(mid 0.402042 -0.402042)
							(end 0.3302 -0.4318)
						)
					)
					(width 0)
					(fill yes)
				)
			)
		)
	)
	(footprint ""
		(layer "F.Cu")
		(at 58.038492 -83.721956 90)
		(property "Reference" "R236"
			(at 0 0 90)
			(layer "F.SilkS")
			(hide yes)
			(effects
				(font
					(size 1.27 1.27)
				)
			)
		)
		(property "Value" "2R2010J-1-GP"
			(at 0.254 -8.0772 90)
			(unlocked yes)
			(layer "F.Fab")
			(hide yes)
			(effects
				(font
					(size 1.016 1.016)
					(thickness 0.1524)
				)
			)
		)
		(property "Device Type" "R2010H28"
			(at 0.254 -9.6774 90)
			(unlocked yes)
			(layer "F.Fab")
			(hide yes)
			(effects
				(font
					(size 1.016 1.016)
					(thickness 0.1524)
				)
			)
		)
		(duplicate_pad_numbers_are_jumpers no)
		(fp_line
			(start 1.651 -3.302)
			(end -1.651 -3.302)
			(stroke
				(width 0.1524)
				(type default)
			)
			(layer "F.SilkS")
		)
		(fp_line
			(start -1.651 -3.302)
			(end -1.651 3.302)
			(stroke
				(width 0.1524)
				(type default)
			)
			(layer "F.SilkS")
		)
		(fp_line
			(start 1.651 3.302)
			(end 1.651 -3.302)
			(stroke
				(width 0.1524)
				(type default)
			)
			(layer "F.SilkS")
		)
		(fp_line
			(start -1.651 3.302)
			(end 1.651 3.302)
			(stroke
				(width 0.1524)
				(type default)
			)
			(layer "F.SilkS")
		)
		(fp_rect
			(start -1.7272 -3.3782)
			(end 1.7272 3.3782)
			(stroke
				(width 0)
				(type default)
			)
			(fill no)
			(layer "F.CrtYd")
		)
		(fp_poly
			(pts
				(xy 1.7272 3.3782) (xy 1.7272 -3.3782) (xy -1.7272 -3.3782) (xy -1.7272 3.3782)
			)
			(stroke
				(width 0)
				(type default)
			)
			(fill no)
			(layer "F.Fab")
		)
		(pad "1" smd rect
			(at 0 -2.3495 90)
			(size 2.794 1.143)
			(layers "F.Cu" "F.Mask" "F.Paste")
			(net "12V_PRE_9")
		)
		(pad "2" smd rect
			(at 0 2.3495 90)
			(size 2.794 1.143)
			(layers "F.Cu" "F.Mask" "F.Paste")
			(net "P12V_HDD9")
		)
	)
	(footprint ""
		(layer "F.Cu")
		(at 42.544746 -212.118702 180)
		(property "Reference" "R277"
			(at 0 0 180)
			(layer "F.SilkS")
			(hide yes)
			(effects
				(font
					(size 1.27 1.27)
				)
			)
		)
		(property "Value" "1KR2F-3-GP"
			(at 0.064008 -3.993896 180)
			(unlocked yes)
			(layer "F.Fab")
			(hide yes)
			(effects
				(font
					(size 1.016 1.016)
					(thickness 0.1524)
				)
			)
		)
		(property "Device Type" "R402H16"
			(at 0.064008 -5.517896 180)
			(unlocked yes)
			(layer "F.Fab")
			(hide yes)
			(effects
				(font
					(size 1.016 1.016)
					(thickness 0.1524)
				)
			)
		)
		(duplicate_pad_numbers_are_jumpers no)
		(fp_line
			(start 0.508 -0.9398)
			(end -0.508 -0.9398)
			(stroke
				(width 0.1524)
				(type default)
			)
			(layer "F.SilkS")
		)
		(fp_line
			(start -0.508 -0.9398)
			(end -0.508 0.9398)
			(stroke
				(width 0.1524)
				(type default)
			)
			(layer "F.SilkS")
		)
		(fp_rect
			(start -0.508 0.9398)
			(end 0.508 -0.9398)
			(stroke
				(width 0)
				(type default)
			)
			(fill no)
			(layer "F.CrtYd")
		)
		(fp_rect
			(start -0.508 0.9398)
			(end 0.508 -0.9398)
			(stroke
				(width 0)
				(type default)
			)
			(fill no)
			(layer "F.Fab")
		)
		(pad "1" smd custom
			(at 0 -0.4445 180)
			(size 0.1397 0.1397)
			(layers "F.Cu" "F.Mask" "F.Paste")
			(net "P3V3")
			(options
				(clearance outline)
				(anchor circle)
			)
			(primitives
				(gr_poly
					(pts
						(arc
							(start -0.1778 -0.2794)
							(mid -0.249642 -0.249642)
							(end -0.2794 -0.1778)
						)
						(arc
							(start -0.2794 0.1778)
							(mid -0.249642 0.249642)
							(end -0.1778 0.2794)
						)
						(arc
							(start 0.1778 0.2794)
							(mid 0.249642 0.249642)
							(end 0.2794 0.1778)
						)
						(arc
							(start 0.2794 -0.1778)
							(mid 0.249642 -0.249642)
							(end 0.1778 -0.2794)
						)
					)
					(width 0)
					(fill yes)
				)
			)
		)
		(pad "2" smd custom
			(at 0 0.4445 180)
			(size 0.1397 0.1397)
			(layers "F.Cu" "F.Mask" "F.Paste")
			(net "SW_PWR_HDD12")
			(options
				(clearance outline)
				(anchor circle)
			)
			(primitives
				(gr_poly
					(pts
						(arc
							(start -0.1778 -0.2794)
							(mid -0.249642 -0.249642)
							(end -0.2794 -0.1778)
						)
						(arc
							(start -0.2794 0.1778)
							(mid -0.249642 0.249642)
							(end -0.1778 0.2794)
						)
						(arc
							(start 0.1778 0.2794)
							(mid 0.249642 0.249642)
							(end 0.2794 0.1778)
						)
						(arc
							(start 0.2794 -0.1778)
							(mid 0.249642 -0.249642)
							(end 0.1778 -0.2794)
						)
					)
					(width 0)
					(fill yes)
				)
			)
		)
	)
	(footprint ""
		(layer "F.Cu")
		(at 27.406346 -405.6761 90)
		(property "Reference" "C350"
			(at 0 0 90)
			(layer "F.SilkS")
			(hide yes)
			(effects
				(font
					(size 1.27 1.27)
				)
			)
		)
		(property "Value" "SC10U25V5KX-GP"
			(at -0.0762 -6.1214 90)
			(unlocked yes)
			(layer "F.Fab")
			(hide yes)
			(effects
				(font
					(size 1.016 1.016)
					(thickness 0.1524)
				)
			)
		)
		(property "Device Type" "C805H56"
			(at -0.0762 -8.1534 90)
			(unlocked yes)
			(layer "F.Fab")
			(hide yes)
			(effects
				(font
					(size 1.016 1.016)
					(thickness 0.1524)
				)
			)
		)
		(duplicate_pad_numbers_are_jumpers no)
		(fp_line
			(start 0.635 0)
			(end -0.635 0)
			(stroke
				(width 0.508)
				(type default)
			)
			(layer "F.SilkS")
		)
		(fp_rect
			(start -0.9652 1.778)
			(end 0.9652 -1.778)
			(stroke
				(width 0)
				(type default)
			)
			(fill no)
			(layer "F.CrtYd")
		)
		(fp_poly
			(pts
				(xy -0.9652 -1.778) (xy 0.9652 -1.778) (xy 0.9652 1.778) (xy -0.9652 1.778)
			)
			(stroke
				(width 0)
				(type default)
			)
			(fill no)
			(layer "F.Fab")
		)
		(pad "1" smd rect
			(at 0 -0.9652 90)
			(size 1.397 1.143)
			(layers "F.Cu" "F.Mask" "F.Paste")
			(net "P12V")
		)
		(pad "2" smd rect
			(at 0 0.9652 90)
			(size 1.397 1.143)
			(layers "F.Cu" "F.Mask" "F.Paste")
			(net "GND")
		)
	)
	(footprint ""
		(layer "F.Cu")
		(at 37.083746 -437.5277 90)
		(property "Reference" "R247"
			(at 0 0 90)
			(layer "F.SilkS")
			(hide yes)
			(effects
				(font
					(size 1.27 1.27)
				)
			)
		)
		(property "Value" "1KR2F-3-GP"
			(at 0.064008 -3.993896 90)
			(unlocked yes)
			(layer "F.Fab")
			(hide yes)
			(effects
				(font
					(size 1.016 1.016)
					(thickness 0.1524)
				)
			)
		)
		(property "Device Type" "R402H16"
			(at 0.064008 -5.517896 90)
			(unlocked yes)
			(layer "F.Fab")
			(hide yes)
			(effects
				(font
					(size 1.016 1.016)
					(thickness 0.1524)
				)
			)
		)
		(duplicate_pad_numbers_are_jumpers no)
		(fp_line
			(start 0.508 -0.9398)
			(end -0.508 -0.9398)
			(stroke
				(width 0.1524)
				(type default)
			)
			(layer "F.SilkS")
		)
		(fp_line
			(start -0.508 -0.9398)
			(end -0.508 0.9398)
			(stroke
				(width 0.1524)
				(type default)
			)
			(layer "F.SilkS")
		)
		(fp_rect
			(start -0.508 0.9398)
			(end 0.508 -0.9398)
			(stroke
				(width 0)
				(type default)
			)
			(fill no)
			(layer "F.CrtYd")
		)
		(fp_rect
			(start -0.508 0.9398)
			(end 0.508 -0.9398)
			(stroke
				(width 0)
				(type default)
			)
			(fill no)
			(layer "F.Fab")
		)
		(pad "1" smd custom
			(at 0 -0.4445 90)
			(size 0.1397 0.1397)
			(layers "F.Cu" "F.Mask" "F.Paste")
			(net "P3V3")
			(options
				(clearance outline)
				(anchor circle)
			)
			(primitives
				(gr_poly
					(pts
						(arc
							(start -0.1778 -0.2794)
							(mid -0.249642 -0.249642)
							(end -0.2794 -0.1778)
						)
						(arc
							(start -0.2794 0.1778)
							(mid -0.249642 0.249642)
							(end -0.1778 0.2794)
						)
						(arc
							(start 0.1778 0.2794)
							(mid 0.249642 0.249642)
							(end 0.2794 0.1778)
						)
						(arc
							(start 0.2794 -0.1778)
							(mid 0.249642 -0.249642)
							(end 0.1778 -0.2794)
						)
					)
					(width 0)
					(fill yes)
				)
			)
		)
		(pad "2" smd custom
			(at 0 0.4445 90)
			(size 0.1397 0.1397)
			(layers "F.Cu" "F.Mask" "F.Paste")
			(net "SW_PWR_HDD10")
			(options
				(clearance outline)
				(anchor circle)
			)
			(primitives
				(gr_poly
					(pts
						(arc
							(start -0.1778 -0.2794)
							(mid -0.249642 -0.249642)
							(end -0.2794 -0.1778)
						)
						(arc
							(start -0.2794 0.1778)
							(mid -0.249642 0.249642)
							(end -0.1778 0.2794)
						)
						(arc
							(start 0.1778 0.2794)
							(mid 0.249642 0.249642)
							(end 0.2794 0.1778)
						)
						(arc
							(start 0.2794 -0.1778)
							(mid 0.249642 -0.249642)
							(end 0.1778 -0.2794)
						)
					)
					(width 0)
					(fill yes)
				)
			)
		)
	)
	(footprint ""
		(layer "F.Cu")
		(at 192.151 -190.754 90)
		(property "Reference" "R148"
			(at 0 0 90)
			(layer "F.SilkS")
			(hide yes)
			(effects
				(font
					(size 1.27 1.27)
				)
			)
		)
		(property "Value" "4K7R2J-2-GP"
			(at 0.064008 -3.993896 90)
			(unlocked yes)
			(layer "F.Fab")
			(hide yes)
			(effects
				(font
					(size 1.016 1.016)
					(thickness 0.1524)
				)
			)
		)
		(property "Device Type" "R402H16"
			(at 0.064008 -5.517896 90)
			(unlocked yes)
			(layer "F.Fab")
			(hide yes)
			(effects
				(font
					(size 1.016 1.016)
					(thickness 0.1524)
				)
			)
		)
		(duplicate_pad_numbers_are_jumpers no)
		(fp_line
			(start 0.508 -0.9398)
			(end -0.508 -0.9398)
			(stroke
				(width 0.1524)
				(type default)
			)
			(layer "F.SilkS")
		)
		(fp_line
			(start -0.508 -0.9398)
			(end -0.508 0.9398)
			(stroke
				(width 0.1524)
				(type default)
			)
			(layer "F.SilkS")
		)
		(fp_rect
			(start -0.508 0.9398)
			(end 0.508 -0.9398)
			(stroke
				(width 0)
				(type default)
			)
			(fill no)
			(layer "F.CrtYd")
		)
		(fp_rect
			(start -0.508 0.9398)
			(end 0.508 -0.9398)
			(stroke
				(width 0)
				(type default)
			)
			(fill no)
			(layer "F.Fab")
		)
		(pad "1" smd custom
			(at 0 -0.4445 90)
			(size 0.1397 0.1397)
			(layers "F.Cu" "F.Mask" "F.Paste")
			(net "P12V")
			(options
				(clearance outline)
				(anchor circle)
			)
			(primitives
				(gr_poly
					(pts
						(arc
							(start -0.1778 -0.2794)
							(mid -0.249642 -0.249642)
							(end -0.2794 -0.1778)
						)
						(arc
							(start -0.2794 0.1778)
							(mid -0.249642 0.249642)
							(end -0.1778 0.2794)
						)
						(arc
							(start 0.1778 0.2794)
							(mid 0.249642 0.249642)
							(end 0.2794 0.1778)
						)
						(arc
							(start 0.2794 -0.1778)
							(mid 0.249642 -0.249642)
							(end 0.1778 -0.2794)
						)
					)
					(width 0)
					(fill yes)
				)
			)
		)
		(pad "2" smd custom
			(at 0 0.4445 90)
			(size 0.1397 0.1397)
			(layers "F.Cu" "F.Mask" "F.Paste")
			(net "SW_HDD3_R")
			(options
				(clearance outline)
				(anchor circle)
			)
			(primitives
				(gr_poly
					(pts
						(arc
							(start -0.1778 -0.2794)
							(mid -0.249642 -0.249642)
							(end -0.2794 -0.1778)
						)
						(arc
							(start -0.2794 0.1778)
							(mid -0.249642 0.249642)
							(end -0.1778 0.2794)
						)
						(arc
							(start 0.1778 0.2794)
							(mid 0.249642 0.249642)
							(end 0.2794 0.1778)
						)
						(arc
							(start 0.2794 -0.1778)
							(mid 0.249642 -0.249642)
							(end 0.1778 -0.2794)
						)
					)
					(width 0)
					(fill yes)
				)
			)
		)
	)
	(footprint ""
		(layer "F.Cu")
		(at 39.743634 -453.874886 90)
		(property "Reference" "R171"
			(at 0 0 90)
			(layer "F.SilkS")
			(hide yes)
			(effects
				(font
					(size 1.27 1.27)
				)
			)
		)
		(property "Value" "402R2F-GP"
			(at 0.064008 -3.993896 90)
			(unlocked yes)
			(layer "F.Fab")
			(hide yes)
			(effects
				(font
					(size 1.016 1.016)
					(thickness 0.1524)
				)
			)
		)
		(property "Device Type" "R402H16"
			(at 0.064008 -5.517896 90)
			(unlocked yes)
			(layer "F.Fab")
			(hide yes)
			(effects
				(font
					(size 1.016 1.016)
					(thickness 0.1524)
				)
			)
		)
		(duplicate_pad_numbers_are_jumpers no)
		(fp_line
			(start 0.508 -0.9398)
			(end -0.508 -0.9398)
			(stroke
				(width 0.1524)
				(type default)
			)
			(layer "F.SilkS")
		)
		(fp_line
			(start -0.508 -0.9398)
			(end -0.508 0.9398)
			(stroke
				(width 0.1524)
				(type default)
			)
			(layer "F.SilkS")
		)
		(fp_rect
			(start -0.508 0.9398)
			(end 0.508 -0.9398)
			(stroke
				(width 0)
				(type default)
			)
			(fill no)
			(layer "F.CrtYd")
		)
		(fp_rect
			(start -0.508 0.9398)
			(end 0.508 -0.9398)
			(stroke
				(width 0)
				(type default)
			)
			(fill no)
			(layer "F.Fab")
		)
		(pad "1" smd custom
			(at 0 -0.4445 90)
			(size 0.1397 0.1397)
			(layers "F.Cu" "F.Mask" "F.Paste")
			(net "P5VB_HDD5_LED")
			(options
				(clearance outline)
				(anchor circle)
			)
			(primitives
				(gr_poly
					(pts
						(arc
							(start -0.1778 -0.2794)
							(mid -0.249642 -0.249642)
							(end -0.2794 -0.1778)
						)
						(arc
							(start -0.2794 0.1778)
							(mid -0.249642 0.249642)
							(end -0.1778 0.2794)
						)
						(arc
							(start 0.1778 0.2794)
							(mid 0.249642 0.249642)
							(end 0.2794 0.1778)
						)
						(arc
							(start 0.2794 -0.1778)
							(mid 0.249642 -0.249642)
							(end 0.1778 -0.2794)
						)
					)
					(width 0)
					(fill yes)
				)
			)
		)
		(pad "2" smd custom
			(at 0 0.4445 90)
			(size 0.1397 0.1397)
			(layers "F.Cu" "F.Mask" "F.Paste")
			(net "DRV_ACT_5")
			(options
				(clearance outline)
				(anchor circle)
			)
			(primitives
				(gr_poly
					(pts
						(arc
							(start -0.1778 -0.2794)
							(mid -0.249642 -0.249642)
							(end -0.2794 -0.1778)
						)
						(arc
							(start -0.2794 0.1778)
							(mid -0.249642 0.249642)
							(end -0.1778 0.2794)
						)
						(arc
							(start 0.1778 0.2794)
							(mid 0.249642 0.249642)
							(end 0.2794 0.1778)
						)
						(arc
							(start 0.2794 -0.1778)
							(mid 0.249642 -0.249642)
							(end 0.1778 -0.2794)
						)
					)
					(width 0)
					(fill yes)
				)
			)
		)
	)
	(footprint ""
		(layer "F.Cu")
		(at 33.2613 -274.5994 90)
		(property "Reference" "C37"
			(at 0 0 90)
			(layer "F.SilkS")
			(hide yes)
			(effects
				(font
					(size 1.27 1.27)
				)
			)
		)
		(property "Value" "SCD01U50V2KX-1GP"
			(at 1.1811 -2.7051 90)
			(unlocked yes)
			(layer "F.Fab")
			(hide yes)
			(effects
				(font
					(size 1.016 1.016)
					(thickness 0.1524)
				)
			)
		)
		(property "Device Type" "C402H22"
			(at 1.1811 -4.2291 90)
			(unlocked yes)
			(layer "F.Fab")
			(hide yes)
			(effects
				(font
					(size 1.016 1.016)
					(thickness 0.1524)
				)
			)
		)
		(duplicate_pad_numbers_are_jumpers no)
		(fp_rect
			(start -0.4318 0.9525)
			(end 0.4318 -0.9525)
			(stroke
				(width 0)
				(type default)
			)
			(fill no)
			(layer "F.CrtYd")
		)
		(fp_rect
			(start -0.4318 0.9525)
			(end 0.4318 -0.9525)
			(stroke
				(width 0)
				(type default)
			)
			(fill no)
			(layer "F.Fab")
		)
		(pad "1" smd custom
			(at 0 -0.4445 90)
			(size 0.1524 0.1524)
			(layers "F.Cu" "F.Mask" "F.Paste")
			(net "SEB_BA_TX-")
			(options
				(clearance outline)
				(anchor circle)
			)
			(primitives
				(gr_poly
					(pts
						(arc
							(start 0.3048 -0.2032)
							(mid 0.275042 -0.275042)
							(end 0.2032 -0.3048)
						)
						(arc
							(start -0.2032 -0.3048)
							(mid -0.275042 -0.275042)
							(end -0.3048 -0.2032)
						)
						(arc
							(start -0.3048 0.2032)
							(mid -0.275042 0.275042)
							(end -0.2032 0.3048)
						)
						(arc
							(start 0.2032 0.3048)
							(mid 0.275042 0.275042)
							(end 0.3048 0.2032)
						)
					)
					(width 0)
					(fill yes)
				)
			)
		)
		(pad "2" smd custom
			(at 0 0.4445 90)
			(size 0.1524 0.1524)
			(layers "F.Cu" "F.Mask" "F.Paste")
			(net "SEB_BA_RX-")
			(options
				(clearance outline)
				(anchor circle)
			)
			(primitives
				(gr_poly
					(pts
						(arc
							(start 0.3048 -0.2032)
							(mid 0.275042 -0.275042)
							(end 0.2032 -0.3048)
						)
						(arc
							(start -0.2032 -0.3048)
							(mid -0.275042 -0.275042)
							(end -0.3048 -0.2032)
						)
						(arc
							(start -0.3048 0.2032)
							(mid -0.275042 0.275042)
							(end -0.2032 0.3048)
						)
						(arc
							(start 0.2032 0.3048)
							(mid 0.275042 0.275042)
							(end 0.3048 0.2032)
						)
					)
					(width 0)
					(fill yes)
				)
			)
		)
	)
	(footprint ""
		(layer "F.Cu")
		(at 202.864974 -493.875822 -90)
		(property "Reference" "R422"
			(at 0 0 270)
			(layer "F.SilkS")
			(hide yes)
			(effects
				(font
					(size 1.27 1.27)
				)
			)
		)
		(property "Value" "4K7R2J-2-GP"
			(at 0.064008 -3.993896 270)
			(unlocked yes)
			(layer "F.Fab")
			(hide yes)
			(effects
				(font
					(size 1.016 1.016)
					(thickness 0.1524)
				)
			)
		)
		(property "Device Type" "R402H16"
			(at 0.064008 -5.517896 270)
			(unlocked yes)
			(layer "F.Fab")
			(hide yes)
			(effects
				(font
					(size 1.016 1.016)
					(thickness 0.1524)
				)
			)
		)
		(duplicate_pad_numbers_are_jumpers no)
		(fp_line
			(start -0.508 -0.9398)
			(end -0.508 0.9398)
			(stroke
				(width 0.1524)
				(type default)
			)
			(layer "F.SilkS")
		)
		(fp_line
			(start 0.508 -0.9398)
			(end -0.508 -0.9398)
			(stroke
				(width 0.1524)
				(type default)
			)
			(layer "F.SilkS")
		)
		(fp_rect
			(start -0.508 0.9398)
			(end 0.508 -0.9398)
			(stroke
				(width 0)
				(type default)
			)
			(fill no)
			(layer "F.CrtYd")
		)
		(fp_rect
			(start -0.508 0.9398)
			(end 0.508 -0.9398)
			(stroke
				(width 0)
				(type default)
			)
			(fill no)
			(layer "F.Fab")
		)
		(pad "1" smd custom
			(at 0 -0.4445 270)
			(size 0.1397 0.1397)
			(layers "F.Cu" "F.Mask" "F.Paste")
			(net "P3V3")
			(options
				(clearance outline)
				(anchor circle)
			)
			(primitives
				(gr_poly
					(pts
						(arc
							(start -0.1778 -0.2794)
							(mid -0.249642 -0.249642)
							(end -0.2794 -0.1778)
						)
						(arc
							(start -0.2794 0.1778)
							(mid -0.249642 0.249642)
							(end -0.1778 0.2794)
						)
						(arc
							(start 0.1778 0.2794)
							(mid 0.249642 0.249642)
							(end 0.2794 0.1778)
						)
						(arc
							(start 0.2794 -0.1778)
							(mid 0.249642 -0.249642)
							(end 0.1778 -0.2794)
						)
					)
					(width 0)
					(fill yes)
				)
			)
		)
		(pad "2" smd custom
			(at 0 0.4445 270)
			(size 0.1397 0.1397)
			(layers "F.Cu" "F.Mask" "F.Paste")
			(net "SAS2X28_B_HDD0_FLT")
			(options
				(clearance outline)
				(anchor circle)
			)
			(primitives
				(gr_poly
					(pts
						(arc
							(start -0.1778 -0.2794)
							(mid -0.249642 -0.249642)
							(end -0.2794 -0.1778)
						)
						(arc
							(start -0.2794 0.1778)
							(mid -0.249642 0.249642)
							(end -0.1778 0.2794)
						)
						(arc
							(start 0.1778 0.2794)
							(mid 0.249642 0.249642)
							(end 0.2794 0.1778)
						)
						(arc
							(start 0.2794 -0.1778)
							(mid 0.249642 -0.249642)
							(end 0.1778 -0.2794)
						)
					)
					(width 0)
					(fill yes)
				)
			)
		)
	)
	(footprint ""
		(layer "F.Cu")
		(at 224.789746 -144.9197 90)
		(property "Reference" "R143"
			(at 0 0 90)
			(layer "F.SilkS")
			(hide yes)
			(effects
				(font
					(size 1.27 1.27)
				)
			)
		)
		(property "Value" "402R2F-GP"
			(at 0.064008 -3.993896 90)
			(unlocked yes)
			(layer "F.Fab")
			(hide yes)
			(effects
				(font
					(size 1.016 1.016)
					(thickness 0.1524)
				)
			)
		)
		(property "Device Type" "R402H16"
			(at 0.064008 -5.517896 90)
			(unlocked yes)
			(layer "F.Fab")
			(hide yes)
			(effects
				(font
					(size 1.016 1.016)
					(thickness 0.1524)
				)
			)
		)
		(duplicate_pad_numbers_are_jumpers no)
		(fp_line
			(start 0.508 -0.9398)
			(end -0.508 -0.9398)
			(stroke
				(width 0.1524)
				(type default)
			)
			(layer "F.SilkS")
		)
		(fp_line
			(start -0.508 -0.9398)
			(end -0.508 0.9398)
			(stroke
				(width 0.1524)
				(type default)
			)
			(layer "F.SilkS")
		)
		(fp_rect
			(start -0.508 0.9398)
			(end 0.508 -0.9398)
			(stroke
				(width 0)
				(type default)
			)
			(fill no)
			(layer "F.CrtYd")
		)
		(fp_rect
			(start -0.508 0.9398)
			(end 0.508 -0.9398)
			(stroke
				(width 0)
				(type default)
			)
			(fill no)
			(layer "F.Fab")
		)
		(pad "1" smd custom
			(at 0 -0.4445 90)
			(size 0.1397 0.1397)
			(layers "F.Cu" "F.Mask" "F.Paste")
			(net "P5VA_HDD3_LED")
			(options
				(clearance outline)
				(anchor circle)
			)
			(primitives
				(gr_poly
					(pts
						(arc
							(start -0.1778 -0.2794)
							(mid -0.249642 -0.249642)
							(end -0.2794 -0.1778)
						)
						(arc
							(start -0.2794 0.1778)
							(mid -0.249642 0.249642)
							(end -0.1778 0.2794)
						)
						(arc
							(start 0.1778 0.2794)
							(mid 0.249642 0.249642)
							(end 0.2794 0.1778)
						)
						(arc
							(start 0.2794 -0.1778)
							(mid 0.249642 -0.249642)
							(end 0.1778 -0.2794)
						)
					)
					(width 0)
					(fill yes)
				)
			)
		)
		(pad "2" smd custom
			(at 0 0.4445 90)
			(size 0.1397 0.1397)
			(layers "F.Cu" "F.Mask" "F.Paste")
			(net "DRV_ACT_3")
			(options
				(clearance outline)
				(anchor circle)
			)
			(primitives
				(gr_poly
					(pts
						(arc
							(start -0.1778 -0.2794)
							(mid -0.249642 -0.249642)
							(end -0.2794 -0.1778)
						)
						(arc
							(start -0.2794 0.1778)
							(mid -0.249642 0.249642)
							(end -0.1778 0.2794)
						)
						(arc
							(start 0.1778 0.2794)
							(mid 0.249642 0.249642)
							(end 0.2794 0.1778)
						)
						(arc
							(start 0.2794 -0.1778)
							(mid 0.249642 -0.249642)
							(end 0.1778 -0.2794)
						)
					)
					(width 0)
					(fill yes)
				)
			)
		)
	)
	(footprint ""
		(layer "F.Cu")
		(at 42.500042 -350.160082 180)
		(property "Reference" "LED7"
			(at 0 0 180)
			(layer "F.SilkS")
			(hide yes)
			(effects
				(font
					(size 1.27 1.27)
				)
			)
		)
		(property "Value" "LED-RB-4-GP"
			(at 5.88899 1.80848 180)
			(unlocked yes)
			(layer "F.Fab")
			(hide yes)
			(effects
				(font
					(size 1.016 1.016)
					(thickness 0.1524)
				)
			)
		)
		(property "Device Type" "LED1613-4PH20"
			(at 5.88899 0.28448 180)
			(unlocked yes)
			(layer "F.Fab")
			(hide yes)
			(effects
				(font
					(size 1.016 1.016)
					(thickness 0.1524)
				)
			)
		)
		(duplicate_pad_numbers_are_jumpers no)
		(fp_line
			(start 1.4478 0.9652)
			(end -1.4478 0.9652)
			(stroke
				(width 0.1524)
				(type default)
			)
			(layer "F.SilkS")
		)
		(fp_line
			(start 1.4478 -0.9652)
			(end 1.4478 0.9652)
			(stroke
				(width 0.1524)
				(type default)
			)
			(layer "F.SilkS")
		)
		(fp_line
			(start -1.4478 0.9652)
			(end -1.4478 -0.9652)
			(stroke
				(width 0.1524)
				(type default)
			)
			(layer "F.SilkS")
		)
		(fp_line
			(start -1.4478 0.9652)
			(end -1.4478 -0.9652)
			(stroke
				(width 0.508)
				(type default)
			)
			(layer "F.SilkS")
		)
		(fp_line
			(start -1.4478 -0.9652)
			(end 1.4478 -0.9652)
			(stroke
				(width 0.1524)
				(type default)
			)
			(layer "F.SilkS")
		)
		(fp_rect
			(start -0.8001 0.6477)
			(end 0.8001 -0.6477)
			(stroke
				(width 0)
				(type default)
			)
			(fill no)
			(layer "F.CrtYd")
		)
		(fp_poly
			(pts
				(xy -1.7018 1.2192) (xy -1.7018 -0.06223) (xy -0.8001 -0.06223) (xy -0.8001 0.6477) (xy 0.8001 0.6477)
				(xy 0.8001 -0.6477) (xy -0.8001 -0.6477) (xy -0.8001 -0.0635) (xy -1.7018 -0.0635) (xy -1.7018 -1.2192)
				(xy 1.7018 -1.2192) (xy 1.7018 1.2192)
			)
			(stroke
				(width 0)
				(type default)
			)
			(fill no)
			(layer "F.CrtYd")
		)
		(fp_rect
			(start -1.7018 1.2192)
			(end 1.7018 -1.2192)
			(stroke
				(width 0)
				(type default)
			)
			(fill no)
			(layer "F.Fab")
		)
		(pad "1" smd rect
			(at -0.73025 0.4064 180)
			(size 0.9144 0.6096)
			(layers "F.Cu" "F.Mask" "F.Paste")
			(net "DRV_ACT_NET6")
		)
		(pad "2" smd rect
			(at -0.73025 -0.4064 180)
			(size 0.9144 0.6096)
			(layers "F.Cu" "F.Mask" "F.Paste")
			(net "FLT_NET_HDD6")
		)
		(pad "3" smd rect
			(at 0.73025 -0.4064 180)
			(size 0.9144 0.6096)
			(layers "F.Cu" "F.Mask" "F.Paste")
			(net "FLT_HDD6")
		)
		(pad "4" smd rect
			(at 0.73025 0.4064 180)
			(size 0.9144 0.6096)
			(layers "F.Cu" "F.Mask" "F.Paste")
			(net "DRV_ACT_6")
		)
	)
	(footprint ""
		(layer "F.Cu")
		(at 187.464446 -458.885036 90)
		(property "Reference" "R346"
			(at 0 0 90)
			(layer "F.SilkS")
			(hide yes)
			(effects
				(font
					(size 1.27 1.27)
				)
			)
		)
		(property "Value" "4K7R2J-2-GP"
			(at 0.064008 -3.993896 90)
			(unlocked yes)
			(layer "F.Fab")
			(hide yes)
			(effects
				(font
					(size 1.016 1.016)
					(thickness 0.1524)
				)
			)
		)
		(property "Device Type" "R402H16"
			(at 0.064008 -5.517896 90)
			(unlocked yes)
			(layer "F.Fab")
			(hide yes)
			(effects
				(font
					(size 1.016 1.016)
					(thickness 0.1524)
				)
			)
		)
		(duplicate_pad_numbers_are_jumpers no)
		(fp_line
			(start 0.508 -0.9398)
			(end -0.508 -0.9398)
			(stroke
				(width 0.1524)
				(type default)
			)
			(layer "F.SilkS")
		)
		(fp_line
			(start -0.508 -0.9398)
			(end -0.508 0.9398)
			(stroke
				(width 0.1524)
				(type default)
			)
			(layer "F.SilkS")
		)
		(fp_rect
			(start -0.508 0.9398)
			(end 0.508 -0.9398)
			(stroke
				(width 0)
				(type default)
			)
			(fill no)
			(layer "F.CrtYd")
		)
		(fp_rect
			(start -0.508 0.9398)
			(end 0.508 -0.9398)
			(stroke
				(width 0)
				(type default)
			)
			(fill no)
			(layer "F.Fab")
		)
		(pad "1" smd custom
			(at 0 -0.4445 90)
			(size 0.1397 0.1397)
			(layers "F.Cu" "F.Mask" "F.Paste")
			(net "P3V3")
			(options
				(clearance outline)
				(anchor circle)
			)
			(primitives
				(gr_poly
					(pts
						(arc
							(start -0.1778 -0.2794)
							(mid -0.249642 -0.249642)
							(end -0.2794 -0.1778)
						)
						(arc
							(start -0.2794 0.1778)
							(mid -0.249642 0.249642)
							(end -0.1778 0.2794)
						)
						(arc
							(start 0.1778 0.2794)
							(mid 0.249642 0.249642)
							(end 0.2794 0.1778)
						)
						(arc
							(start 0.2794 -0.1778)
							(mid 0.249642 -0.249642)
							(end 0.1778 -0.2794)
						)
					)
					(width 0)
					(fill yes)
				)
			)
		)
		(pad "2" smd custom
			(at 0 0.4445 90)
			(size 0.1397 0.1397)
			(layers "F.Cu" "F.Mask" "F.Paste")
			(net "EEPROM_A1")
			(options
				(clearance outline)
				(anchor circle)
			)
			(primitives
				(gr_poly
					(pts
						(arc
							(start -0.1778 -0.2794)
							(mid -0.249642 -0.249642)
							(end -0.2794 -0.1778)
						)
						(arc
							(start -0.2794 0.1778)
							(mid -0.249642 0.249642)
							(end -0.1778 0.2794)
						)
						(arc
							(start 0.1778 0.2794)
							(mid 0.249642 0.249642)
							(end 0.2794 0.1778)
						)
						(arc
							(start 0.2794 -0.1778)
							(mid 0.249642 -0.249642)
							(end 0.1778 -0.2794)
						)
					)
					(width 0)
					(fill yes)
				)
			)
		)
	)
	(footprint ""
		(layer "F.Cu")
		(at 29.654246 -384.0099)
		(property "Reference" "R310"
			(at 0 0 0)
			(layer "F.SilkS")
			(hide yes)
			(effects
				(font
					(size 1.27 1.27)
				)
			)
		)
		(property "Value" "0R2J-2-GP"
			(at 0.064008 -3.993896 0)
			(unlocked yes)
			(layer "F.Fab")
			(hide yes)
			(effects
				(font
					(size 1.016 1.016)
					(thickness 0.1524)
				)
			)
		)
		(property "Device Type" "R402H16"
			(at 0.064008 -5.517896 0)
			(unlocked yes)
			(layer "F.Fab")
			(hide yes)
			(effects
				(font
					(size 1.016 1.016)
					(thickness 0.1524)
				)
			)
		)
		(duplicate_pad_numbers_are_jumpers no)
		(fp_line
			(start -0.508 -0.9398)
			(end -0.508 0.9398)
			(stroke
				(width 0.1524)
				(type default)
			)
			(layer "F.SilkS")
		)
		(fp_line
			(start 0.508 -0.9398)
			(end -0.508 -0.9398)
			(stroke
				(width 0.1524)
				(type default)
			)
			(layer "F.SilkS")
		)
		(fp_rect
			(start -0.508 0.9398)
			(end 0.508 -0.9398)
			(stroke
				(width 0)
				(type default)
			)
			(fill no)
			(layer "F.CrtYd")
		)
		(fp_rect
			(start -0.508 0.9398)
			(end 0.508 -0.9398)
			(stroke
				(width 0)
				(type default)
			)
			(fill no)
			(layer "F.Fab")
		)
		(pad "1" smd custom
			(at 0 -0.4445)
			(size 0.1397 0.1397)
			(layers "F.Cu" "F.Mask" "F.Paste")
			(net "I2C_B_SDA")
			(options
				(clearance outline)
				(anchor circle)
			)
			(primitives
				(gr_poly
					(pts
						(arc
							(start -0.1778 -0.2794)
							(mid -0.249642 -0.249642)
							(end -0.2794 -0.1778)
						)
						(arc
							(start -0.2794 0.1778)
							(mid -0.249642 0.249642)
							(end -0.1778 0.2794)
						)
						(arc
							(start 0.1778 0.2794)
							(mid 0.249642 0.249642)
							(end 0.2794 0.1778)
						)
						(arc
							(start 0.2794 -0.1778)
							(mid 0.249642 -0.249642)
							(end 0.1778 -0.2794)
						)
					)
					(width 0)
					(fill yes)
				)
			)
		)
		(pad "2" smd custom
			(at 0 0.4445)
			(size 0.1397 0.1397)
			(layers "F.Cu" "F.Mask" "F.Paste")
			(net "TMP1_SDA")
			(options
				(clearance outline)
				(anchor circle)
			)
			(primitives
				(gr_poly
					(pts
						(arc
							(start -0.1778 -0.2794)
							(mid -0.249642 -0.249642)
							(end -0.2794 -0.1778)
						)
						(arc
							(start -0.2794 0.1778)
							(mid -0.249642 0.249642)
							(end -0.1778 0.2794)
						)
						(arc
							(start 0.1778 0.2794)
							(mid 0.249642 0.249642)
							(end 0.2794 0.1778)
						)
						(arc
							(start 0.2794 -0.1778)
							(mid 0.249642 -0.249642)
							(end 0.1778 -0.2794)
						)
					)
					(width 0)
					(fill yes)
				)
			)
		)
	)
	(footprint ""
		(layer "F.Cu")
		(at 179.971446 -459.824836 180)
		(property "Reference" "R389"
			(at 0 0 180)
			(layer "F.SilkS")
			(hide yes)
			(effects
				(font
					(size 1.27 1.27)
				)
			)
		)
		(property "Value" "2KR2F-3-GP"
			(at 0.064008 -3.993896 180)
			(unlocked yes)
			(layer "F.Fab")
			(hide yes)
			(effects
				(font
					(size 1.016 1.016)
					(thickness 0.1524)
				)
			)
		)
		(property "Device Type" "R402H16"
			(at 0.064008 -5.517896 180)
			(unlocked yes)
			(layer "F.Fab")
			(hide yes)
			(effects
				(font
					(size 1.016 1.016)
					(thickness 0.1524)
				)
			)
		)
		(duplicate_pad_numbers_are_jumpers no)
		(fp_line
			(start 0.508 -0.9398)
			(end -0.508 -0.9398)
			(stroke
				(width 0.1524)
				(type default)
			)
			(layer "F.SilkS")
		)
		(fp_line
			(start -0.508 -0.9398)
			(end -0.508 0.9398)
			(stroke
				(width 0.1524)
				(type default)
			)
			(layer "F.SilkS")
		)
		(fp_rect
			(start -0.508 0.9398)
			(end 0.508 -0.9398)
			(stroke
				(width 0)
				(type default)
			)
			(fill no)
			(layer "F.CrtYd")
		)
		(fp_rect
			(start -0.508 0.9398)
			(end 0.508 -0.9398)
			(stroke
				(width 0)
				(type default)
			)
			(fill no)
			(layer "F.Fab")
		)
		(pad "1" smd custom
			(at 0 -0.4445 180)
			(size 0.1397 0.1397)
			(layers "F.Cu" "F.Mask" "F.Paste")
			(net "P12V_DIV")
			(options
				(clearance outline)
				(anchor circle)
			)
			(primitives
				(gr_poly
					(pts
						(arc
							(start -0.1778 -0.2794)
							(mid -0.249642 -0.249642)
							(end -0.2794 -0.1778)
						)
						(arc
							(start -0.2794 0.1778)
							(mid -0.249642 0.249642)
							(end -0.1778 0.2794)
						)
						(arc
							(start 0.1778 0.2794)
							(mid 0.249642 0.249642)
							(end 0.2794 0.1778)
						)
						(arc
							(start 0.2794 -0.1778)
							(mid 0.249642 -0.249642)
							(end 0.1778 -0.2794)
						)
					)
					(width 0)
					(fill yes)
				)
			)
		)
		(pad "2" smd custom
			(at 0 0.4445 180)
			(size 0.1397 0.1397)
			(layers "F.Cu" "F.Mask" "F.Paste")
			(net "GND")
			(options
				(clearance outline)
				(anchor circle)
			)
			(primitives
				(gr_poly
					(pts
						(arc
							(start -0.1778 -0.2794)
							(mid -0.249642 -0.249642)
							(end -0.2794 -0.1778)
						)
						(arc
							(start -0.2794 0.1778)
							(mid -0.249642 0.249642)
							(end -0.1778 0.2794)
						)
						(arc
							(start 0.1778 0.2794)
							(mid 0.249642 0.249642)
							(end 0.2794 0.1778)
						)
						(arc
							(start 0.2794 -0.1778)
							(mid 0.249642 -0.249642)
							(end 0.1778 -0.2794)
						)
					)
					(width 0)
					(fill yes)
				)
			)
		)
	)
	(footprint ""
		(layer "F.Cu")
		(at 45.465746 -29.9847 180)
		(property "Reference" "PC25"
			(at 0 0 180)
			(layer "F.SilkS")
			(hide yes)
			(effects
				(font
					(size 1.27 1.27)
				)
			)
		)
		(property "Value" "SC10U16V6KX-2GP"
			(at -0.0762 -5.1308 180)
			(unlocked yes)
			(layer "F.Fab")
			(hide yes)
			(effects
				(font
					(size 1.016 1.016)
					(thickness 0.1524)
				)
			)
		)
		(property "Device Type" "C1206H71"
			(at -0.127 -6.6548 180)
			(unlocked yes)
			(layer "F.Fab")
			(hide yes)
			(effects
				(font
					(size 1.016 1.016)
					(thickness 0.1524)
				)
			)
		)
		(duplicate_pad_numbers_are_jumpers no)
		(fp_line
			(start 1.016 2.2352)
			(end -1.016 2.2352)
			(stroke
				(width 0.1524)
				(type default)
			)
			(layer "F.SilkS")
		)
		(fp_line
			(start 1.016 0.8382)
			(end 1.016 2.2352)
			(stroke
				(width 0.1524)
				(type default)
			)
			(layer "F.SilkS")
		)
		(fp_line
			(start 1.016 -2.2352)
			(end 1.016 -0.8382)
			(stroke
				(width 0.1524)
				(type default)
			)
			(layer "F.SilkS")
		)
		(fp_line
			(start -1.016 2.2352)
			(end -1.016 0.8382)
			(stroke
				(width 0.1524)
				(type default)
			)
			(layer "F.SilkS")
		)
		(fp_line
			(start -1.016 -0.8382)
			(end -1.016 -2.2352)
			(stroke
				(width 0.1524)
				(type default)
			)
			(layer "F.SilkS")
		)
		(fp_line
			(start -1.016 -2.2352)
			(end 1.016 -2.2352)
			(stroke
				(width 0.1524)
				(type default)
			)
			(layer "F.SilkS")
		)
		(fp_rect
			(start -1.0922 2.3114)
			(end 1.0922 -2.3114)
			(stroke
				(width 0)
				(type default)
			)
			(fill no)
			(layer "F.CrtYd")
		)
		(fp_poly
			(pts
				(xy 1.0922 -2.3114) (xy 1.0922 2.3114) (xy -1.0922 2.3114) (xy -1.0922 -2.3114)
			)
			(stroke
				(width 0)
				(type default)
			)
			(fill no)
			(layer "F.Fab")
		)
		(pad "1" smd rect
			(at 0 -1.397 180)
			(size 1.651 1.27)
			(layers "F.Cu" "F.Mask" "F.Paste")
			(net "P5VB")
		)
		(pad "2" smd rect
			(at 0 1.397 180)
			(size 1.651 1.27)
			(layers "F.Cu" "F.Mask" "F.Paste")
			(net "GND")
		)
	)
	(footprint ""
		(layer "F.Cu")
		(at 43.814746 -212.118702 180)
		(property "Reference" "R281"
			(at 0 0 180)
			(layer "F.SilkS")
			(hide yes)
			(effects
				(font
					(size 1.27 1.27)
				)
			)
		)
		(property "Value" "0R2J-2-GP"
			(at 0.064008 -3.993896 180)
			(unlocked yes)
			(layer "F.Fab")
			(hide yes)
			(effects
				(font
					(size 1.016 1.016)
					(thickness 0.1524)
				)
			)
		)
		(property "Device Type" "R402H16"
			(at 0.064008 -5.517896 180)
			(unlocked yes)
			(layer "F.Fab")
			(hide yes)
			(effects
				(font
					(size 1.016 1.016)
					(thickness 0.1524)
				)
			)
		)
		(duplicate_pad_numbers_are_jumpers no)
		(fp_line
			(start 0.508 -0.9398)
			(end -0.508 -0.9398)
			(stroke
				(width 0.1524)
				(type default)
			)
			(layer "F.SilkS")
		)
		(fp_line
			(start -0.508 -0.9398)
			(end -0.508 0.9398)
			(stroke
				(width 0.1524)
				(type default)
			)
			(layer "F.SilkS")
		)
		(fp_rect
			(start -0.508 0.9398)
			(end 0.508 -0.9398)
			(stroke
				(width 0)
				(type default)
			)
			(fill no)
			(layer "F.CrtYd")
		)
		(fp_rect
			(start -0.508 0.9398)
			(end 0.508 -0.9398)
			(stroke
				(width 0)
				(type default)
			)
			(fill no)
			(layer "F.Fab")
		)
		(pad "1" smd custom
			(at 0 -0.4445 180)
			(size 0.1397 0.1397)
			(layers "F.Cu" "F.Mask" "F.Paste")
			(net "DRIVE_PWR12")
			(options
				(clearance outline)
				(anchor circle)
			)
			(primitives
				(gr_poly
					(pts
						(arc
							(start -0.1778 -0.2794)
							(mid -0.249642 -0.249642)
							(end -0.2794 -0.1778)
						)
						(arc
							(start -0.2794 0.1778)
							(mid -0.249642 0.249642)
							(end -0.1778 0.2794)
						)
						(arc
							(start 0.1778 0.2794)
							(mid 0.249642 0.249642)
							(end 0.2794 0.1778)
						)
						(arc
							(start 0.2794 -0.1778)
							(mid 0.249642 -0.249642)
							(end 0.1778 -0.2794)
						)
					)
					(width 0)
					(fill yes)
				)
			)
		)
		(pad "2" smd custom
			(at 0 0.4445 180)
			(size 0.1397 0.1397)
			(layers "F.Cu" "F.Mask" "F.Paste")
			(net "SW_PWR_HDD12")
			(options
				(clearance outline)
				(anchor circle)
			)
			(primitives
				(gr_poly
					(pts
						(arc
							(start -0.1778 -0.2794)
							(mid -0.249642 -0.249642)
							(end -0.2794 -0.1778)
						)
						(arc
							(start -0.2794 0.1778)
							(mid -0.249642 0.249642)
							(end -0.1778 0.2794)
						)
						(arc
							(start 0.1778 0.2794)
							(mid 0.249642 0.249642)
							(end 0.2794 0.1778)
						)
						(arc
							(start 0.2794 -0.1778)
							(mid 0.249642 -0.249642)
							(end 0.1778 -0.2794)
						)
					)
					(width 0)
					(fill yes)
				)
			)
		)
	)
	(footprint ""
		(layer "F.Cu")
		(at 237.870746 -27.9527)
		(property "Reference" "PR12"
			(at 0 0 0)
			(layer "F.SilkS")
			(hide yes)
			(effects
				(font
					(size 1.27 1.27)
				)
			)
		)
		(property "Value" "866KR2F-GP"
			(at 0.064008 -3.993896 0)
			(unlocked yes)
			(layer "F.Fab")
			(hide yes)
			(effects
				(font
					(size 1.016 1.016)
					(thickness 0.1524)
				)
			)
		)
		(property "Device Type" "R402H16"
			(at 0.064008 -5.517896 0)
			(unlocked yes)
			(layer "F.Fab")
			(hide yes)
			(effects
				(font
					(size 1.016 1.016)
					(thickness 0.1524)
				)
			)
		)
		(duplicate_pad_numbers_are_jumpers no)
		(fp_line
			(start -0.508 -0.9398)
			(end -0.508 0.9398)
			(stroke
				(width 0.1524)
				(type default)
			)
			(layer "F.SilkS")
		)
		(fp_line
			(start 0.508 -0.9398)
			(end -0.508 -0.9398)
			(stroke
				(width 0.1524)
				(type default)
			)
			(layer "F.SilkS")
		)
		(fp_rect
			(start -0.508 0.9398)
			(end 0.508 -0.9398)
			(stroke
				(width 0)
				(type default)
			)
			(fill no)
			(layer "F.CrtYd")
		)
		(fp_rect
			(start -0.508 0.9398)
			(end 0.508 -0.9398)
			(stroke
				(width 0)
				(type default)
			)
			(fill no)
			(layer "F.Fab")
		)
		(pad "1" smd custom
			(at 0 -0.4445)
			(size 0.1397 0.1397)
			(layers "F.Cu" "F.Mask" "F.Paste")
			(net "P5VA_VREG")
			(options
				(clearance outline)
				(anchor circle)
			)
			(primitives
				(gr_poly
					(pts
						(arc
							(start -0.1778 -0.2794)
							(mid -0.249642 -0.249642)
							(end -0.2794 -0.1778)
						)
						(arc
							(start -0.2794 0.1778)
							(mid -0.249642 0.249642)
							(end -0.1778 0.2794)
						)
						(arc
							(start 0.1778 0.2794)
							(mid 0.249642 0.249642)
							(end 0.2794 0.1778)
						)
						(arc
							(start 0.2794 -0.1778)
							(mid 0.249642 -0.249642)
							(end 0.1778 -0.2794)
						)
					)
					(width 0)
					(fill yes)
				)
			)
		)
		(pad "2" smd custom
			(at 0 0.4445)
			(size 0.1397 0.1397)
			(layers "F.Cu" "F.Mask" "F.Paste")
			(net "P5VA_RF")
			(options
				(clearance outline)
				(anchor circle)
			)
			(primitives
				(gr_poly
					(pts
						(arc
							(start -0.1778 -0.2794)
							(mid -0.249642 -0.249642)
							(end -0.2794 -0.1778)
						)
						(arc
							(start -0.2794 0.1778)
							(mid -0.249642 0.249642)
							(end -0.1778 0.2794)
						)
						(arc
							(start 0.1778 0.2794)
							(mid 0.249642 0.249642)
							(end 0.2794 0.1778)
						)
						(arc
							(start 0.2794 -0.1778)
							(mid 0.249642 -0.249642)
							(end 0.1778 -0.2794)
						)
					)
					(width 0)
					(fill yes)
				)
			)
		)
	)
	(footprint ""
		(layer "F.Cu")
		(at 83.185 -89.662)
		(property "Reference" "C373"
			(at 0 0 0)
			(layer "F.SilkS")
			(hide yes)
			(effects
				(font
					(size 1.27 1.27)
				)
			)
		)
		(property "Value" "SCD033U25V2KX-GP"
			(at 1.1811 -2.7051 0)
			(unlocked yes)
			(layer "F.Fab")
			(hide yes)
			(effects
				(font
					(size 1.016 1.016)
					(thickness 0.1524)
				)
			)
		)
		(property "Device Type" "C402H22"
			(at 1.1811 -4.2291 0)
			(unlocked yes)
			(layer "F.Fab")
			(hide yes)
			(effects
				(font
					(size 1.016 1.016)
					(thickness 0.1524)
				)
			)
		)
		(duplicate_pad_numbers_are_jumpers no)
		(fp_rect
			(start -0.4318 0.9525)
			(end 0.4318 -0.9525)
			(stroke
				(width 0)
				(type default)
			)
			(fill no)
			(layer "F.CrtYd")
		)
		(fp_rect
			(start -0.4318 0.9525)
			(end 0.4318 -0.9525)
			(stroke
				(width 0)
				(type default)
			)
			(fill no)
			(layer "F.Fab")
		)
		(pad "1" smd custom
			(at 0 -0.4445)
			(size 0.1524 0.1524)
			(layers "F.Cu" "F.Mask" "F.Paste")
			(net "SW_HDD9_P")
			(options
				(clearance outline)
				(anchor circle)
			)
			(primitives
				(gr_poly
					(pts
						(arc
							(start 0.3048 -0.2032)
							(mid 0.275042 -0.275042)
							(end 0.2032 -0.3048)
						)
						(arc
							(start -0.2032 -0.3048)
							(mid -0.275042 -0.275042)
							(end -0.3048 -0.2032)
						)
						(arc
							(start -0.3048 0.2032)
							(mid -0.275042 0.275042)
							(end -0.2032 0.3048)
						)
						(arc
							(start 0.2032 0.3048)
							(mid 0.275042 0.275042)
							(end 0.3048 0.2032)
						)
					)
					(width 0)
					(fill yes)
				)
			)
		)
		(pad "2" smd custom
			(at 0 0.4445)
			(size 0.1524 0.1524)
			(layers "F.Cu" "F.Mask" "F.Paste")
			(net "GND")
			(options
				(clearance outline)
				(anchor circle)
			)
			(primitives
				(gr_poly
					(pts
						(arc
							(start 0.3048 -0.2032)
							(mid 0.275042 -0.275042)
							(end 0.2032 -0.3048)
						)
						(arc
							(start -0.2032 -0.3048)
							(mid -0.275042 -0.275042)
							(end -0.3048 -0.2032)
						)
						(arc
							(start -0.3048 0.2032)
							(mid -0.275042 0.275042)
							(end -0.2032 0.3048)
						)
						(arc
							(start 0.2032 0.3048)
							(mid 0.275042 0.275042)
							(end 0.3048 0.2032)
						)
					)
					(width 0)
					(fill yes)
				)
			)
		)
	)
	(footprint ""
		(layer "F.Cu")
		(at 26.796746 -304.828702 180)
		(property "Reference" "R467"
			(at 0 0 180)
			(layer "F.SilkS")
			(hide yes)
			(effects
				(font
					(size 1.27 1.27)
				)
			)
		)
		(property "Value" "4K7R2J-2-GP"
			(at 0.064008 -3.993896 180)
			(unlocked yes)
			(layer "F.Fab")
			(hide yes)
			(effects
				(font
					(size 1.016 1.016)
					(thickness 0.1524)
				)
			)
		)
		(property "Device Type" "R402H16"
			(at 0.064008 -5.517896 180)
			(unlocked yes)
			(layer "F.Fab")
			(hide yes)
			(effects
				(font
					(size 1.016 1.016)
					(thickness 0.1524)
				)
			)
		)
		(duplicate_pad_numbers_are_jumpers no)
		(fp_line
			(start 0.508 -0.9398)
			(end -0.508 -0.9398)
			(stroke
				(width 0.1524)
				(type default)
			)
			(layer "F.SilkS")
		)
		(fp_line
			(start -0.508 -0.9398)
			(end -0.508 0.9398)
			(stroke
				(width 0.1524)
				(type default)
			)
			(layer "F.SilkS")
		)
		(fp_rect
			(start -0.508 0.9398)
			(end 0.508 -0.9398)
			(stroke
				(width 0)
				(type default)
			)
			(fill no)
			(layer "F.CrtYd")
		)
		(fp_rect
			(start -0.508 0.9398)
			(end 0.508 -0.9398)
			(stroke
				(width 0)
				(type default)
			)
			(fill no)
			(layer "F.Fab")
		)
		(pad "1" smd custom
			(at 0 -0.4445 180)
			(size 0.1397 0.1397)
			(layers "F.Cu" "F.Mask" "F.Paste")
			(net "P3V3")
			(options
				(clearance outline)
				(anchor circle)
			)
			(primitives
				(gr_poly
					(pts
						(arc
							(start -0.1778 -0.2794)
							(mid -0.249642 -0.249642)
							(end -0.2794 -0.1778)
						)
						(arc
							(start -0.2794 0.1778)
							(mid -0.249642 0.249642)
							(end -0.1778 0.2794)
						)
						(arc
							(start 0.1778 0.2794)
							(mid 0.249642 0.249642)
							(end 0.2794 0.1778)
						)
						(arc
							(start 0.2794 -0.1778)
							(mid 0.249642 -0.249642)
							(end 0.1778 -0.2794)
						)
					)
					(width 0)
					(fill yes)
				)
			)
		)
		(pad "2" smd custom
			(at 0 0.4445 180)
			(size 0.1397 0.1397)
			(layers "F.Cu" "F.Mask" "F.Paste")
			(net "SAS_EXP_B_PWR11")
			(options
				(clearance outline)
				(anchor circle)
			)
			(primitives
				(gr_poly
					(pts
						(arc
							(start -0.1778 -0.2794)
							(mid -0.249642 -0.249642)
							(end -0.2794 -0.1778)
						)
						(arc
							(start -0.2794 0.1778)
							(mid -0.249642 0.249642)
							(end -0.1778 0.2794)
						)
						(arc
							(start 0.1778 0.2794)
							(mid 0.249642 0.249642)
							(end 0.2794 0.1778)
						)
						(arc
							(start 0.2794 -0.1778)
							(mid 0.249642 -0.249642)
							(end 0.1778 -0.2794)
						)
					)
					(width 0)
					(fill yes)
				)
			)
		)
	)
	(footprint ""
		(layer "F.Cu")
		(at 50.095404 -22.968712 90)
		(property "Reference" "TP23"
			(at 0 0 90)
			(layer "F.SilkS")
			(hide yes)
			(effects
				(font
					(size 1.27 1.27)
				)
			)
		)
		(property "Value" "TPAD32-GP"
			(at 0 -3.166364 90)
			(unlocked yes)
			(layer "F.Fab")
			(hide yes)
			(effects
				(font
					(size 1.016 1.016)
					(thickness 0.1524)
				)
			)
		)
		(property "Device Type" "TPAD32"
			(at 0 -4.690618 90)
			(unlocked yes)
			(layer "F.Fab")
			(hide yes)
			(effects
				(font
					(size 1.016 1.016)
					(thickness 0.1524)
				)
			)
		)
		(duplicate_pad_numbers_are_jumpers no)
		(fp_poly
			(pts
				(arc
					(start 0 0.4064)
					(mid 0 -0.4064)
					(end 0 0.4064)
				)
			)
			(stroke
				(width 0)
				(type default)
			)
			(fill no)
			(layer "F.CrtYd")
		)
		(fp_poly
			(pts
				(arc
					(start 0 0.7112)
					(mid 0 -0.7112)
					(end 0 0.7112)
				)
			)
			(stroke
				(width 0)
				(type default)
			)
			(fill no)
			(layer "F.Fab")
		)
		(pad "1" smd circle
			(at 0 0 90)
			(size 0.8128 0.8128)
			(layers "F.Cu" "F.Mask" "F.Paste")
			(net "P5VB_PGD")
		)
	)
	(footprint ""
		(layer "F.Cu")
		(at 219.6846 -86.8934 180)
		(property "Reference" "C179"
			(at 0 0 180)
			(layer "F.SilkS")
			(hide yes)
			(effects
				(font
					(size 1.27 1.27)
				)
			)
		)
		(property "Value" "SC1U25V3KX-1-GP"
			(at 0 -2.8194 180)
			(unlocked yes)
			(layer "F.Fab")
			(hide yes)
			(effects
				(font
					(size 1.016 1.016)
					(thickness 0.1524)
				)
			)
		)
		(property "Device Type" "C603H36"
			(at 0 -4.3434 180)
			(unlocked yes)
			(layer "F.Fab")
			(hide yes)
			(effects
				(font
					(size 1.016 1.016)
					(thickness 0.1524)
				)
			)
		)
		(duplicate_pad_numbers_are_jumpers no)
		(fp_line
			(start 0.508 0)
			(end -0.508 0)
			(stroke
				(width 0.2032)
				(type default)
			)
			(layer "F.SilkS")
		)
		(fp_rect
			(start -0.5842 1.3335)
			(end 0.5842 -1.3335)
			(stroke
				(width 0)
				(type default)
			)
			(fill no)
			(layer "F.CrtYd")
		)
		(fp_rect
			(start -0.5842 1.3335)
			(end 0.5842 -1.3335)
			(stroke
				(width 0)
				(type default)
			)
			(fill no)
			(layer "F.Fab")
		)
		(pad "1" smd custom
			(at 0 -0.762 180)
			(size 0.2159 0.2159)
			(layers "F.Cu" "F.Mask" "F.Paste")
			(net "P12V_HDD4")
			(options
				(clearance outline)
				(anchor circle)
			)
			(primitives
				(gr_poly
					(pts
						(arc
							(start -0.3302 -0.4318)
							(mid -0.402042 -0.402042)
							(end -0.4318 -0.3302)
						)
						(arc
							(start -0.4318 0.3302)
							(mid -0.402042 0.402042)
							(end -0.3302 0.4318)
						)
						(arc
							(start 0.3302 0.4318)
							(mid 0.402042 0.402042)
							(end 0.4318 0.3302)
						)
						(arc
							(start 0.4318 -0.3302)
							(mid 0.402042 -0.402042)
							(end 0.3302 -0.4318)
						)
					)
					(width 0)
					(fill yes)
				)
			)
		)
		(pad "2" smd custom
			(at 0 0.762 180)
			(size 0.2159 0.2159)
			(layers "F.Cu" "F.Mask" "F.Paste")
			(net "GND")
			(options
				(clearance outline)
				(anchor circle)
			)
			(primitives
				(gr_poly
					(pts
						(arc
							(start -0.3302 -0.4318)
							(mid -0.402042 -0.402042)
							(end -0.4318 -0.3302)
						)
						(arc
							(start -0.4318 0.3302)
							(mid -0.402042 0.402042)
							(end -0.3302 0.4318)
						)
						(arc
							(start 0.3302 0.4318)
							(mid 0.402042 0.402042)
							(end 0.4318 0.3302)
						)
						(arc
							(start 0.4318 -0.3302)
							(mid 0.402042 -0.402042)
							(end 0.3302 -0.4318)
						)
					)
					(width 0)
					(fill yes)
				)
			)
		)
	)
	(footprint ""
		(layer "F.Cu")
		(at 211.835746 -52.4637)
		(property "Reference" "R330"
			(at 0 0 0)
			(layer "F.SilkS")
			(hide yes)
			(effects
				(font
					(size 1.27 1.27)
				)
			)
		)
		(property "Value" "0R2J-2-GP"
			(at 0.064008 -3.993896 0)
			(unlocked yes)
			(layer "F.Fab")
			(hide yes)
			(effects
				(font
					(size 1.016 1.016)
					(thickness 0.1524)
				)
			)
		)
		(property "Device Type" "R402H16"
			(at 0.064008 -5.517896 0)
			(unlocked yes)
			(layer "F.Fab")
			(hide yes)
			(effects
				(font
					(size 1.016 1.016)
					(thickness 0.1524)
				)
			)
		)
		(duplicate_pad_numbers_are_jumpers no)
		(fp_line
			(start -0.508 -0.9398)
			(end -0.508 0.9398)
			(stroke
				(width 0.1524)
				(type default)
			)
			(layer "F.SilkS")
		)
		(fp_line
			(start 0.508 -0.9398)
			(end -0.508 -0.9398)
			(stroke
				(width 0.1524)
				(type default)
			)
			(layer "F.SilkS")
		)
		(fp_rect
			(start -0.508 0.9398)
			(end 0.508 -0.9398)
			(stroke
				(width 0)
				(type default)
			)
			(fill no)
			(layer "F.CrtYd")
		)
		(fp_rect
			(start -0.508 0.9398)
			(end 0.508 -0.9398)
			(stroke
				(width 0)
				(type default)
			)
			(fill no)
			(layer "F.Fab")
		)
		(pad "1" smd custom
			(at 0 -0.4445)
			(size 0.1397 0.1397)
			(layers "F.Cu" "F.Mask" "F.Paste")
			(net "I2C_B_SDA")
			(options
				(clearance outline)
				(anchor circle)
			)
			(primitives
				(gr_poly
					(pts
						(arc
							(start -0.1778 -0.2794)
							(mid -0.249642 -0.249642)
							(end -0.2794 -0.1778)
						)
						(arc
							(start -0.2794 0.1778)
							(mid -0.249642 0.249642)
							(end -0.1778 0.2794)
						)
						(arc
							(start 0.1778 0.2794)
							(mid 0.249642 0.249642)
							(end 0.2794 0.1778)
						)
						(arc
							(start 0.2794 -0.1778)
							(mid 0.249642 -0.249642)
							(end 0.1778 -0.2794)
						)
					)
					(width 0)
					(fill yes)
				)
			)
		)
		(pad "2" smd custom
			(at 0 0.4445)
			(size 0.1397 0.1397)
			(layers "F.Cu" "F.Mask" "F.Paste")
			(net "TMP4_SDA")
			(options
				(clearance outline)
				(anchor circle)
			)
			(primitives
				(gr_poly
					(pts
						(arc
							(start -0.1778 -0.2794)
							(mid -0.249642 -0.249642)
							(end -0.2794 -0.1778)
						)
						(arc
							(start -0.2794 0.1778)
							(mid -0.249642 0.249642)
							(end -0.1778 0.2794)
						)
						(arc
							(start 0.1778 0.2794)
							(mid 0.249642 0.249642)
							(end 0.2794 0.1778)
						)
						(arc
							(start 0.2794 -0.1778)
							(mid 0.249642 -0.249642)
							(end 0.1778 -0.2794)
						)
					)
					(width 0)
					(fill yes)
				)
			)
		)
	)
	(footprint ""
		(layer "F.Cu")
		(at 78.358746 -399.5547 90)
		(property "Reference" "R194"
			(at 0 0 90)
			(layer "F.SilkS")
			(hide yes)
			(effects
				(font
					(size 1.27 1.27)
				)
			)
		)
		(property "Value" "200KR2F-L-GP"
			(at 0.064008 -3.993896 90)
			(unlocked yes)
			(layer "F.Fab")
			(hide yes)
			(effects
				(font
					(size 1.016 1.016)
					(thickness 0.1524)
				)
			)
		)
		(property "Device Type" "R402H16"
			(at 0.064008 -5.517896 90)
			(unlocked yes)
			(layer "F.Fab")
			(hide yes)
			(effects
				(font
					(size 1.016 1.016)
					(thickness 0.1524)
				)
			)
		)
		(duplicate_pad_numbers_are_jumpers no)
		(fp_line
			(start 0.508 -0.9398)
			(end -0.508 -0.9398)
			(stroke
				(width 0.1524)
				(type default)
			)
			(layer "F.SilkS")
		)
		(fp_line
			(start -0.508 -0.9398)
			(end -0.508 0.9398)
			(stroke
				(width 0.1524)
				(type default)
			)
			(layer "F.SilkS")
		)
		(fp_rect
			(start -0.508 0.9398)
			(end 0.508 -0.9398)
			(stroke
				(width 0)
				(type default)
			)
			(fill no)
			(layer "F.CrtYd")
		)
		(fp_rect
			(start -0.508 0.9398)
			(end 0.508 -0.9398)
			(stroke
				(width 0)
				(type default)
			)
			(fill no)
			(layer "F.Fab")
		)
		(pad "1" smd custom
			(at 0 -0.4445 90)
			(size 0.1397 0.1397)
			(layers "F.Cu" "F.Mask" "F.Paste")
			(net "P12V")
			(options
				(clearance outline)
				(anchor circle)
			)
			(primitives
				(gr_poly
					(pts
						(arc
							(start -0.1778 -0.2794)
							(mid -0.249642 -0.249642)
							(end -0.2794 -0.1778)
						)
						(arc
							(start -0.2794 0.1778)
							(mid -0.249642 0.249642)
							(end -0.1778 0.2794)
						)
						(arc
							(start 0.1778 0.2794)
							(mid 0.249642 0.249642)
							(end 0.2794 0.1778)
						)
						(arc
							(start 0.2794 -0.1778)
							(mid 0.249642 -0.249642)
							(end 0.1778 -0.2794)
						)
					)
					(width 0)
					(fill yes)
				)
			)
		)
		(pad "2" smd custom
			(at 0 0.4445 90)
			(size 0.1397 0.1397)
			(layers "F.Cu" "F.Mask" "F.Paste")
			(net "SW_HDD6_P")
			(options
				(clearance outline)
				(anchor circle)
			)
			(primitives
				(gr_poly
					(pts
						(arc
							(start -0.1778 -0.2794)
							(mid -0.249642 -0.249642)
							(end -0.2794 -0.1778)
						)
						(arc
							(start -0.2794 0.1778)
							(mid -0.249642 0.249642)
							(end -0.1778 0.2794)
						)
						(arc
							(start 0.1778 0.2794)
							(mid 0.249642 0.249642)
							(end 0.2794 0.1778)
						)
						(arc
							(start 0.2794 -0.1778)
							(mid 0.249642 -0.249642)
							(end 0.1778 -0.2794)
						)
					)
					(width 0)
					(fill yes)
				)
			)
		)
	)
	(footprint ""
		(layer "F.Cu")
		(at 29.209746 -327.307702 90)
		(property "Reference" "R260"
			(at 0 0 90)
			(layer "F.SilkS")
			(hide yes)
			(effects
				(font
					(size 1.27 1.27)
				)
			)
		)
		(property "Value" "2R2010J-1-GP"
			(at 0.254 -8.0772 90)
			(unlocked yes)
			(layer "F.Fab")
			(hide yes)
			(effects
				(font
					(size 1.016 1.016)
					(thickness 0.1524)
				)
			)
		)
		(property "Device Type" "R2010H28"
			(at 0.254 -9.6774 90)
			(unlocked yes)
			(layer "F.Fab")
			(hide yes)
			(effects
				(font
					(size 1.016 1.016)
					(thickness 0.1524)
				)
			)
		)
		(duplicate_pad_numbers_are_jumpers no)
		(fp_line
			(start 1.651 -3.302)
			(end -1.651 -3.302)
			(stroke
				(width 0.1524)
				(type default)
			)
			(layer "F.SilkS")
		)
		(fp_line
			(start -1.651 -3.302)
			(end -1.651 3.302)
			(stroke
				(width 0.1524)
				(type default)
			)
			(layer "F.SilkS")
		)
		(fp_line
			(start 1.651 3.302)
			(end 1.651 -3.302)
			(stroke
				(width 0.1524)
				(type default)
			)
			(layer "F.SilkS")
		)
		(fp_line
			(start -1.651 3.302)
			(end 1.651 3.302)
			(stroke
				(width 0.1524)
				(type default)
			)
			(layer "F.SilkS")
		)
		(fp_rect
			(start -1.7272 -3.3782)
			(end 1.7272 3.3782)
			(stroke
				(width 0)
				(type default)
			)
			(fill no)
			(layer "F.CrtYd")
		)
		(fp_poly
			(pts
				(xy 1.7272 3.3782) (xy 1.7272 -3.3782) (xy -1.7272 -3.3782) (xy -1.7272 3.3782)
			)
			(stroke
				(width 0)
				(type default)
			)
			(fill no)
			(layer "F.Fab")
		)
		(pad "1" smd rect
			(at 0 -2.3495 90)
			(size 2.794 1.143)
			(layers "F.Cu" "F.Mask" "F.Paste")
			(net "5V_PRE_11")
		)
		(pad "2" smd rect
			(at 0 2.3495 90)
			(size 2.794 1.143)
			(layers "F.Cu" "F.Mask" "F.Paste")
			(net "P5V_HDD11")
		)
	)
	(footprint ""
		(layer "F.Cu")
		(at 75.401932 -494.240312 180)
		(property "Reference" "C187"
			(at 0 0 180)
			(layer "F.SilkS")
			(hide yes)
			(effects
				(font
					(size 1.27 1.27)
				)
			)
		)
		(property "Value" "SCD1U10V2KX-5GP"
			(at 1.1811 -2.7051 180)
			(unlocked yes)
			(layer "F.Fab")
			(hide yes)
			(effects
				(font
					(size 1.016 1.016)
					(thickness 0.1524)
				)
			)
		)
		(property "Device Type" "C402H22"
			(at 1.1811 -4.2291 180)
			(unlocked yes)
			(layer "F.Fab")
			(hide yes)
			(effects
				(font
					(size 1.016 1.016)
					(thickness 0.1524)
				)
			)
		)
		(duplicate_pad_numbers_are_jumpers no)
		(fp_rect
			(start -0.4318 0.9525)
			(end 0.4318 -0.9525)
			(stroke
				(width 0)
				(type default)
			)
			(fill no)
			(layer "F.CrtYd")
		)
		(fp_rect
			(start -0.4318 0.9525)
			(end 0.4318 -0.9525)
			(stroke
				(width 0)
				(type default)
			)
			(fill no)
			(layer "F.Fab")
		)
		(pad "1" smd custom
			(at 0 -0.4445 180)
			(size 0.1524 0.1524)
			(layers "F.Cu" "F.Mask" "F.Paste")
			(net "P3V3")
			(options
				(clearance outline)
				(anchor circle)
			)
			(primitives
				(gr_poly
					(pts
						(arc
							(start 0.3048 -0.2032)
							(mid 0.275042 -0.275042)
							(end 0.2032 -0.3048)
						)
						(arc
							(start -0.2032 -0.3048)
							(mid -0.275042 -0.275042)
							(end -0.3048 -0.2032)
						)
						(arc
							(start -0.3048 0.2032)
							(mid -0.275042 0.275042)
							(end -0.2032 0.3048)
						)
						(arc
							(start 0.2032 0.3048)
							(mid 0.275042 0.275042)
							(end 0.3048 0.2032)
						)
					)
					(width 0)
					(fill yes)
				)
			)
		)
		(pad "2" smd custom
			(at 0 0.4445 180)
			(size 0.1524 0.1524)
			(layers "F.Cu" "F.Mask" "F.Paste")
			(net "GND")
			(options
				(clearance outline)
				(anchor circle)
			)
			(primitives
				(gr_poly
					(pts
						(arc
							(start 0.3048 -0.2032)
							(mid 0.275042 -0.275042)
							(end 0.2032 -0.3048)
						)
						(arc
							(start -0.2032 -0.3048)
							(mid -0.275042 -0.275042)
							(end -0.3048 -0.2032)
						)
						(arc
							(start -0.3048 0.2032)
							(mid -0.275042 0.275042)
							(end -0.2032 0.3048)
						)
						(arc
							(start 0.2032 0.3048)
							(mid 0.275042 0.275042)
							(end 0.3048 0.2032)
						)
					)
					(width 0)
					(fill yes)
				)
			)
		)
	)
	(footprint ""
		(layer "F.Cu")
		(at 19.176746 -466.7377 -90)
		(property "Reference" "R240"
			(at 0 0 270)
			(layer "F.SilkS")
			(hide yes)
			(effects
				(font
					(size 1.27 1.27)
				)
			)
		)
		(property "Value" "10KR2F-2-GP"
			(at 0.064008 -3.993896 270)
			(unlocked yes)
			(layer "F.Fab")
			(hide yes)
			(effects
				(font
					(size 1.016 1.016)
					(thickness 0.1524)
				)
			)
		)
		(property "Device Type" "R402H16"
			(at 0.064008 -5.517896 270)
			(unlocked yes)
			(layer "F.Fab")
			(hide yes)
			(effects
				(font
					(size 1.016 1.016)
					(thickness 0.1524)
				)
			)
		)
		(duplicate_pad_numbers_are_jumpers no)
		(fp_line
			(start -0.508 -0.9398)
			(end -0.508 0.9398)
			(stroke
				(width 0.1524)
				(type default)
			)
			(layer "F.SilkS")
		)
		(fp_line
			(start 0.508 -0.9398)
			(end -0.508 -0.9398)
			(stroke
				(width 0.1524)
				(type default)
			)
			(layer "F.SilkS")
		)
		(fp_rect
			(start -0.508 0.9398)
			(end 0.508 -0.9398)
			(stroke
				(width 0)
				(type default)
			)
			(fill no)
			(layer "F.CrtYd")
		)
		(fp_rect
			(start -0.508 0.9398)
			(end 0.508 -0.9398)
			(stroke
				(width 0)
				(type default)
			)
			(fill no)
			(layer "F.Fab")
		)
		(pad "1" smd custom
			(at 0 -0.4445 270)
			(size 0.1397 0.1397)
			(layers "F.Cu" "F.Mask" "F.Paste")
			(net "P5VC")
			(options
				(clearance outline)
				(anchor circle)
			)
			(primitives
				(gr_poly
					(pts
						(arc
							(start -0.1778 -0.2794)
							(mid -0.249642 -0.249642)
							(end -0.2794 -0.1778)
						)
						(arc
							(start -0.2794 0.1778)
							(mid -0.249642 0.249642)
							(end -0.1778 0.2794)
						)
						(arc
							(start 0.1778 0.2794)
							(mid 0.249642 0.249642)
							(end 0.2794 0.1778)
						)
						(arc
							(start 0.2794 -0.1778)
							(mid 0.249642 -0.249642)
							(end 0.1778 -0.2794)
						)
					)
					(width 0)
					(fill yes)
				)
			)
		)
		(pad "2" smd custom
			(at 0 0.4445 270)
			(size 0.1397 0.1397)
			(layers "F.Cu" "F.Mask" "F.Paste")
			(net "DRIVE_ACT_10")
			(options
				(clearance outline)
				(anchor circle)
			)
			(primitives
				(gr_poly
					(pts
						(arc
							(start -0.1778 -0.2794)
							(mid -0.249642 -0.249642)
							(end -0.2794 -0.1778)
						)
						(arc
							(start -0.2794 0.1778)
							(mid -0.249642 0.249642)
							(end -0.1778 0.2794)
						)
						(arc
							(start 0.1778 0.2794)
							(mid 0.249642 0.249642)
							(end 0.2794 0.1778)
						)
						(arc
							(start 0.2794 -0.1778)
							(mid 0.249642 -0.249642)
							(end 0.1778 -0.2794)
						)
					)
					(width 0)
					(fill yes)
				)
			)
		)
	)
	(footprint ""
		(layer "F.Cu")
		(at 190.930784 -185.390028 -90)
		(property "Reference" "R155"
			(at 0 0 270)
			(layer "F.SilkS")
			(hide yes)
			(effects
				(font
					(size 1.27 1.27)
				)
			)
		)
		(property "Value" "0R2J-2-GP"
			(at 0.064008 -3.993896 270)
			(unlocked yes)
			(layer "F.Fab")
			(hide yes)
			(effects
				(font
					(size 1.016 1.016)
					(thickness 0.1524)
				)
			)
		)
		(property "Device Type" "R402H16"
			(at 0.064008 -5.517896 270)
			(unlocked yes)
			(layer "F.Fab")
			(hide yes)
			(effects
				(font
					(size 1.016 1.016)
					(thickness 0.1524)
				)
			)
		)
		(duplicate_pad_numbers_are_jumpers no)
		(fp_line
			(start -0.508 -0.9398)
			(end -0.508 0.9398)
			(stroke
				(width 0.1524)
				(type default)
			)
			(layer "F.SilkS")
		)
		(fp_line
			(start 0.508 -0.9398)
			(end -0.508 -0.9398)
			(stroke
				(width 0.1524)
				(type default)
			)
			(layer "F.SilkS")
		)
		(fp_rect
			(start -0.508 0.9398)
			(end 0.508 -0.9398)
			(stroke
				(width 0)
				(type default)
			)
			(fill no)
			(layer "F.CrtYd")
		)
		(fp_rect
			(start -0.508 0.9398)
			(end 0.508 -0.9398)
			(stroke
				(width 0)
				(type default)
			)
			(fill no)
			(layer "F.Fab")
		)
		(pad "1" smd custom
			(at 0 -0.4445 270)
			(size 0.1397 0.1397)
			(layers "F.Cu" "F.Mask" "F.Paste")
			(net "DRIVE_PWR3")
			(options
				(clearance outline)
				(anchor circle)
			)
			(primitives
				(gr_poly
					(pts
						(arc
							(start -0.1778 -0.2794)
							(mid -0.249642 -0.249642)
							(end -0.2794 -0.1778)
						)
						(arc
							(start -0.2794 0.1778)
							(mid -0.249642 0.249642)
							(end -0.1778 0.2794)
						)
						(arc
							(start 0.1778 0.2794)
							(mid 0.249642 0.249642)
							(end 0.2794 0.1778)
						)
						(arc
							(start 0.2794 -0.1778)
							(mid 0.249642 -0.249642)
							(end 0.1778 -0.2794)
						)
					)
					(width 0)
					(fill yes)
				)
			)
		)
		(pad "2" smd custom
			(at 0 0.4445 270)
			(size 0.1397 0.1397)
			(layers "F.Cu" "F.Mask" "F.Paste")
			(net "SW_PWR_HDD3")
			(options
				(clearance outline)
				(anchor circle)
			)
			(primitives
				(gr_poly
					(pts
						(arc
							(start -0.1778 -0.2794)
							(mid -0.249642 -0.249642)
							(end -0.2794 -0.1778)
						)
						(arc
							(start -0.2794 0.1778)
							(mid -0.249642 0.249642)
							(end -0.1778 0.2794)
						)
						(arc
							(start 0.1778 0.2794)
							(mid 0.249642 0.249642)
							(end 0.2794 0.1778)
						)
						(arc
							(start 0.2794 -0.1778)
							(mid 0.249642 -0.249642)
							(end 0.1778 -0.2794)
						)
					)
					(width 0)
					(fill yes)
				)
			)
		)
	)
	(footprint ""
		(layer "F.Cu")
		(at 212.724746 -479.6917 180)
		(property "Reference" "Q49"
			(at 0 0 180)
			(layer "F.SilkS")
			(hide yes)
			(effects
				(font
					(size 1.27 1.27)
				)
			)
		)
		(property "Value" "2N7002-11-GP"
			(at 0.127 -8.9662 180)
			(unlocked yes)
			(layer "F.Fab")
			(hide yes)
			(effects
				(font
					(size 1.016 1.016)
					(thickness 0.1524)
				)
			)
		)
		(property "Device Type" "SOT23DGS2D4H44"
			(at 0.127 -10.4902 180)
			(unlocked yes)
			(layer "F.Fab")
			(hide yes)
			(effects
				(font
					(size 1.016 1.016)
					(thickness 0.1524)
				)
			)
		)
		(duplicate_pad_numbers_are_jumpers no)
		(fp_line
			(start 1.651 1.778)
			(end 1.651 -1.778)
			(stroke
				(width 0.1524)
				(type default)
			)
			(layer "F.SilkS")
		)
		(fp_line
			(start 1.651 -1.778)
			(end -1.651 -1.778)
			(stroke
				(width 0.1524)
				(type default)
			)
			(layer "F.SilkS")
		)
		(fp_line
			(start -1.651 1.778)
			(end 1.651 1.778)
			(stroke
				(width 0.1524)
				(type default)
			)
			(layer "F.SilkS")
		)
		(fp_line
			(start -1.651 -1.778)
			(end -1.651 1.778)
			(stroke
				(width 0.1524)
				(type default)
			)
			(layer "F.SilkS")
		)
		(fp_poly
			(pts
				(xy -1.778 1.8796) (xy -1.778 -1.8796) (xy 1.778 -1.8796) (xy 1.778 1.8796)
			)
			(stroke
				(width 0)
				(type default)
			)
			(fill no)
			(layer "F.CrtYd")
		)
		(fp_poly
			(pts
				(xy -1.778 1.8796) (xy -1.778 -1.8796) (xy 1.778 -1.8796) (xy 1.778 1.8796)
			)
			(stroke
				(width 0)
				(type default)
			)
			(fill no)
			(layer "F.Fab")
		)
		(pad "D" smd custom
			(at 0 -0.9525 180)
			(size 0.1905 0.1905)
			(layers "F.Cu" "F.Mask" "F.Paste")
			(net "HDD0_LED_G")
			(options
				(clearance outline)
				(anchor circle)
			)
			(primitives
				(gr_poly
					(pts
						(arc
							(start -0.1778 0.5715)
							(mid -0.321484 0.511984)
							(end -0.381 0.3683)
						)
						(arc
							(start -0.381 -0.3683)
							(mid -0.321484 -0.511984)
							(end -0.1778 -0.5715)
						)
						(arc
							(start 0.1778 -0.5715)
							(mid 0.321484 -0.511984)
							(end 0.381 -0.3683)
						)
						(arc
							(start 0.381 0.3683)
							(mid 0.321484 0.511984)
							(end 0.1778 0.5715)
						)
					)
					(width 0)
					(fill yes)
				)
			)
		)
		(pad "G" smd custom
			(at -0.98425 0.9525 180)
			(size 0.1905 0.1905)
			(layers "F.Cu" "F.Mask" "F.Paste")
			(net "HDD0_LED_B")
			(options
				(clearance outline)
				(anchor circle)
			)
			(primitives
				(gr_poly
					(pts
						(arc
							(start -0.1778 0.5715)
							(mid -0.321484 0.511984)
							(end -0.381 0.3683)
						)
						(arc
							(start -0.381 -0.3683)
							(mid -0.321484 -0.511984)
							(end -0.1778 -0.5715)
						)
						(arc
							(start 0.1778 -0.5715)
							(mid 0.321484 -0.511984)
							(end 0.381 -0.3683)
						)
						(arc
							(start 0.381 0.3683)
							(mid 0.321484 0.511984)
							(end 0.1778 0.5715)
						)
					)
					(width 0)
					(fill yes)
				)
			)
		)
		(pad "S" smd custom
			(at 0.98425 0.9525 180)
			(size 0.1905 0.1905)
			(layers "F.Cu" "F.Mask" "F.Paste")
			(net "GND")
			(options
				(clearance outline)
				(anchor circle)
			)
			(primitives
				(gr_poly
					(pts
						(arc
							(start -0.1778 0.5715)
							(mid -0.321484 0.511984)
							(end -0.381 0.3683)
						)
						(arc
							(start -0.381 -0.3683)
							(mid -0.321484 -0.511984)
							(end -0.1778 -0.5715)
						)
						(arc
							(start 0.1778 -0.5715)
							(mid 0.321484 -0.511984)
							(end 0.381 -0.3683)
						)
						(arc
							(start 0.381 0.3683)
							(mid 0.321484 0.511984)
							(end 0.1778 0.5715)
						)
					)
					(width 0)
					(fill yes)
				)
			)
		)
	)
	(footprint ""
		(layer "F.Cu")
		(at 187.464446 -456.853036 90)
		(property "Reference" "R347"
			(at 0 0 90)
			(layer "F.SilkS")
			(hide yes)
			(effects
				(font
					(size 1.27 1.27)
				)
			)
		)
		(property "Value" "4K7R2J-2-GP"
			(at 0.064008 -3.993896 90)
			(unlocked yes)
			(layer "F.Fab")
			(hide yes)
			(effects
				(font
					(size 1.016 1.016)
					(thickness 0.1524)
				)
			)
		)
		(property "Device Type" "R402H16"
			(at 0.064008 -5.517896 90)
			(unlocked yes)
			(layer "F.Fab")
			(hide yes)
			(effects
				(font
					(size 1.016 1.016)
					(thickness 0.1524)
				)
			)
		)
		(duplicate_pad_numbers_are_jumpers no)
		(fp_line
			(start 0.508 -0.9398)
			(end -0.508 -0.9398)
			(stroke
				(width 0.1524)
				(type default)
			)
			(layer "F.SilkS")
		)
		(fp_line
			(start -0.508 -0.9398)
			(end -0.508 0.9398)
			(stroke
				(width 0.1524)
				(type default)
			)
			(layer "F.SilkS")
		)
		(fp_rect
			(start -0.508 0.9398)
			(end 0.508 -0.9398)
			(stroke
				(width 0)
				(type default)
			)
			(fill no)
			(layer "F.CrtYd")
		)
		(fp_rect
			(start -0.508 0.9398)
			(end 0.508 -0.9398)
			(stroke
				(width 0)
				(type default)
			)
			(fill no)
			(layer "F.Fab")
		)
		(pad "1" smd custom
			(at 0 -0.4445 90)
			(size 0.1397 0.1397)
			(layers "F.Cu" "F.Mask" "F.Paste")
			(net "P3V3")
			(options
				(clearance outline)
				(anchor circle)
			)
			(primitives
				(gr_poly
					(pts
						(arc
							(start -0.1778 -0.2794)
							(mid -0.249642 -0.249642)
							(end -0.2794 -0.1778)
						)
						(arc
							(start -0.2794 0.1778)
							(mid -0.249642 0.249642)
							(end -0.1778 0.2794)
						)
						(arc
							(start 0.1778 0.2794)
							(mid 0.249642 0.249642)
							(end 0.2794 0.1778)
						)
						(arc
							(start 0.2794 -0.1778)
							(mid 0.249642 -0.249642)
							(end 0.1778 -0.2794)
						)
					)
					(width 0)
					(fill yes)
				)
			)
		)
		(pad "2" smd custom
			(at 0 0.4445 90)
			(size 0.1397 0.1397)
			(layers "F.Cu" "F.Mask" "F.Paste")
			(net "EEPROM_A2")
			(options
				(clearance outline)
				(anchor circle)
			)
			(primitives
				(gr_poly
					(pts
						(arc
							(start -0.1778 -0.2794)
							(mid -0.249642 -0.249642)
							(end -0.2794 -0.1778)
						)
						(arc
							(start -0.2794 0.1778)
							(mid -0.249642 0.249642)
							(end -0.1778 0.2794)
						)
						(arc
							(start 0.1778 0.2794)
							(mid 0.249642 0.249642)
							(end 0.2794 0.1778)
						)
						(arc
							(start 0.2794 -0.1778)
							(mid 0.249642 -0.249642)
							(end 0.1778 -0.2794)
						)
					)
					(width 0)
					(fill yes)
				)
			)
		)
	)
	(footprint ""
		(layer "F.Cu")
		(at 57.864756 -481.104702)
		(property "Reference" "R177"
			(at 0 0 0)
			(layer "F.SilkS")
			(hide yes)
			(effects
				(font
					(size 1.27 1.27)
				)
			)
		)
		(property "Value" "220R3F-1-GP"
			(at -0.0254 -2.5146 0)
			(unlocked yes)
			(layer "F.Fab")
			(hide yes)
			(effects
				(font
					(size 1.016 1.016)
					(thickness 0.1524)
				)
			)
		)
		(property "Device Type" "R603H22"
			(at -0.0254 -4.0386 0)
			(unlocked yes)
			(layer "F.Fab")
			(hide yes)
			(effects
				(font
					(size 1.016 1.016)
					(thickness 0.1524)
				)
			)
		)
		(duplicate_pad_numbers_are_jumpers no)
		(fp_line
			(start -0.4826 0)
			(end -0.2032 0)
			(stroke
				(width 0.2032)
				(type default)
			)
			(layer "F.SilkS")
		)
		(fp_line
			(start 0.2032 0)
			(end 0.4826 0)
			(stroke
				(width 0.2032)
				(type default)
			)
			(layer "F.SilkS")
		)
		(fp_rect
			(start -0.5842 1.3335)
			(end 0.5842 -1.3335)
			(stroke
				(width 0)
				(type default)
			)
			(fill no)
			(layer "F.CrtYd")
		)
		(fp_rect
			(start -0.5842 1.3335)
			(end 0.5842 -1.3335)
			(stroke
				(width 0)
				(type default)
			)
			(fill no)
			(layer "F.Fab")
		)
		(pad "1" smd custom
			(at 0 -0.762)
			(size 0.2159 0.2159)
			(layers "F.Cu" "F.Mask" "F.Paste")
			(net "HDD_PRSNT_NET5")
			(options
				(clearance outline)
				(anchor circle)
			)
			(primitives
				(gr_poly
					(pts
						(arc
							(start -0.3302 -0.4318)
							(mid -0.402042 -0.402042)
							(end -0.4318 -0.3302)
						)
						(arc
							(start -0.4318 0.3302)
							(mid -0.402042 0.402042)
							(end -0.3302 0.4318)
						)
						(arc
							(start 0.3302 0.4318)
							(mid 0.402042 0.402042)
							(end 0.4318 0.3302)
						)
						(arc
							(start 0.4318 -0.3302)
							(mid 0.402042 -0.402042)
							(end 0.3302 -0.4318)
						)
					)
					(width 0)
					(fill yes)
				)
			)
		)
		(pad "2" smd custom
			(at 0 0.762)
			(size 0.2159 0.2159)
			(layers "F.Cu" "F.Mask" "F.Paste")
			(net "HDD_PRSNT5")
			(options
				(clearance outline)
				(anchor circle)
			)
			(primitives
				(gr_poly
					(pts
						(arc
							(start -0.3302 -0.4318)
							(mid -0.402042 -0.402042)
							(end -0.4318 -0.3302)
						)
						(arc
							(start -0.4318 0.3302)
							(mid -0.402042 0.402042)
							(end -0.3302 0.4318)
						)
						(arc
							(start 0.3302 0.4318)
							(mid 0.402042 0.402042)
							(end 0.4318 0.3302)
						)
						(arc
							(start 0.4318 -0.3302)
							(mid 0.402042 -0.402042)
							(end 0.3302 -0.4318)
						)
					)
					(width 0)
					(fill yes)
				)
			)
		)
	)
	(footprint ""
		(layer "F.Cu")
		(at 17.500092 -52.839874)
		(property "Reference" "LED15"
			(at 0 0 0)
			(layer "F.SilkS")
			(hide yes)
			(effects
				(font
					(size 1.27 1.27)
				)
			)
		)
		(property "Value" "LED-RB-4-GP"
			(at 5.88899 1.80848 0)
			(unlocked yes)
			(layer "F.Fab")
			(hide yes)
			(effects
				(font
					(size 1.016 1.016)
					(thickness 0.1524)
				)
			)
		)
		(property "Device Type" "LED1613-4PH20"
			(at 5.88899 0.28448 0)
			(unlocked yes)
			(layer "F.Fab")
			(hide yes)
			(effects
				(font
					(size 1.016 1.016)
					(thickness 0.1524)
				)
			)
		)
		(duplicate_pad_numbers_are_jumpers no)
		(fp_line
			(start -1.4478 -0.9652)
			(end 1.4478 -0.9652)
			(stroke
				(width 0.1524)
				(type default)
			)
			(layer "F.SilkS")
		)
		(fp_line
			(start -1.4478 0.9652)
			(end -1.4478 -0.9652)
			(stroke
				(width 0.1524)
				(type default)
			)
			(layer "F.SilkS")
		)
		(fp_line
			(start -1.4478 0.9652)
			(end -1.4478 -0.9652)
			(stroke
				(width 0.508)
				(type default)
			)
			(layer "F.SilkS")
		)
		(fp_line
			(start 1.4478 -0.9652)
			(end 1.4478 0.9652)
			(stroke
				(width 0.1524)
				(type default)
			)
			(layer "F.SilkS")
		)
		(fp_line
			(start 1.4478 0.9652)
			(end -1.4478 0.9652)
			(stroke
				(width 0.1524)
				(type default)
			)
			(layer "F.SilkS")
		)
		(fp_rect
			(start -0.8001 0.6477)
			(end 0.8001 -0.6477)
			(stroke
				(width 0)
				(type default)
			)
			(fill no)
			(layer "F.CrtYd")
		)
		(fp_poly
			(pts
				(xy -1.7018 1.2192) (xy -1.7018 -0.06223) (xy -0.8001 -0.06223) (xy -0.8001 0.6477) (xy 0.8001 0.6477)
				(xy 0.8001 -0.6477) (xy -0.8001 -0.6477) (xy -0.8001 -0.0635) (xy -1.7018 -0.0635) (xy -1.7018 -1.2192)
				(xy 1.7018 -1.2192) (xy 1.7018 1.2192)
			)
			(stroke
				(width 0)
				(type default)
			)
			(fill no)
			(layer "F.CrtYd")
		)
		(fp_rect
			(start -1.7018 1.2192)
			(end 1.7018 -1.2192)
			(stroke
				(width 0)
				(type default)
			)
			(fill no)
			(layer "F.Fab")
		)
		(pad "1" smd rect
			(at -0.73025 0.4064)
			(size 0.9144 0.6096)
			(layers "F.Cu" "F.Mask" "F.Paste")
			(net "DRV_ACT_NET14")
		)
		(pad "2" smd rect
			(at -0.73025 -0.4064)
			(size 0.9144 0.6096)
			(layers "F.Cu" "F.Mask" "F.Paste")
			(net "FLT_NET_HDD14")
		)
		(pad "3" smd rect
			(at 0.73025 -0.4064)
			(size 0.9144 0.6096)
			(layers "F.Cu" "F.Mask" "F.Paste")
			(net "FLT_HDD14")
		)
		(pad "4" smd rect
			(at 0.73025 0.4064)
			(size 0.9144 0.6096)
			(layers "F.Cu" "F.Mask" "F.Paste")
			(net "DRV_ACT_14")
		)
	)
	(footprint ""
		(layer "F.Cu")
		(at 6.095746 -499.5037 180)
		(property "Reference" "PR34"
			(at 0 0 180)
			(layer "F.SilkS")
			(hide yes)
			(effects
				(font
					(size 1.27 1.27)
				)
			)
		)
		(property "Value" "0R2J-2-GP"
			(at 0.064008 -3.993896 180)
			(unlocked yes)
			(layer "F.Fab")
			(hide yes)
			(effects
				(font
					(size 1.016 1.016)
					(thickness 0.1524)
				)
			)
		)
		(property "Device Type" "R402H16"
			(at 0.064008 -5.517896 180)
			(unlocked yes)
			(layer "F.Fab")
			(hide yes)
			(effects
				(font
					(size 1.016 1.016)
					(thickness 0.1524)
				)
			)
		)
		(duplicate_pad_numbers_are_jumpers no)
		(fp_line
			(start 0.508 -0.9398)
			(end -0.508 -0.9398)
			(stroke
				(width 0.1524)
				(type default)
			)
			(layer "F.SilkS")
		)
		(fp_line
			(start -0.508 -0.9398)
			(end -0.508 0.9398)
			(stroke
				(width 0.1524)
				(type default)
			)
			(layer "F.SilkS")
		)
		(fp_rect
			(start -0.508 0.9398)
			(end 0.508 -0.9398)
			(stroke
				(width 0)
				(type default)
			)
			(fill no)
			(layer "F.CrtYd")
		)
		(fp_rect
			(start -0.508 0.9398)
			(end 0.508 -0.9398)
			(stroke
				(width 0)
				(type default)
			)
			(fill no)
			(layer "F.Fab")
		)
		(pad "1" smd custom
			(at 0 -0.4445 180)
			(size 0.1397 0.1397)
			(layers "F.Cu" "F.Mask" "F.Paste")
			(net "P5VC_RF")
			(options
				(clearance outline)
				(anchor circle)
			)
			(primitives
				(gr_poly
					(pts
						(arc
							(start -0.1778 -0.2794)
							(mid -0.249642 -0.249642)
							(end -0.2794 -0.1778)
						)
						(arc
							(start -0.2794 0.1778)
							(mid -0.249642 0.249642)
							(end -0.1778 0.2794)
						)
						(arc
							(start 0.1778 0.2794)
							(mid 0.249642 0.249642)
							(end 0.2794 0.1778)
						)
						(arc
							(start 0.2794 -0.1778)
							(mid 0.249642 -0.249642)
							(end 0.1778 -0.2794)
						)
					)
					(width 0)
					(fill yes)
				)
			)
		)
		(pad "2" smd custom
			(at 0 0.4445 180)
			(size 0.1397 0.1397)
			(layers "F.Cu" "F.Mask" "F.Paste")
			(net "P5VC_AGND")
			(options
				(clearance outline)
				(anchor circle)
			)
			(primitives
				(gr_poly
					(pts
						(arc
							(start -0.1778 -0.2794)
							(mid -0.249642 -0.249642)
							(end -0.2794 -0.1778)
						)
						(arc
							(start -0.2794 0.1778)
							(mid -0.249642 0.249642)
							(end -0.1778 0.2794)
						)
						(arc
							(start 0.1778 0.2794)
							(mid 0.249642 0.249642)
							(end 0.2794 0.1778)
						)
						(arc
							(start 0.2794 -0.1778)
							(mid 0.249642 -0.249642)
							(end 0.1778 -0.2794)
						)
					)
					(width 0)
					(fill yes)
				)
			)
		)
	)
	(footprint ""
		(layer "F.Cu")
		(at 211.708746 -452.6407 180)
		(property "Reference" "R327"
			(at 0 0 180)
			(layer "F.SilkS")
			(hide yes)
			(effects
				(font
					(size 1.27 1.27)
				)
			)
		)
		(property "Value" "4K7R2J-2-GP"
			(at 0.064008 -3.993896 180)
			(unlocked yes)
			(layer "F.Fab")
			(hide yes)
			(effects
				(font
					(size 1.016 1.016)
					(thickness 0.1524)
				)
			)
		)
		(property "Device Type" "R402H16"
			(at 0.064008 -5.517896 180)
			(unlocked yes)
			(layer "F.Fab")
			(hide yes)
			(effects
				(font
					(size 1.016 1.016)
					(thickness 0.1524)
				)
			)
		)
		(duplicate_pad_numbers_are_jumpers no)
		(fp_line
			(start 0.508 -0.9398)
			(end -0.508 -0.9398)
			(stroke
				(width 0.1524)
				(type default)
			)
			(layer "F.SilkS")
		)
		(fp_line
			(start -0.508 -0.9398)
			(end -0.508 0.9398)
			(stroke
				(width 0.1524)
				(type default)
			)
			(layer "F.SilkS")
		)
		(fp_rect
			(start -0.508 0.9398)
			(end 0.508 -0.9398)
			(stroke
				(width 0)
				(type default)
			)
			(fill no)
			(layer "F.CrtYd")
		)
		(fp_rect
			(start -0.508 0.9398)
			(end 0.508 -0.9398)
			(stroke
				(width 0)
				(type default)
			)
			(fill no)
			(layer "F.Fab")
		)
		(pad "1" smd custom
			(at 0 -0.4445 180)
			(size 0.1397 0.1397)
			(layers "F.Cu" "F.Mask" "F.Paste")
			(net "P3V3")
			(options
				(clearance outline)
				(anchor circle)
			)
			(primitives
				(gr_poly
					(pts
						(arc
							(start -0.1778 -0.2794)
							(mid -0.249642 -0.249642)
							(end -0.2794 -0.1778)
						)
						(arc
							(start -0.2794 0.1778)
							(mid -0.249642 0.249642)
							(end -0.1778 0.2794)
						)
						(arc
							(start 0.1778 0.2794)
							(mid 0.249642 0.249642)
							(end 0.2794 0.1778)
						)
						(arc
							(start 0.2794 -0.1778)
							(mid 0.249642 -0.249642)
							(end 0.1778 -0.2794)
						)
					)
					(width 0)
					(fill yes)
				)
			)
		)
		(pad "2" smd custom
			(at 0 0.4445 180)
			(size 0.1397 0.1397)
			(layers "F.Cu" "F.Mask" "F.Paste")
			(net "I2C_B_TMP3_A0")
			(options
				(clearance outline)
				(anchor circle)
			)
			(primitives
				(gr_poly
					(pts
						(arc
							(start -0.1778 -0.2794)
							(mid -0.249642 -0.249642)
							(end -0.2794 -0.1778)
						)
						(arc
							(start -0.2794 0.1778)
							(mid -0.249642 0.249642)
							(end -0.1778 0.2794)
						)
						(arc
							(start 0.1778 0.2794)
							(mid 0.249642 0.249642)
							(end 0.2794 0.1778)
						)
						(arc
							(start 0.2794 -0.1778)
							(mid 0.249642 -0.249642)
							(end 0.1778 -0.2794)
						)
					)
					(width 0)
					(fill yes)
				)
			)
		)
	)
	(footprint ""
		(layer "F.Cu")
		(at 191.853058 -390.219184 -90)
		(property "Reference" "R127"
			(at 0 0 270)
			(layer "F.SilkS")
			(hide yes)
			(effects
				(font
					(size 1.27 1.27)
				)
			)
		)
		(property "Value" "0R2J-2-GP"
			(at 0.064008 -3.993896 270)
			(unlocked yes)
			(layer "F.Fab")
			(hide yes)
			(effects
				(font
					(size 1.016 1.016)
					(thickness 0.1524)
				)
			)
		)
		(property "Device Type" "R402H16"
			(at 0.064008 -5.517896 270)
			(unlocked yes)
			(layer "F.Fab")
			(hide yes)
			(effects
				(font
					(size 1.016 1.016)
					(thickness 0.1524)
				)
			)
		)
		(duplicate_pad_numbers_are_jumpers no)
		(fp_line
			(start -0.508 -0.9398)
			(end -0.508 0.9398)
			(stroke
				(width 0.1524)
				(type default)
			)
			(layer "F.SilkS")
		)
		(fp_line
			(start 0.508 -0.9398)
			(end -0.508 -0.9398)
			(stroke
				(width 0.1524)
				(type default)
			)
			(layer "F.SilkS")
		)
		(fp_rect
			(start -0.508 0.9398)
			(end 0.508 -0.9398)
			(stroke
				(width 0)
				(type default)
			)
			(fill no)
			(layer "F.CrtYd")
		)
		(fp_rect
			(start -0.508 0.9398)
			(end 0.508 -0.9398)
			(stroke
				(width 0)
				(type default)
			)
			(fill no)
			(layer "F.Fab")
		)
		(pad "1" smd custom
			(at 0 -0.4445 270)
			(size 0.1397 0.1397)
			(layers "F.Cu" "F.Mask" "F.Paste")
			(net "DRIVE_PWR1")
			(options
				(clearance outline)
				(anchor circle)
			)
			(primitives
				(gr_poly
					(pts
						(arc
							(start -0.1778 -0.2794)
							(mid -0.249642 -0.249642)
							(end -0.2794 -0.1778)
						)
						(arc
							(start -0.2794 0.1778)
							(mid -0.249642 0.249642)
							(end -0.1778 0.2794)
						)
						(arc
							(start 0.1778 0.2794)
							(mid 0.249642 0.249642)
							(end 0.2794 0.1778)
						)
						(arc
							(start 0.2794 -0.1778)
							(mid 0.249642 -0.249642)
							(end 0.1778 -0.2794)
						)
					)
					(width 0)
					(fill yes)
				)
			)
		)
		(pad "2" smd custom
			(at 0 0.4445 270)
			(size 0.1397 0.1397)
			(layers "F.Cu" "F.Mask" "F.Paste")
			(net "SW_PWR_HDD1")
			(options
				(clearance outline)
				(anchor circle)
			)
			(primitives
				(gr_poly
					(pts
						(arc
							(start -0.1778 -0.2794)
							(mid -0.249642 -0.249642)
							(end -0.2794 -0.1778)
						)
						(arc
							(start -0.2794 0.1778)
							(mid -0.249642 0.249642)
							(end -0.1778 0.2794)
						)
						(arc
							(start 0.1778 0.2794)
							(mid 0.249642 0.249642)
							(end 0.2794 0.1778)
						)
						(arc
							(start 0.2794 -0.1778)
							(mid 0.249642 -0.249642)
							(end 0.1778 -0.2794)
						)
					)
					(width 0)
					(fill yes)
				)
			)
		)
	)
	(footprint ""
		(layer "F.Cu")
		(at 39.750746 -41.9227 90)
		(property "Reference" "R227"
			(at 0 0 90)
			(layer "F.SilkS")
			(hide yes)
			(effects
				(font
					(size 1.27 1.27)
				)
			)
		)
		(property "Value" "402R2F-GP"
			(at 0.064008 -3.993896 90)
			(unlocked yes)
			(layer "F.Fab")
			(hide yes)
			(effects
				(font
					(size 1.016 1.016)
					(thickness 0.1524)
				)
			)
		)
		(property "Device Type" "R402H16"
			(at 0.064008 -5.517896 90)
			(unlocked yes)
			(layer "F.Fab")
			(hide yes)
			(effects
				(font
					(size 1.016 1.016)
					(thickness 0.1524)
				)
			)
		)
		(duplicate_pad_numbers_are_jumpers no)
		(fp_line
			(start 0.508 -0.9398)
			(end -0.508 -0.9398)
			(stroke
				(width 0.1524)
				(type default)
			)
			(layer "F.SilkS")
		)
		(fp_line
			(start -0.508 -0.9398)
			(end -0.508 0.9398)
			(stroke
				(width 0.1524)
				(type default)
			)
			(layer "F.SilkS")
		)
		(fp_rect
			(start -0.508 0.9398)
			(end 0.508 -0.9398)
			(stroke
				(width 0)
				(type default)
			)
			(fill no)
			(layer "F.CrtYd")
		)
		(fp_rect
			(start -0.508 0.9398)
			(end 0.508 -0.9398)
			(stroke
				(width 0)
				(type default)
			)
			(fill no)
			(layer "F.Fab")
		)
		(pad "1" smd custom
			(at 0 -0.4445 90)
			(size 0.1397 0.1397)
			(layers "F.Cu" "F.Mask" "F.Paste")
			(net "P5VB_HDD9_LED")
			(options
				(clearance outline)
				(anchor circle)
			)
			(primitives
				(gr_poly
					(pts
						(arc
							(start -0.1778 -0.2794)
							(mid -0.249642 -0.249642)
							(end -0.2794 -0.1778)
						)
						(arc
							(start -0.2794 0.1778)
							(mid -0.249642 0.249642)
							(end -0.1778 0.2794)
						)
						(arc
							(start 0.1778 0.2794)
							(mid 0.249642 0.249642)
							(end 0.2794 0.1778)
						)
						(arc
							(start 0.2794 -0.1778)
							(mid 0.249642 -0.249642)
							(end 0.1778 -0.2794)
						)
					)
					(width 0)
					(fill yes)
				)
			)
		)
		(pad "2" smd custom
			(at 0 0.4445 90)
			(size 0.1397 0.1397)
			(layers "F.Cu" "F.Mask" "F.Paste")
			(net "DRV_ACT_9")
			(options
				(clearance outline)
				(anchor circle)
			)
			(primitives
				(gr_poly
					(pts
						(arc
							(start -0.1778 -0.2794)
							(mid -0.249642 -0.249642)
							(end -0.2794 -0.1778)
						)
						(arc
							(start -0.2794 0.1778)
							(mid -0.249642 0.249642)
							(end -0.1778 0.2794)
						)
						(arc
							(start 0.1778 0.2794)
							(mid 0.249642 0.249642)
							(end 0.2794 0.1778)
						)
						(arc
							(start 0.2794 -0.1778)
							(mid 0.249642 -0.249642)
							(end 0.1778 -0.2794)
						)
					)
					(width 0)
					(fill yes)
				)
			)
		)
	)
	(footprint ""
		(layer "F.Cu")
		(at 197.116446 -461.679036 90)
		(property "Reference" "R351"
			(at 0 0 90)
			(layer "F.SilkS")
			(hide yes)
			(effects
				(font
					(size 1.27 1.27)
				)
			)
		)
		(property "Value" "0R2J-2-GP"
			(at 0.064008 -3.993896 90)
			(unlocked yes)
			(layer "F.Fab")
			(hide yes)
			(effects
				(font
					(size 1.016 1.016)
					(thickness 0.1524)
				)
			)
		)
		(property "Device Type" "R402H16"
			(at 0.064008 -5.517896 90)
			(unlocked yes)
			(layer "F.Fab")
			(hide yes)
			(effects
				(font
					(size 1.016 1.016)
					(thickness 0.1524)
				)
			)
		)
		(duplicate_pad_numbers_are_jumpers no)
		(fp_line
			(start 0.508 -0.9398)
			(end -0.508 -0.9398)
			(stroke
				(width 0.1524)
				(type default)
			)
			(layer "F.SilkS")
		)
		(fp_line
			(start -0.508 -0.9398)
			(end -0.508 0.9398)
			(stroke
				(width 0.1524)
				(type default)
			)
			(layer "F.SilkS")
		)
		(fp_rect
			(start -0.508 0.9398)
			(end 0.508 -0.9398)
			(stroke
				(width 0)
				(type default)
			)
			(fill no)
			(layer "F.CrtYd")
		)
		(fp_rect
			(start -0.508 0.9398)
			(end 0.508 -0.9398)
			(stroke
				(width 0)
				(type default)
			)
			(fill no)
			(layer "F.Fab")
		)
		(pad "1" smd custom
			(at 0 -0.4445 90)
			(size 0.1397 0.1397)
			(layers "F.Cu" "F.Mask" "F.Paste")
			(net "EEPROM_WP")
			(options
				(clearance outline)
				(anchor circle)
			)
			(primitives
				(gr_poly
					(pts
						(arc
							(start -0.1778 -0.2794)
							(mid -0.249642 -0.249642)
							(end -0.2794 -0.1778)
						)
						(arc
							(start -0.2794 0.1778)
							(mid -0.249642 0.249642)
							(end -0.1778 0.2794)
						)
						(arc
							(start 0.1778 0.2794)
							(mid 0.249642 0.249642)
							(end 0.2794 0.1778)
						)
						(arc
							(start 0.2794 -0.1778)
							(mid 0.249642 -0.249642)
							(end 0.1778 -0.2794)
						)
					)
					(width 0)
					(fill yes)
				)
			)
		)
		(pad "2" smd custom
			(at 0 0.4445 90)
			(size 0.1397 0.1397)
			(layers "F.Cu" "F.Mask" "F.Paste")
			(net "GND")
			(options
				(clearance outline)
				(anchor circle)
			)
			(primitives
				(gr_poly
					(pts
						(arc
							(start -0.1778 -0.2794)
							(mid -0.249642 -0.249642)
							(end -0.2794 -0.1778)
						)
						(arc
							(start -0.2794 0.1778)
							(mid -0.249642 0.249642)
							(end -0.1778 0.2794)
						)
						(arc
							(start 0.1778 0.2794)
							(mid 0.249642 0.249642)
							(end 0.2794 0.1778)
						)
						(arc
							(start 0.2794 -0.1778)
							(mid 0.249642 -0.249642)
							(end 0.1778 -0.2794)
						)
					)
					(width 0)
					(fill yes)
				)
			)
		)
	)
	(footprint ""
		(layer "F.Cu")
		(at 42.600118 -137.510012 180)
		(property "Reference" "U47"
			(at 0 0 180)
			(layer "F.SilkS")
			(hide yes)
			(effects
				(font
					(size 1.27 1.27)
				)
			)
		)
		(property "Value" "TMP75AIDGKR-GP"
			(at -0.1143 -9.1948 180)
			(unlocked yes)
			(layer "F.Fab")
			(hide yes)
			(effects
				(font
					(size 1.016 1.016)
					(thickness 0.1524)
				)
			)
		)
		(property "Device Type" "MSOP8-1H44"
			(at -0.1143 -10.795 180)
			(unlocked yes)
			(layer "F.Fab")
			(hide yes)
			(effects
				(font
					(size 1.016 1.016)
					(thickness 0.1524)
				)
			)
		)
		(duplicate_pad_numbers_are_jumpers no)
		(fp_line
			(start 1.0795 1.016)
			(end 1.0795 -1.016)
			(stroke
				(width 0.1524)
				(type default)
			)
			(layer "F.SilkS")
		)
		(fp_line
			(start 1.0795 -1.016)
			(end -1.9558 -1.016)
			(stroke
				(width 0.1524)
				(type default)
			)
			(layer "F.SilkS")
		)
		(fp_line
			(start -1.4478 -0.0381)
			(end -1.9558 0.4699)
			(stroke
				(width 0.1524)
				(type default)
			)
			(layer "F.SilkS")
		)
		(fp_line
			(start -1.778 1.0922)
			(end -1.778 3.048)
			(stroke
				(width 0.508)
				(type default)
			)
			(layer "F.SilkS")
		)
		(fp_line
			(start -1.9558 1.016)
			(end 1.0795 1.016)
			(stroke
				(width 0.1524)
				(type default)
			)
			(layer "F.SilkS")
		)
		(fp_line
			(start -1.9558 -0.5461)
			(end -1.4478 -0.0381)
			(stroke
				(width 0.1524)
				(type default)
			)
			(layer "F.SilkS")
		)
		(fp_line
			(start -1.9558 -1.016)
			(end -1.9558 1.016)
			(stroke
				(width 0.1524)
				(type default)
			)
			(layer "F.SilkS")
		)
		(fp_poly
			(pts
				(xy -1.1557 -1.016) (xy -1.1557 1.016) (xy 1.1557 1.016) (xy 1.1557 -1.016)
			)
			(stroke
				(width 0)
				(type default)
			)
			(fill yes)
			(layer "F.SilkS")
		)
		(fp_rect
			(start -1.4986 2.4511)
			(end 1.4986 -2.4511)
			(stroke
				(width 0)
				(type default)
			)
			(fill no)
			(layer "F.CrtYd")
		)
		(fp_poly
			(pts
				(xy -2.032 3.302) (xy -2.032 -3.302) (xy 2.032 -3.302) (xy 2.032 -2.1209) (xy 1.4986 -2.1209) (xy 1.4986 -2.4511)
				(xy -1.4986 -2.4511) (xy -1.4986 2.4511) (xy 1.4986 2.4511) (xy 1.4986 -2.1082) (xy 2.032 -2.1082)
				(xy 2.032 3.302)
			)
			(stroke
				(width 0)
				(type default)
			)
			(fill no)
			(layer "F.CrtYd")
		)
		(fp_rect
			(start -2.032 3.302)
			(end 2.032 -3.302)
			(stroke
				(width 0)
				(type default)
			)
			(fill no)
			(layer "F.Fab")
		)
		(pad "1" smd rect
			(at -0.97536 2.05486 180)
			(size 0.3556 1.524)
			(layers "F.Cu" "F.Mask" "F.Paste")
			(net "TMP2_SDA")
		)
		(pad "2" smd rect
			(at -0.32512 2.05486 180)
			(size 0.3556 1.524)
			(layers "F.Cu" "F.Mask" "F.Paste")
			(net "TMP2_SCL")
		)
		(pad "3" smd rect
			(at 0.32512 2.05486 180)
			(size 0.3556 1.524)
			(layers "F.Cu" "F.Mask" "F.Paste")
			(net "I2C_B_TMP2_ALERT")
		)
		(pad "4" smd rect
			(at 0.97536 2.05486 180)
			(size 0.3556 1.524)
			(layers "F.Cu" "F.Mask" "F.Paste")
			(net "GND")
		)
		(pad "5" smd rect
			(at 0.97536 -2.05486 180)
			(size 0.3556 1.524)
			(layers "F.Cu" "F.Mask" "F.Paste")
			(net "I2C_B_TMP2_A2")
		)
		(pad "6" smd rect
			(at 0.32512 -2.05486 180)
			(size 0.3556 1.524)
			(layers "F.Cu" "F.Mask" "F.Paste")
			(net "I2C_B_TMP2_A1")
		)
		(pad "7" smd rect
			(at -0.32512 -2.05486 180)
			(size 0.3556 1.524)
			(layers "F.Cu" "F.Mask" "F.Paste")
			(net "I2C_B_TMP2_A0")
		)
		(pad "8" smd rect
			(at -0.97536 -2.05486 180)
			(size 0.3556 1.524)
			(layers "F.Cu" "F.Mask" "F.Paste")
			(net "P3V3")
		)
	)
	(footprint ""
		(layer "F.Cu")
		(at 191.256412 -85.705696 180)
		(property "Reference" "R168"
			(at 0 0 180)
			(layer "F.SilkS")
			(hide yes)
			(effects
				(font
					(size 1.27 1.27)
				)
			)
		)
		(property "Value" "0R2J-2-GP"
			(at 0.064008 -3.993896 180)
			(unlocked yes)
			(layer "F.Fab")
			(hide yes)
			(effects
				(font
					(size 1.016 1.016)
					(thickness 0.1524)
				)
			)
		)
		(property "Device Type" "R402H16"
			(at 0.064008 -5.517896 180)
			(unlocked yes)
			(layer "F.Fab")
			(hide yes)
			(effects
				(font
					(size 1.016 1.016)
					(thickness 0.1524)
				)
			)
		)
		(duplicate_pad_numbers_are_jumpers no)
		(fp_line
			(start 0.508 -0.9398)
			(end -0.508 -0.9398)
			(stroke
				(width 0.1524)
				(type default)
			)
			(layer "F.SilkS")
		)
		(fp_line
			(start -0.508 -0.9398)
			(end -0.508 0.9398)
			(stroke
				(width 0.1524)
				(type default)
			)
			(layer "F.SilkS")
		)
		(fp_rect
			(start -0.508 0.9398)
			(end 0.508 -0.9398)
			(stroke
				(width 0)
				(type default)
			)
			(fill no)
			(layer "F.CrtYd")
		)
		(fp_rect
			(start -0.508 0.9398)
			(end 0.508 -0.9398)
			(stroke
				(width 0)
				(type default)
			)
			(fill no)
			(layer "F.Fab")
		)
		(pad "1" smd custom
			(at 0 -0.4445 180)
			(size 0.1397 0.1397)
			(layers "F.Cu" "F.Mask" "F.Paste")
			(net "SW_PWR_HDD4")
			(options
				(clearance outline)
				(anchor circle)
			)
			(primitives
				(gr_poly
					(pts
						(arc
							(start -0.1778 -0.2794)
							(mid -0.249642 -0.249642)
							(end -0.2794 -0.1778)
						)
						(arc
							(start -0.2794 0.1778)
							(mid -0.249642 0.249642)
							(end -0.1778 0.2794)
						)
						(arc
							(start 0.1778 0.2794)
							(mid 0.249642 0.249642)
							(end 0.2794 0.1778)
						)
						(arc
							(start 0.2794 -0.1778)
							(mid 0.249642 -0.249642)
							(end 0.1778 -0.2794)
						)
					)
					(width 0)
					(fill yes)
				)
			)
		)
		(pad "2" smd custom
			(at 0 0.4445 180)
			(size 0.1397 0.1397)
			(layers "F.Cu" "F.Mask" "F.Paste")
			(net "SW_PWR_R_HDD4")
			(options
				(clearance outline)
				(anchor circle)
			)
			(primitives
				(gr_poly
					(pts
						(arc
							(start -0.1778 -0.2794)
							(mid -0.249642 -0.249642)
							(end -0.2794 -0.1778)
						)
						(arc
							(start -0.2794 0.1778)
							(mid -0.249642 0.249642)
							(end -0.1778 0.2794)
						)
						(arc
							(start 0.1778 0.2794)
							(mid 0.249642 0.249642)
							(end 0.2794 0.1778)
						)
						(arc
							(start 0.2794 -0.1778)
							(mid 0.249642 -0.249642)
							(end 0.1778 -0.2794)
						)
					)
					(width 0)
					(fill yes)
				)
			)
		)
	)
	(footprint ""
		(layer "F.Cu")
		(at 28.574746 -425.986702)
		(property "Reference" "C267"
			(at 0 0 0)
			(layer "F.SilkS")
			(hide yes)
			(effects
				(font
					(size 1.27 1.27)
				)
			)
		)
		(property "Value" "SC10U16V6KX-2GP"
			(at -0.0762 -5.1308 0)
			(unlocked yes)
			(layer "F.Fab")
			(hide yes)
			(effects
				(font
					(size 1.016 1.016)
					(thickness 0.1524)
				)
			)
		)
		(property "Device Type" "C1206H71"
			(at -0.127 -6.6548 0)
			(unlocked yes)
			(layer "F.Fab")
			(hide yes)
			(effects
				(font
					(size 1.016 1.016)
					(thickness 0.1524)
				)
			)
		)
		(duplicate_pad_numbers_are_jumpers no)
		(fp_line
			(start -1.016 -2.2352)
			(end 1.016 -2.2352)
			(stroke
				(width 0.1524)
				(type default)
			)
			(layer "F.SilkS")
		)
		(fp_line
			(start -1.016 -0.8382)
			(end -1.016 -2.2352)
			(stroke
				(width 0.1524)
				(type default)
			)
			(layer "F.SilkS")
		)
		(fp_line
			(start -1.016 2.2352)
			(end -1.016 0.8382)
			(stroke
				(width 0.1524)
				(type default)
			)
			(layer "F.SilkS")
		)
		(fp_line
			(start 1.016 -2.2352)
			(end 1.016 -0.8382)
			(stroke
				(width 0.1524)
				(type default)
			)
			(layer "F.SilkS")
		)
		(fp_line
			(start 1.016 0.8382)
			(end 1.016 2.2352)
			(stroke
				(width 0.1524)
				(type default)
			)
			(layer "F.SilkS")
		)
		(fp_line
			(start 1.016 2.2352)
			(end -1.016 2.2352)
			(stroke
				(width 0.1524)
				(type default)
			)
			(layer "F.SilkS")
		)
		(fp_rect
			(start -1.0922 2.3114)
			(end 1.0922 -2.3114)
			(stroke
				(width 0)
				(type default)
			)
			(fill no)
			(layer "F.CrtYd")
		)
		(fp_poly
			(pts
				(xy 1.0922 -2.3114) (xy 1.0922 2.3114) (xy -1.0922 2.3114) (xy -1.0922 -2.3114)
			)
			(stroke
				(width 0)
				(type default)
			)
			(fill no)
			(layer "F.Fab")
		)
		(pad "1" smd rect
			(at 0 -1.397)
			(size 1.651 1.27)
			(layers "F.Cu" "F.Mask" "F.Paste")
			(net "P5V_HDD10")
		)
		(pad "2" smd rect
			(at 0 1.397)
			(size 1.651 1.27)
			(layers "F.Cu" "F.Mask" "F.Paste")
			(net "GND")
		)
	)
	(footprint ""
		(layer "F.Cu")
		(at 80.01 -199.517 -90)
		(property "Reference" "D23"
			(at 0 0 270)
			(layer "F.SilkS")
			(hide yes)
			(effects
				(font
					(size 1.27 1.27)
				)
			)
		)
		(property "Value" "RB551V30-1-GP"
			(at 0 -6.7818 270)
			(unlocked yes)
			(layer "F.Fab")
			(hide yes)
			(effects
				(font
					(size 1.016 1.016)
					(thickness 0.1524)
				)
			)
		)
		(property "Device Type" "SOD323AKH44"
			(at 0 -8.6868 270)
			(unlocked yes)
			(layer "F.Fab")
			(hide yes)
			(effects
				(font
					(size 1.016 1.016)
					(thickness 0.1524)
				)
			)
		)
		(duplicate_pad_numbers_are_jumpers no)
		(fp_line
			(start -0.889 2.159)
			(end -0.889 -1.9304)
			(stroke
				(width 0.1524)
				(type default)
			)
			(layer "F.SilkS")
		)
		(fp_line
			(start 0.889 2.159)
			(end -0.889 2.159)
			(stroke
				(width 0.1524)
				(type default)
			)
			(layer "F.SilkS")
		)
		(fp_line
			(start 0.762 2.0574)
			(end -0.762 2.0574)
			(stroke
				(width 0.508)
				(type default)
			)
			(layer "F.SilkS")
		)
		(fp_line
			(start -0.889 -1.9304)
			(end 0.889 -1.9304)
			(stroke
				(width 0.1524)
				(type default)
			)
			(layer "F.SilkS")
		)
		(fp_line
			(start 0.889 -1.9304)
			(end 0.889 2.159)
			(stroke
				(width 0.1524)
				(type default)
			)
			(layer "F.SilkS")
		)
		(fp_rect
			(start -1.016 2.3114)
			(end 1.016 -2.0066)
			(stroke
				(width 0)
				(type default)
			)
			(fill no)
			(layer "F.CrtYd")
		)
		(fp_poly
			(pts
				(xy -1.016 -2.0066) (xy 1.016 -2.0066) (xy 1.016 2.3114) (xy -1.016 2.3114)
			)
			(stroke
				(width 0)
				(type default)
			)
			(fill no)
			(layer "F.Fab")
		)
		(pad "A" smd rect
			(at 0 -1.143 270)
			(size 0.5588 1.016)
			(layers "F.Cu" "F.Mask" "F.Paste")
			(net "SW_HDD8_R")
		)
		(pad "K" smd rect
			(at 0 1.143 270)
			(size 0.5588 1.016)
			(layers "F.Cu" "F.Mask" "F.Paste")
			(net "SW_HDD8_N")
		)
	)
	(footprint ""
		(layer "F.Cu")
		(at 45.770546 -133.3119 90)
		(property "Reference" "C341"
			(at 0 0 90)
			(layer "F.SilkS")
			(hide yes)
			(effects
				(font
					(size 1.27 1.27)
				)
			)
		)
		(property "Value" "SCD1U10V2KX-5GP"
			(at 1.1811 -2.7051 90)
			(unlocked yes)
			(layer "F.Fab")
			(hide yes)
			(effects
				(font
					(size 1.016 1.016)
					(thickness 0.1524)
				)
			)
		)
		(property "Device Type" "C402H22"
			(at 1.1811 -4.2291 90)
			(unlocked yes)
			(layer "F.Fab")
			(hide yes)
			(effects
				(font
					(size 1.016 1.016)
					(thickness 0.1524)
				)
			)
		)
		(duplicate_pad_numbers_are_jumpers no)
		(fp_rect
			(start -0.4318 0.9525)
			(end 0.4318 -0.9525)
			(stroke
				(width 0)
				(type default)
			)
			(fill no)
			(layer "F.CrtYd")
		)
		(fp_rect
			(start -0.4318 0.9525)
			(end 0.4318 -0.9525)
			(stroke
				(width 0)
				(type default)
			)
			(fill no)
			(layer "F.Fab")
		)
		(pad "1" smd custom
			(at 0 -0.4445 90)
			(size 0.1524 0.1524)
			(layers "F.Cu" "F.Mask" "F.Paste")
			(net "P3V3")
			(options
				(clearance outline)
				(anchor circle)
			)
			(primitives
				(gr_poly
					(pts
						(arc
							(start 0.3048 -0.2032)
							(mid 0.275042 -0.275042)
							(end 0.2032 -0.3048)
						)
						(arc
							(start -0.2032 -0.3048)
							(mid -0.275042 -0.275042)
							(end -0.3048 -0.2032)
						)
						(arc
							(start -0.3048 0.2032)
							(mid -0.275042 0.275042)
							(end -0.2032 0.3048)
						)
						(arc
							(start 0.2032 0.3048)
							(mid 0.275042 0.275042)
							(end 0.3048 0.2032)
						)
					)
					(width 0)
					(fill yes)
				)
			)
		)
		(pad "2" smd custom
			(at 0 0.4445 90)
			(size 0.1524 0.1524)
			(layers "F.Cu" "F.Mask" "F.Paste")
			(net "GND")
			(options
				(clearance outline)
				(anchor circle)
			)
			(primitives
				(gr_poly
					(pts
						(arc
							(start 0.3048 -0.2032)
							(mid 0.275042 -0.275042)
							(end 0.2032 -0.3048)
						)
						(arc
							(start -0.2032 -0.3048)
							(mid -0.275042 -0.275042)
							(end -0.3048 -0.2032)
						)
						(arc
							(start -0.3048 0.2032)
							(mid -0.275042 0.275042)
							(end -0.2032 0.3048)
						)
						(arc
							(start 0.2032 0.3048)
							(mid 0.275042 0.275042)
							(end 0.3048 0.2032)
						)
					)
					(width 0)
					(fill yes)
				)
			)
		)
	)
	(footprint ""
		(layer "F.Cu")
		(at 47.116746 -30.2387 180)
		(property "Reference" "PR21"
			(at 0 0 180)
			(layer "F.SilkS")
			(hide yes)
			(effects
				(font
					(size 1.27 1.27)
				)
			)
		)
		(property "Value" "10R2F-L-GP"
			(at 0.064008 -3.993896 180)
			(unlocked yes)
			(layer "F.Fab")
			(hide yes)
			(effects
				(font
					(size 1.016 1.016)
					(thickness 0.1524)
				)
			)
		)
		(property "Device Type" "R402H14"
			(at 0.064008 -5.517896 180)
			(unlocked yes)
			(layer "F.Fab")
			(hide yes)
			(effects
				(font
					(size 1.016 1.016)
					(thickness 0.1524)
				)
			)
		)
		(duplicate_pad_numbers_are_jumpers no)
		(fp_line
			(start 0.508 -0.9398)
			(end -0.508 -0.9398)
			(stroke
				(width 0.1524)
				(type default)
			)
			(layer "F.SilkS")
		)
		(fp_line
			(start -0.508 -0.9398)
			(end -0.508 0.9398)
			(stroke
				(width 0.1524)
				(type default)
			)
			(layer "F.SilkS")
		)
		(fp_rect
			(start -0.508 0.9398)
			(end 0.508 -0.9398)
			(stroke
				(width 0)
				(type default)
			)
			(fill no)
			(layer "F.CrtYd")
		)
		(fp_rect
			(start -0.508 0.9398)
			(end 0.508 -0.9398)
			(stroke
				(width 0)
				(type default)
			)
			(fill no)
			(layer "F.Fab")
		)
		(pad "1" smd custom
			(at 0 -0.4445 180)
			(size 0.1397 0.1397)
			(layers "F.Cu" "F.Mask" "F.Paste")
			(net "P5VB")
			(options
				(clearance outline)
				(anchor circle)
			)
			(primitives
				(gr_poly
					(pts
						(arc
							(start -0.1778 -0.2794)
							(mid -0.249642 -0.249642)
							(end -0.2794 -0.1778)
						)
						(arc
							(start -0.2794 0.1778)
							(mid -0.249642 0.249642)
							(end -0.1778 0.2794)
						)
						(arc
							(start 0.1778 0.2794)
							(mid 0.249642 0.249642)
							(end 0.2794 0.1778)
						)
						(arc
							(start 0.2794 -0.1778)
							(mid 0.249642 -0.249642)
							(end 0.1778 -0.2794)
						)
					)
					(width 0)
					(fill yes)
				)
			)
		)
		(pad "2" smd custom
			(at 0 0.4445 180)
			(size 0.1397 0.1397)
			(layers "F.Cu" "F.Mask" "F.Paste")
			(net "P5VB_VFB_NET")
			(options
				(clearance outline)
				(anchor circle)
			)
			(primitives
				(gr_poly
					(pts
						(arc
							(start -0.1778 -0.2794)
							(mid -0.249642 -0.249642)
							(end -0.2794 -0.1778)
						)
						(arc
							(start -0.2794 0.1778)
							(mid -0.249642 0.249642)
							(end -0.1778 0.2794)
						)
						(arc
							(start 0.1778 0.2794)
							(mid 0.249642 0.249642)
							(end 0.2794 0.1778)
						)
						(arc
							(start 0.2794 -0.1778)
							(mid 0.249642 -0.249642)
							(end 0.1778 -0.2794)
						)
					)
					(width 0)
					(fill yes)
				)
			)
		)
	)
	(footprint ""
		(layer "F.Cu")
		(at 210.692746 -52.4637)
		(property "Reference" "R335"
			(at 0 0 0)
			(layer "F.SilkS")
			(hide yes)
			(effects
				(font
					(size 1.27 1.27)
				)
			)
		)
		(property "Value" "0R2J-2-GP"
			(at 0.064008 -3.993896 0)
			(unlocked yes)
			(layer "F.Fab")
			(hide yes)
			(effects
				(font
					(size 1.016 1.016)
					(thickness 0.1524)
				)
			)
		)
		(property "Device Type" "R402H16"
			(at 0.064008 -5.517896 0)
			(unlocked yes)
			(layer "F.Fab")
			(hide yes)
			(effects
				(font
					(size 1.016 1.016)
					(thickness 0.1524)
				)
			)
		)
		(duplicate_pad_numbers_are_jumpers no)
		(fp_line
			(start -0.508 -0.9398)
			(end -0.508 0.9398)
			(stroke
				(width 0.1524)
				(type default)
			)
			(layer "F.SilkS")
		)
		(fp_line
			(start 0.508 -0.9398)
			(end -0.508 -0.9398)
			(stroke
				(width 0.1524)
				(type default)
			)
			(layer "F.SilkS")
		)
		(fp_rect
			(start -0.508 0.9398)
			(end 0.508 -0.9398)
			(stroke
				(width 0)
				(type default)
			)
			(fill no)
			(layer "F.CrtYd")
		)
		(fp_rect
			(start -0.508 0.9398)
			(end 0.508 -0.9398)
			(stroke
				(width 0)
				(type default)
			)
			(fill no)
			(layer "F.Fab")
		)
		(pad "1" smd custom
			(at 0 -0.4445)
			(size 0.1397 0.1397)
			(layers "F.Cu" "F.Mask" "F.Paste")
			(net "I2C_B_SCL")
			(options
				(clearance outline)
				(anchor circle)
			)
			(primitives
				(gr_poly
					(pts
						(arc
							(start -0.1778 -0.2794)
							(mid -0.249642 -0.249642)
							(end -0.2794 -0.1778)
						)
						(arc
							(start -0.2794 0.1778)
							(mid -0.249642 0.249642)
							(end -0.1778 0.2794)
						)
						(arc
							(start 0.1778 0.2794)
							(mid 0.249642 0.249642)
							(end 0.2794 0.1778)
						)
						(arc
							(start 0.2794 -0.1778)
							(mid 0.249642 -0.249642)
							(end 0.1778 -0.2794)
						)
					)
					(width 0)
					(fill yes)
				)
			)
		)
		(pad "2" smd custom
			(at 0 0.4445)
			(size 0.1397 0.1397)
			(layers "F.Cu" "F.Mask" "F.Paste")
			(net "TMP4_SCL")
			(options
				(clearance outline)
				(anchor circle)
			)
			(primitives
				(gr_poly
					(pts
						(arc
							(start -0.1778 -0.2794)
							(mid -0.249642 -0.249642)
							(end -0.2794 -0.1778)
						)
						(arc
							(start -0.2794 0.1778)
							(mid -0.249642 0.249642)
							(end -0.1778 0.2794)
						)
						(arc
							(start 0.1778 0.2794)
							(mid 0.249642 0.249642)
							(end 0.2794 0.1778)
						)
						(arc
							(start 0.2794 -0.1778)
							(mid 0.249642 -0.249642)
							(end 0.1778 -0.2794)
						)
					)
					(width 0)
					(fill yes)
				)
			)
		)
	)
	(footprint ""
		(layer "F.Cu")
		(at 79.191358 -498.396514 90)
		(property "Reference" "R181"
			(at 0 0 90)
			(layer "F.SilkS")
			(hide yes)
			(effects
				(font
					(size 1.27 1.27)
				)
			)
		)
		(property "Value" "200KR2F-L-GP"
			(at 0.064008 -3.993896 90)
			(unlocked yes)
			(layer "F.Fab")
			(hide yes)
			(effects
				(font
					(size 1.016 1.016)
					(thickness 0.1524)
				)
			)
		)
		(property "Device Type" "R402H16"
			(at 0.064008 -5.517896 90)
			(unlocked yes)
			(layer "F.Fab")
			(hide yes)
			(effects
				(font
					(size 1.016 1.016)
					(thickness 0.1524)
				)
			)
		)
		(duplicate_pad_numbers_are_jumpers no)
		(fp_line
			(start 0.508 -0.9398)
			(end -0.508 -0.9398)
			(stroke
				(width 0.1524)
				(type default)
			)
			(layer "F.SilkS")
		)
		(fp_line
			(start -0.508 -0.9398)
			(end -0.508 0.9398)
			(stroke
				(width 0.1524)
				(type default)
			)
			(layer "F.SilkS")
		)
		(fp_rect
			(start -0.508 0.9398)
			(end 0.508 -0.9398)
			(stroke
				(width 0)
				(type default)
			)
			(fill no)
			(layer "F.CrtYd")
		)
		(fp_rect
			(start -0.508 0.9398)
			(end 0.508 -0.9398)
			(stroke
				(width 0)
				(type default)
			)
			(fill no)
			(layer "F.Fab")
		)
		(pad "1" smd custom
			(at 0 -0.4445 90)
			(size 0.1397 0.1397)
			(layers "F.Cu" "F.Mask" "F.Paste")
			(net "P12V")
			(options
				(clearance outline)
				(anchor circle)
			)
			(primitives
				(gr_poly
					(pts
						(arc
							(start -0.1778 -0.2794)
							(mid -0.249642 -0.249642)
							(end -0.2794 -0.1778)
						)
						(arc
							(start -0.2794 0.1778)
							(mid -0.249642 0.249642)
							(end -0.1778 0.2794)
						)
						(arc
							(start 0.1778 0.2794)
							(mid 0.249642 0.249642)
							(end 0.2794 0.1778)
						)
						(arc
							(start 0.2794 -0.1778)
							(mid 0.249642 -0.249642)
							(end 0.1778 -0.2794)
						)
					)
					(width 0)
					(fill yes)
				)
			)
		)
		(pad "2" smd custom
			(at 0 0.4445 90)
			(size 0.1397 0.1397)
			(layers "F.Cu" "F.Mask" "F.Paste")
			(net "SW_HDD5_P")
			(options
				(clearance outline)
				(anchor circle)
			)
			(primitives
				(gr_poly
					(pts
						(arc
							(start -0.1778 -0.2794)
							(mid -0.249642 -0.249642)
							(end -0.2794 -0.1778)
						)
						(arc
							(start -0.2794 0.1778)
							(mid -0.249642 0.249642)
							(end -0.1778 0.2794)
						)
						(arc
							(start 0.1778 0.2794)
							(mid 0.249642 0.249642)
							(end 0.2794 0.1778)
						)
						(arc
							(start 0.2794 -0.1778)
							(mid 0.249642 -0.249642)
							(end 0.1778 -0.2794)
						)
					)
					(width 0)
					(fill yes)
				)
			)
		)
	)
	(footprint ""
		(layer "F.Cu")
		(at 36.449 -140.716)
		(property "Reference" "Q72"
			(at 0 0 0)
			(layer "F.SilkS")
			(hide yes)
			(effects
				(font
					(size 1.27 1.27)
				)
			)
		)
		(property "Value" "2N7002DW-7F-GP"
			(at -2.3622 -8.2042 0)
			(unlocked yes)
			(layer "F.Fab")
			(hide yes)
			(effects
				(font
					(size 1.016 1.016)
					(thickness 0.1524)
				)
			)
		)
		(property "Device Type" "SOT-363H44"
			(at -2.3622 -10.1092 0)
			(unlocked yes)
			(layer "F.Fab")
			(hide yes)
			(effects
				(font
					(size 1.016 1.016)
					(thickness 0.1524)
				)
			)
		)
		(duplicate_pad_numbers_are_jumpers no)
		(fp_line
			(start -1.4478 -1.7018)
			(end -1.4478 1.7018)
			(stroke
				(width 0.1524)
				(type default)
			)
			(layer "F.SilkS")
		)
		(fp_line
			(start -1.4478 1.7018)
			(end 1.4478 1.7018)
			(stroke
				(width 0.1524)
				(type default)
			)
			(layer "F.SilkS")
		)
		(fp_line
			(start -1.27 1.524)
			(end -1.27 0.6604)
			(stroke
				(width 0.4826)
				(type default)
			)
			(layer "F.SilkS")
		)
		(fp_line
			(start 1.4478 -1.7018)
			(end -1.4478 -1.7018)
			(stroke
				(width 0.1524)
				(type default)
			)
			(layer "F.SilkS")
		)
		(fp_line
			(start 1.4478 1.7018)
			(end 1.4478 -1.7018)
			(stroke
				(width 0.1524)
				(type default)
			)
			(layer "F.SilkS")
		)
		(fp_poly
			(pts
				(xy -1.524 -1.778) (xy 1.524 -1.778) (xy 1.524 1.778) (xy -1.524 1.778)
			)
			(stroke
				(width 0)
				(type default)
			)
			(fill no)
			(layer "F.CrtYd")
		)
		(fp_poly
			(pts
				(xy -1.524 -1.778) (xy 1.524 -1.778) (xy 1.524 1.778) (xy -1.524 1.778)
			)
			(stroke
				(width 0)
				(type default)
			)
			(fill no)
			(layer "F.Fab")
		)
		(pad "1" smd rect
			(at -0.65024 0.9398)
			(size 0.4064 1.016)
			(layers "F.Cu" "F.Mask" "F.Paste")
			(net "P3V3_HDD13_LED")
		)
		(pad "2" smd rect
			(at 0 0.9398)
			(size 0.4064 1.016)
			(layers "F.Cu" "F.Mask" "F.Paste")
			(net "HDD13_LED_G")
		)
		(pad "3" smd rect
			(at 0.65024 0.9398)
			(size 0.4064 1.016)
			(layers "F.Cu" "F.Mask" "F.Paste")
			(net "P5VC")
		)
		(pad "4" smd rect
			(at 0.65024 -0.9398)
			(size 0.4064 1.016)
			(layers "F.Cu" "F.Mask" "F.Paste")
			(net "P5VC_HDD13_LED")
		)
		(pad "5" smd rect
			(at 0 -0.9398)
			(size 0.4064 1.016)
			(layers "F.Cu" "F.Mask" "F.Paste")
			(net "HDD13_LED_G")
		)
		(pad "6" smd rect
			(at -0.65024 -0.9398)
			(size 0.4064 1.016)
			(layers "F.Cu" "F.Mask" "F.Paste")
			(net "P3V3")
		)
	)
	(footprint ""
		(layer "F.Cu")
		(at 11.8618 -161.417 90)
		(property "Reference" "R357"
			(at 0 0 90)
			(layer "F.SilkS")
			(hide yes)
			(effects
				(font
					(size 1.27 1.27)
				)
			)
		)
		(property "Value" "0R2J-2-GP"
			(at 0.064008 -3.993896 90)
			(unlocked yes)
			(layer "F.Fab")
			(hide yes)
			(effects
				(font
					(size 1.016 1.016)
					(thickness 0.1524)
				)
			)
		)
		(property "Device Type" "R402H16"
			(at 0.064008 -5.517896 90)
			(unlocked yes)
			(layer "F.Fab")
			(hide yes)
			(effects
				(font
					(size 1.016 1.016)
					(thickness 0.1524)
				)
			)
		)
		(duplicate_pad_numbers_are_jumpers no)
		(fp_line
			(start 0.508 -0.9398)
			(end -0.508 -0.9398)
			(stroke
				(width 0.1524)
				(type default)
			)
			(layer "F.SilkS")
		)
		(fp_line
			(start -0.508 -0.9398)
			(end -0.508 0.9398)
			(stroke
				(width 0.1524)
				(type default)
			)
			(layer "F.SilkS")
		)
		(fp_rect
			(start -0.508 0.9398)
			(end 0.508 -0.9398)
			(stroke
				(width 0)
				(type default)
			)
			(fill no)
			(layer "F.CrtYd")
		)
		(fp_rect
			(start -0.508 0.9398)
			(end 0.508 -0.9398)
			(stroke
				(width 0)
				(type default)
			)
			(fill no)
			(layer "F.Fab")
		)
		(pad "1" smd custom
			(at 0 -0.4445 90)
			(size 0.1397 0.1397)
			(layers "F.Cu" "F.Mask" "F.Paste")
			(net "SELF_1A&2A_HB")
			(options
				(clearance outline)
				(anchor circle)
			)
			(primitives
				(gr_poly
					(pts
						(arc
							(start -0.1778 -0.2794)
							(mid -0.249642 -0.249642)
							(end -0.2794 -0.1778)
						)
						(arc
							(start -0.2794 0.1778)
							(mid -0.249642 0.249642)
							(end -0.1778 0.2794)
						)
						(arc
							(start 0.1778 0.2794)
							(mid 0.249642 0.249642)
							(end 0.2794 0.1778)
						)
						(arc
							(start 0.2794 -0.1778)
							(mid 0.249642 -0.249642)
							(end 0.1778 -0.2794)
						)
					)
					(width 0)
					(fill yes)
				)
			)
		)
		(pad "2" smd custom
			(at 0 0.4445 90)
			(size 0.1397 0.1397)
			(layers "F.Cu" "F.Mask" "F.Paste")
			(net "HB_EXP_B_INPUT")
			(options
				(clearance outline)
				(anchor circle)
			)
			(primitives
				(gr_poly
					(pts
						(arc
							(start -0.1778 -0.2794)
							(mid -0.249642 -0.249642)
							(end -0.2794 -0.1778)
						)
						(arc
							(start -0.2794 0.1778)
							(mid -0.249642 0.249642)
							(end -0.1778 0.2794)
						)
						(arc
							(start 0.1778 0.2794)
							(mid 0.249642 0.249642)
							(end 0.2794 0.1778)
						)
						(arc
							(start 0.2794 -0.1778)
							(mid 0.249642 -0.249642)
							(end 0.1778 -0.2794)
						)
					)
					(width 0)
					(fill yes)
				)
			)
		)
	)
	(footprint ""
		(layer "F.Cu")
		(at 217.762582 -263.116568 -90)
		(property "Reference" "C134"
			(at 0 0 270)
			(layer "F.SilkS")
			(hide yes)
			(effects
				(font
					(size 1.27 1.27)
				)
			)
		)
		(property "Value" "SCD01U50V2KX-1GP"
			(at 1.1811 -2.7051 270)
			(unlocked yes)
			(layer "F.Fab")
			(hide yes)
			(effects
				(font
					(size 1.016 1.016)
					(thickness 0.1524)
				)
			)
		)
		(property "Device Type" "C402H22"
			(at 1.1811 -4.2291 270)
			(unlocked yes)
			(layer "F.Fab")
			(hide yes)
			(effects
				(font
					(size 1.016 1.016)
					(thickness 0.1524)
				)
			)
		)
		(duplicate_pad_numbers_are_jumpers no)
		(fp_rect
			(start -0.4318 0.9525)
			(end 0.4318 -0.9525)
			(stroke
				(width 0)
				(type default)
			)
			(fill no)
			(layer "F.CrtYd")
		)
		(fp_rect
			(start -0.4318 0.9525)
			(end 0.4318 -0.9525)
			(stroke
				(width 0)
				(type default)
			)
			(fill no)
			(layer "F.Fab")
		)
		(pad "1" smd custom
			(at 0 -0.4445 270)
			(size 0.1524 0.1524)
			(layers "F.Cu" "F.Mask" "F.Paste")
			(net "SAS2X28_DRIVE_RX_N_A2")
			(options
				(clearance outline)
				(anchor circle)
			)
			(primitives
				(gr_poly
					(pts
						(arc
							(start 0.3048 -0.2032)
							(mid 0.275042 -0.275042)
							(end 0.2032 -0.3048)
						)
						(arc
							(start -0.2032 -0.3048)
							(mid -0.275042 -0.275042)
							(end -0.3048 -0.2032)
						)
						(arc
							(start -0.3048 0.2032)
							(mid -0.275042 0.275042)
							(end -0.2032 0.3048)
						)
						(arc
							(start 0.2032 0.3048)
							(mid 0.275042 0.275042)
							(end 0.3048 0.2032)
						)
					)
					(width 0)
					(fill yes)
				)
			)
		)
		(pad "2" smd custom
			(at 0 0.4445 270)
			(size 0.1524 0.1524)
			(layers "F.Cu" "F.Mask" "F.Paste")
			(net "SAS2X28_A_HDD2_RX_-")
			(options
				(clearance outline)
				(anchor circle)
			)
			(primitives
				(gr_poly
					(pts
						(arc
							(start 0.3048 -0.2032)
							(mid 0.275042 -0.275042)
							(end 0.2032 -0.3048)
						)
						(arc
							(start -0.2032 -0.3048)
							(mid -0.275042 -0.275042)
							(end -0.3048 -0.2032)
						)
						(arc
							(start -0.3048 0.2032)
							(mid -0.275042 0.275042)
							(end -0.2032 0.3048)
						)
						(arc
							(start 0.2032 0.3048)
							(mid 0.275042 0.275042)
							(end 0.3048 0.2032)
						)
					)
					(width 0)
					(fill yes)
				)
			)
		)
	)
	(footprint ""
		(layer "F.Cu")
		(at 200.146412 -88.753696 -90)
		(property "Reference" "U14"
			(at 0 0 270)
			(layer "F.SilkS")
			(hide yes)
			(effects
				(font
					(size 1.27 1.27)
				)
			)
		)
		(property "Value" "P2003EVG-GP"
			(at 0 -11.1252 270)
			(unlocked yes)
			(layer "F.Fab")
			(hide yes)
			(effects
				(font
					(size 1.016 1.016)
					(thickness 0.1524)
				)
			)
		)
		(property "Device Type" "SOIC8H79"
			(at 0 -12.6492 270)
			(unlocked yes)
			(layer "F.Fab")
			(hide yes)
			(effects
				(font
					(size 1.016 1.016)
					(thickness 0.1524)
				)
			)
		)
		(duplicate_pad_numbers_are_jumpers no)
		(fp_line
			(start -2.6162 3.429)
			(end -2.6162 1.4732)
			(stroke
				(width 0.4064)
				(type default)
			)
			(layer "F.SilkS")
		)
		(fp_line
			(start -2.7432 1.4224)
			(end 2.1336 1.4224)
			(stroke
				(width 0.1524)
				(type default)
			)
			(layer "F.SilkS")
		)
		(fp_line
			(start 2.1336 1.4224)
			(end 2.1336 -1.4224)
			(stroke
				(width 0.1524)
				(type default)
			)
			(layer "F.SilkS")
		)
		(fp_line
			(start -2.2352 0)
			(end -2.7432 0.508)
			(stroke
				(width 0.1524)
				(type default)
			)
			(layer "F.SilkS")
		)
		(fp_line
			(start -2.7432 -0.508)
			(end -2.2352 0)
			(stroke
				(width 0.1524)
				(type default)
			)
			(layer "F.SilkS")
		)
		(fp_line
			(start -2.7432 -1.4224)
			(end -2.7432 1.4224)
			(stroke
				(width 0.1524)
				(type default)
			)
			(layer "F.SilkS")
		)
		(fp_line
			(start 2.1336 -1.4224)
			(end -2.7432 -1.4224)
			(stroke
				(width 0.1524)
				(type default)
			)
			(layer "F.SilkS")
		)
		(fp_poly
			(pts
				(xy 2.2098 -1.4224) (xy 2.2098 1.4224) (xy -2.2225 1.4224) (xy -2.2225 -1.4224)
			)
			(stroke
				(width 0)
				(type default)
			)
			(fill yes)
			(layer "F.SilkS")
		)
		(fp_rect
			(start -2.4511 2.9972)
			(end 2.4511 -2.9972)
			(stroke
				(width 0)
				(type default)
			)
			(fill no)
			(layer "F.CrtYd")
		)
		(fp_poly
			(pts
				(xy -2.8194 3.6322) (xy -2.8194 -3.6322) (xy 2.8194 -3.6322) (xy 2.8194 -2.2987) (xy 2.4511 -2.2987)
				(xy 2.4511 -2.9972) (xy -2.4511 -2.9972) (xy -2.4511 2.9972) (xy 2.4511 2.9972) (xy 2.4511 -2.286)
				(xy 2.8194 -2.286) (xy 2.8194 3.6322)
			)
			(stroke
				(width 0)
				(type default)
			)
			(fill no)
			(layer "F.CrtYd")
		)
		(fp_rect
			(start -2.8194 3.6322)
			(end 2.8194 -3.6322)
			(stroke
				(width 0)
				(type default)
			)
			(fill no)
			(layer "F.Fab")
		)
		(pad "1" smd rect
			(at -1.905 2.54 270)
			(size 0.635 1.651)
			(layers "F.Cu" "F.Mask" "F.Paste")
			(net "P12V")
		)
		(pad "2" smd rect
			(at -0.635 2.54 270)
			(size 0.635 1.651)
			(layers "F.Cu" "F.Mask" "F.Paste")
			(net "P12V")
		)
		(pad "3" smd rect
			(at 0.635 2.54 270)
			(size 0.635 1.651)
			(layers "F.Cu" "F.Mask" "F.Paste")
			(net "P12V")
		)
		(pad "4" smd rect
			(at 1.905 2.54 270)
			(size 0.635 1.651)
			(layers "F.Cu" "F.Mask" "F.Paste")
			(net "SW_HDD4_N")
		)
		(pad "5" smd rect
			(at 1.905 -2.54 270)
			(size 0.635 1.651)
			(layers "F.Cu" "F.Mask" "F.Paste")
			(net "P12V_HDD4")
		)
		(pad "6" smd rect
			(at 0.635 -2.54 270)
			(size 0.635 1.651)
			(layers "F.Cu" "F.Mask" "F.Paste")
			(net "P12V_HDD4")
		)
		(pad "7" smd rect
			(at -0.635 -2.54 270)
			(size 0.635 1.651)
			(layers "F.Cu" "F.Mask" "F.Paste")
			(net "P12V_HDD4")
		)
		(pad "8" smd rect
			(at -1.905 -2.54 270)
			(size 0.635 1.651)
			(layers "F.Cu" "F.Mask" "F.Paste")
			(net "P12V_HDD4")
		)
	)
	(footprint ""
		(layer "F.Cu")
		(at 49.021746 -349.7707 90)
		(property "Reference" "R186"
			(at 0 0 90)
			(layer "F.SilkS")
			(hide yes)
			(effects
				(font
					(size 1.27 1.27)
				)
			)
		)
		(property "Value" "0R2J-2-GP"
			(at 0.064008 -3.993896 90)
			(unlocked yes)
			(layer "F.Fab")
			(hide yes)
			(effects
				(font
					(size 1.016 1.016)
					(thickness 0.1524)
				)
			)
		)
		(property "Device Type" "R402H16"
			(at 0.064008 -5.517896 90)
			(unlocked yes)
			(layer "F.Fab")
			(hide yes)
			(effects
				(font
					(size 1.016 1.016)
					(thickness 0.1524)
				)
			)
		)
		(duplicate_pad_numbers_are_jumpers no)
		(fp_line
			(start 0.508 -0.9398)
			(end -0.508 -0.9398)
			(stroke
				(width 0.1524)
				(type default)
			)
			(layer "F.SilkS")
		)
		(fp_line
			(start -0.508 -0.9398)
			(end -0.508 0.9398)
			(stroke
				(width 0.1524)
				(type default)
			)
			(layer "F.SilkS")
		)
		(fp_rect
			(start -0.508 0.9398)
			(end 0.508 -0.9398)
			(stroke
				(width 0)
				(type default)
			)
			(fill no)
			(layer "F.CrtYd")
		)
		(fp_rect
			(start -0.508 0.9398)
			(end 0.508 -0.9398)
			(stroke
				(width 0)
				(type default)
			)
			(fill no)
			(layer "F.Fab")
		)
		(pad "1" smd custom
			(at 0 -0.4445 90)
			(size 0.1397 0.1397)
			(layers "F.Cu" "F.Mask" "F.Paste")
			(net "DRV_ACT_NET6")
			(options
				(clearance outline)
				(anchor circle)
			)
			(primitives
				(gr_poly
					(pts
						(arc
							(start -0.1778 -0.2794)
							(mid -0.249642 -0.249642)
							(end -0.2794 -0.1778)
						)
						(arc
							(start -0.2794 0.1778)
							(mid -0.249642 0.249642)
							(end -0.1778 0.2794)
						)
						(arc
							(start 0.1778 0.2794)
							(mid 0.249642 0.249642)
							(end 0.2794 0.1778)
						)
						(arc
							(start 0.2794 -0.1778)
							(mid 0.249642 -0.249642)
							(end 0.1778 -0.2794)
						)
					)
					(width 0)
					(fill yes)
				)
			)
		)
		(pad "2" smd custom
			(at 0 0.4445 90)
			(size 0.1397 0.1397)
			(layers "F.Cu" "F.Mask" "F.Paste")
			(net "DRIVE_ACT_6")
			(options
				(clearance outline)
				(anchor circle)
			)
			(primitives
				(gr_poly
					(pts
						(arc
							(start -0.1778 -0.2794)
							(mid -0.249642 -0.249642)
							(end -0.2794 -0.1778)
						)
						(arc
							(start -0.2794 0.1778)
							(mid -0.249642 0.249642)
							(end -0.1778 0.2794)
						)
						(arc
							(start 0.1778 0.2794)
							(mid 0.249642 0.249642)
							(end 0.2794 0.1778)
						)
						(arc
							(start 0.2794 -0.1778)
							(mid 0.249642 -0.249642)
							(end 0.1778 -0.2794)
						)
					)
					(width 0)
					(fill yes)
				)
			)
		)
	)
	(footprint ""
		(layer "F.Cu")
		(at 31.495746 -441.099702 180)
		(property "Reference" "C261"
			(at 0 0 180)
			(layer "F.SilkS")
			(hide yes)
			(effects
				(font
					(size 1.27 1.27)
				)
			)
		)
		(property "Value" "SCD1U10V2KX-5GP"
			(at 1.1811 -2.7051 180)
			(unlocked yes)
			(layer "F.Fab")
			(hide yes)
			(effects
				(font
					(size 1.016 1.016)
					(thickness 0.1524)
				)
			)
		)
		(property "Device Type" "C402H22"
			(at 1.1811 -4.2291 180)
			(unlocked yes)
			(layer "F.Fab")
			(hide yes)
			(effects
				(font
					(size 1.016 1.016)
					(thickness 0.1524)
				)
			)
		)
		(duplicate_pad_numbers_are_jumpers no)
		(fp_rect
			(start -0.4318 0.9525)
			(end 0.4318 -0.9525)
			(stroke
				(width 0)
				(type default)
			)
			(fill no)
			(layer "F.CrtYd")
		)
		(fp_rect
			(start -0.4318 0.9525)
			(end 0.4318 -0.9525)
			(stroke
				(width 0)
				(type default)
			)
			(fill no)
			(layer "F.Fab")
		)
		(pad "1" smd custom
			(at 0 -0.4445 180)
			(size 0.1524 0.1524)
			(layers "F.Cu" "F.Mask" "F.Paste")
			(net "P3V3")
			(options
				(clearance outline)
				(anchor circle)
			)
			(primitives
				(gr_poly
					(pts
						(arc
							(start 0.3048 -0.2032)
							(mid 0.275042 -0.275042)
							(end 0.2032 -0.3048)
						)
						(arc
							(start -0.2032 -0.3048)
							(mid -0.275042 -0.275042)
							(end -0.3048 -0.2032)
						)
						(arc
							(start -0.3048 0.2032)
							(mid -0.275042 0.275042)
							(end -0.2032 0.3048)
						)
						(arc
							(start 0.2032 0.3048)
							(mid 0.275042 0.275042)
							(end 0.3048 0.2032)
						)
					)
					(width 0)
					(fill yes)
				)
			)
		)
		(pad "2" smd custom
			(at 0 0.4445 180)
			(size 0.1524 0.1524)
			(layers "F.Cu" "F.Mask" "F.Paste")
			(net "GND")
			(options
				(clearance outline)
				(anchor circle)
			)
			(primitives
				(gr_poly
					(pts
						(arc
							(start 0.3048 -0.2032)
							(mid 0.275042 -0.275042)
							(end 0.2032 -0.3048)
						)
						(arc
							(start -0.2032 -0.3048)
							(mid -0.275042 -0.275042)
							(end -0.3048 -0.2032)
						)
						(arc
							(start -0.3048 0.2032)
							(mid -0.275042 0.275042)
							(end -0.2032 0.3048)
						)
						(arc
							(start 0.2032 0.3048)
							(mid 0.275042 0.275042)
							(end 0.3048 0.2032)
						)
					)
					(width 0)
					(fill yes)
				)
			)
		)
	)
	(footprint ""
		(layer "F.Cu")
		(at 45.482256 -452.783702 90)
		(property "Reference" "R172"
			(at 0 0 90)
			(layer "F.SilkS")
			(hide yes)
			(effects
				(font
					(size 1.27 1.27)
				)
			)
		)
		(property "Value" "0R2J-2-GP"
			(at 0.064008 -3.993896 90)
			(unlocked yes)
			(layer "F.Fab")
			(hide yes)
			(effects
				(font
					(size 1.016 1.016)
					(thickness 0.1524)
				)
			)
		)
		(property "Device Type" "R402H16"
			(at 0.064008 -5.517896 90)
			(unlocked yes)
			(layer "F.Fab")
			(hide yes)
			(effects
				(font
					(size 1.016 1.016)
					(thickness 0.1524)
				)
			)
		)
		(duplicate_pad_numbers_are_jumpers no)
		(fp_line
			(start 0.508 -0.9398)
			(end -0.508 -0.9398)
			(stroke
				(width 0.1524)
				(type default)
			)
			(layer "F.SilkS")
		)
		(fp_line
			(start -0.508 -0.9398)
			(end -0.508 0.9398)
			(stroke
				(width 0.1524)
				(type default)
			)
			(layer "F.SilkS")
		)
		(fp_rect
			(start -0.508 0.9398)
			(end 0.508 -0.9398)
			(stroke
				(width 0)
				(type default)
			)
			(fill no)
			(layer "F.CrtYd")
		)
		(fp_rect
			(start -0.508 0.9398)
			(end 0.508 -0.9398)
			(stroke
				(width 0)
				(type default)
			)
			(fill no)
			(layer "F.Fab")
		)
		(pad "1" smd custom
			(at 0 -0.4445 90)
			(size 0.1397 0.1397)
			(layers "F.Cu" "F.Mask" "F.Paste")
			(net "DRV_ACT_NET5")
			(options
				(clearance outline)
				(anchor circle)
			)
			(primitives
				(gr_poly
					(pts
						(arc
							(start -0.1778 -0.2794)
							(mid -0.249642 -0.249642)
							(end -0.2794 -0.1778)
						)
						(arc
							(start -0.2794 0.1778)
							(mid -0.249642 0.249642)
							(end -0.1778 0.2794)
						)
						(arc
							(start 0.1778 0.2794)
							(mid 0.249642 0.249642)
							(end 0.2794 0.1778)
						)
						(arc
							(start 0.2794 -0.1778)
							(mid 0.249642 -0.249642)
							(end 0.1778 -0.2794)
						)
					)
					(width 0)
					(fill yes)
				)
			)
		)
		(pad "2" smd custom
			(at 0 0.4445 90)
			(size 0.1397 0.1397)
			(layers "F.Cu" "F.Mask" "F.Paste")
			(net "DRIVE_ACT_5")
			(options
				(clearance outline)
				(anchor circle)
			)
			(primitives
				(gr_poly
					(pts
						(arc
							(start -0.1778 -0.2794)
							(mid -0.249642 -0.249642)
							(end -0.2794 -0.1778)
						)
						(arc
							(start -0.2794 0.1778)
							(mid -0.249642 0.249642)
							(end -0.1778 0.2794)
						)
						(arc
							(start 0.1778 0.2794)
							(mid 0.249642 0.249642)
							(end 0.2794 0.1778)
						)
						(arc
							(start 0.2794 -0.1778)
							(mid 0.249642 -0.249642)
							(end 0.1778 -0.2794)
						)
					)
					(width 0)
					(fill yes)
				)
			)
		)
	)
	(footprint ""
		(layer "F.Cu")
		(at 216.110058 -385.520184 180)
		(property "Reference" "C123"
			(at 0 0 180)
			(layer "F.SilkS")
			(hide yes)
			(effects
				(font
					(size 1.27 1.27)
				)
			)
		)
		(property "Value" "SC10U16V6KX-2GP"
			(at -0.0762 -5.1308 180)
			(unlocked yes)
			(layer "F.Fab")
			(hide yes)
			(effects
				(font
					(size 1.016 1.016)
					(thickness 0.1524)
				)
			)
		)
		(property "Device Type" "C1206H71"
			(at -0.127 -6.6548 180)
			(unlocked yes)
			(layer "F.Fab")
			(hide yes)
			(effects
				(font
					(size 1.016 1.016)
					(thickness 0.1524)
				)
			)
		)
		(duplicate_pad_numbers_are_jumpers no)
		(fp_line
			(start 1.016 2.2352)
			(end -1.016 2.2352)
			(stroke
				(width 0.1524)
				(type default)
			)
			(layer "F.SilkS")
		)
		(fp_line
			(start 1.016 0.8382)
			(end 1.016 2.2352)
			(stroke
				(width 0.1524)
				(type default)
			)
			(layer "F.SilkS")
		)
		(fp_line
			(start 1.016 -2.2352)
			(end 1.016 -0.8382)
			(stroke
				(width 0.1524)
				(type default)
			)
			(layer "F.SilkS")
		)
		(fp_line
			(start -1.016 2.2352)
			(end -1.016 0.8382)
			(stroke
				(width 0.1524)
				(type default)
			)
			(layer "F.SilkS")
		)
		(fp_line
			(start -1.016 -0.8382)
			(end -1.016 -2.2352)
			(stroke
				(width 0.1524)
				(type default)
			)
			(layer "F.SilkS")
		)
		(fp_line
			(start -1.016 -2.2352)
			(end 1.016 -2.2352)
			(stroke
				(width 0.1524)
				(type default)
			)
			(layer "F.SilkS")
		)
		(fp_rect
			(start -1.0922 2.3114)
			(end 1.0922 -2.3114)
			(stroke
				(width 0)
				(type default)
			)
			(fill no)
			(layer "F.CrtYd")
		)
		(fp_poly
			(pts
				(xy 1.0922 -2.3114) (xy 1.0922 2.3114) (xy -1.0922 2.3114) (xy -1.0922 -2.3114)
			)
			(stroke
				(width 0)
				(type default)
			)
			(fill no)
			(layer "F.Fab")
		)
		(pad "1" smd rect
			(at 0 -1.397 180)
			(size 1.651 1.27)
			(layers "F.Cu" "F.Mask" "F.Paste")
			(net "P5V_HDD1")
		)
		(pad "2" smd rect
			(at 0 1.397 180)
			(size 1.651 1.27)
			(layers "F.Cu" "F.Mask" "F.Paste")
			(net "GND")
		)
	)
	(footprint ""
		(layer "F.Cu")
		(at 4.49961 -483.399846)
		(property "Reference" "H2"
			(at 0 0 0)
			(layer "F.SilkS")
			(hide yes)
			(effects
				(font
					(size 1.27 1.27)
				)
			)
		)
		(property "Value" "HOLE315R140"
			(at 0 -7.5692 0)
			(unlocked yes)
			(layer "F.Fab")
			(hide yes)
			(effects
				(font
					(size 1.016 1.016)
					(thickness 0.1524)
				)
			)
		)
		(property "Device Type" "HOLE315R140"
			(at 0 -9.0932 0)
			(unlocked yes)
			(layer "F.Fab")
			(hide yes)
			(effects
				(font
					(size 1.016 1.016)
					(thickness 0.1524)
				)
			)
		)
		(duplicate_pad_numbers_are_jumpers no)
		(fp_poly
			(pts
				(arc
					(start 4.3053 0)
					(mid -4.3053 0)
					(end 4.3053 0)
				)
			)
			(stroke
				(width 0)
				(type default)
			)
			(fill no)
			(layer "F.CrtYd")
		)
		(fp_poly
			(pts
				(arc
					(start 4.3053 0)
					(mid -4.3053 0)
					(end 4.3053 0)
				)
			)
			(stroke
				(width 0)
				(type default)
			)
			(fill no)
			(layer "F.Fab")
		)
		(pad "1" thru_hole circle
			(at 0.00127 0.00127)
			(size 8.001 8.001)
			(drill 3.556)
			(layers "*.Cu" "*.Mask")
			(remove_unused_layers no)
			(net "GND")
			(clearance -1.7145)
			(thermal_gap 0.3048)
			(padstack
				(mode front_inner_back)
				(layer "Inner"
					(shape circle)
					(size 3.9624 3.9624)
					(clearance 0.3048)
				)
				(layer "B.Cu"
					(shape circle)
					(size 8.001 8.001)
					(clearance -1.7145)
				)
			)
		)
	)
	(footprint ""
		(layer "F.Cu")
		(at 33.043368 -469.837516 -90)
		(property "Reference" "C183"
			(at 0 0 270)
			(layer "F.SilkS")
			(hide yes)
			(effects
				(font
					(size 1.27 1.27)
				)
			)
		)
		(property "Value" "SCD01U50V2KX-1GP"
			(at 1.1811 -2.7051 270)
			(unlocked yes)
			(layer "F.Fab")
			(hide yes)
			(effects
				(font
					(size 1.016 1.016)
					(thickness 0.1524)
				)
			)
		)
		(property "Device Type" "C402H22"
			(at 1.1811 -4.2291 270)
			(unlocked yes)
			(layer "F.Fab")
			(hide yes)
			(effects
				(font
					(size 1.016 1.016)
					(thickness 0.1524)
				)
			)
		)
		(duplicate_pad_numbers_are_jumpers no)
		(fp_rect
			(start -0.4318 0.9525)
			(end 0.4318 -0.9525)
			(stroke
				(width 0)
				(type default)
			)
			(fill no)
			(layer "F.CrtYd")
		)
		(fp_rect
			(start -0.4318 0.9525)
			(end 0.4318 -0.9525)
			(stroke
				(width 0)
				(type default)
			)
			(fill no)
			(layer "F.Fab")
		)
		(pad "1" smd custom
			(at 0 -0.4445 270)
			(size 0.1524 0.1524)
			(layers "F.Cu" "F.Mask" "F.Paste")
			(net "SAS2X28_DRIVE_RX_P_A5")
			(options
				(clearance outline)
				(anchor circle)
			)
			(primitives
				(gr_poly
					(pts
						(arc
							(start 0.3048 -0.2032)
							(mid 0.275042 -0.275042)
							(end 0.2032 -0.3048)
						)
						(arc
							(start -0.2032 -0.3048)
							(mid -0.275042 -0.275042)
							(end -0.3048 -0.2032)
						)
						(arc
							(start -0.3048 0.2032)
							(mid -0.275042 0.275042)
							(end -0.2032 0.3048)
						)
						(arc
							(start 0.2032 0.3048)
							(mid 0.275042 0.275042)
							(end 0.3048 0.2032)
						)
					)
					(width 0)
					(fill yes)
				)
			)
		)
		(pad "2" smd custom
			(at 0 0.4445 270)
			(size 0.1524 0.1524)
			(layers "F.Cu" "F.Mask" "F.Paste")
			(net "SAS2X28_A_HDD5_RX_+")
			(options
				(clearance outline)
				(anchor circle)
			)
			(primitives
				(gr_poly
					(pts
						(arc
							(start 0.3048 -0.2032)
							(mid 0.275042 -0.275042)
							(end 0.2032 -0.3048)
						)
						(arc
							(start -0.2032 -0.3048)
							(mid -0.275042 -0.275042)
							(end -0.3048 -0.2032)
						)
						(arc
							(start -0.3048 0.2032)
							(mid -0.275042 0.275042)
							(end -0.2032 0.3048)
						)
						(arc
							(start 0.2032 0.3048)
							(mid 0.275042 0.275042)
							(end 0.3048 0.2032)
						)
					)
					(width 0)
					(fill yes)
				)
			)
		)
	)
	(footprint ""
		(layer "F.Cu")
		(at 200.037446 -457.361036 90)
		(property "Reference" "R354"
			(at 0 0 90)
			(layer "F.SilkS")
			(hide yes)
			(effects
				(font
					(size 1.27 1.27)
				)
			)
		)
		(property "Value" "0R2J-2-GP"
			(at 0.064008 -3.993896 90)
			(unlocked yes)
			(layer "F.Fab")
			(hide yes)
			(effects
				(font
					(size 1.016 1.016)
					(thickness 0.1524)
				)
			)
		)
		(property "Device Type" "R402H16"
			(at 0.064008 -5.517896 90)
			(unlocked yes)
			(layer "F.Fab")
			(hide yes)
			(effects
				(font
					(size 1.016 1.016)
					(thickness 0.1524)
				)
			)
		)
		(duplicate_pad_numbers_are_jumpers no)
		(fp_line
			(start 0.508 -0.9398)
			(end -0.508 -0.9398)
			(stroke
				(width 0.1524)
				(type default)
			)
			(layer "F.SilkS")
		)
		(fp_line
			(start -0.508 -0.9398)
			(end -0.508 0.9398)
			(stroke
				(width 0.1524)
				(type default)
			)
			(layer "F.SilkS")
		)
		(fp_rect
			(start -0.508 0.9398)
			(end 0.508 -0.9398)
			(stroke
				(width 0)
				(type default)
			)
			(fill no)
			(layer "F.CrtYd")
		)
		(fp_rect
			(start -0.508 0.9398)
			(end 0.508 -0.9398)
			(stroke
				(width 0)
				(type default)
			)
			(fill no)
			(layer "F.Fab")
		)
		(pad "1" smd custom
			(at 0 -0.4445 90)
			(size 0.1397 0.1397)
			(layers "F.Cu" "F.Mask" "F.Paste")
			(net "EEPROM_SDA")
			(options
				(clearance outline)
				(anchor circle)
			)
			(primitives
				(gr_poly
					(pts
						(arc
							(start -0.1778 -0.2794)
							(mid -0.249642 -0.249642)
							(end -0.2794 -0.1778)
						)
						(arc
							(start -0.2794 0.1778)
							(mid -0.249642 0.249642)
							(end -0.1778 0.2794)
						)
						(arc
							(start 0.1778 0.2794)
							(mid 0.249642 0.249642)
							(end 0.2794 0.1778)
						)
						(arc
							(start 0.2794 -0.1778)
							(mid 0.249642 -0.249642)
							(end 0.1778 -0.2794)
						)
					)
					(width 0)
					(fill yes)
				)
			)
		)
		(pad "2" smd custom
			(at 0 0.4445 90)
			(size 0.1397 0.1397)
			(layers "F.Cu" "F.Mask" "F.Paste")
			(net "I2C_B_SDA")
			(options
				(clearance outline)
				(anchor circle)
			)
			(primitives
				(gr_poly
					(pts
						(arc
							(start -0.1778 -0.2794)
							(mid -0.249642 -0.249642)
							(end -0.2794 -0.1778)
						)
						(arc
							(start -0.2794 0.1778)
							(mid -0.249642 0.249642)
							(end -0.1778 0.2794)
						)
						(arc
							(start 0.1778 0.2794)
							(mid 0.249642 0.249642)
							(end 0.2794 0.1778)
						)
						(arc
							(start 0.2794 -0.1778)
							(mid 0.249642 -0.249642)
							(end 0.1778 -0.2794)
						)
					)
					(width 0)
					(fill yes)
				)
			)
		)
	)
	(footprint ""
		(layer "F.Cu")
		(at 195.326 -89.916)
		(property "Reference" "C383"
			(at 0 0 0)
			(layer "F.SilkS")
			(hide yes)
			(effects
				(font
					(size 1.27 1.27)
				)
			)
		)
		(property "Value" "SCD033U25V2KX-GP"
			(at 1.1811 -2.7051 0)
			(unlocked yes)
			(layer "F.Fab")
			(hide yes)
			(effects
				(font
					(size 1.016 1.016)
					(thickness 0.1524)
				)
			)
		)
		(property "Device Type" "C402H22"
			(at 1.1811 -4.2291 0)
			(unlocked yes)
			(layer "F.Fab")
			(hide yes)
			(effects
				(font
					(size 1.016 1.016)
					(thickness 0.1524)
				)
			)
		)
		(duplicate_pad_numbers_are_jumpers no)
		(fp_rect
			(start -0.4318 0.9525)
			(end 0.4318 -0.9525)
			(stroke
				(width 0)
				(type default)
			)
			(fill no)
			(layer "F.CrtYd")
		)
		(fp_rect
			(start -0.4318 0.9525)
			(end 0.4318 -0.9525)
			(stroke
				(width 0)
				(type default)
			)
			(fill no)
			(layer "F.Fab")
		)
		(pad "1" smd custom
			(at 0 -0.4445)
			(size 0.1524 0.1524)
			(layers "F.Cu" "F.Mask" "F.Paste")
			(net "P12V")
			(options
				(clearance outline)
				(anchor circle)
			)
			(primitives
				(gr_poly
					(pts
						(arc
							(start 0.3048 -0.2032)
							(mid 0.275042 -0.275042)
							(end 0.2032 -0.3048)
						)
						(arc
							(start -0.2032 -0.3048)
							(mid -0.275042 -0.275042)
							(end -0.3048 -0.2032)
						)
						(arc
							(start -0.3048 0.2032)
							(mid -0.275042 0.275042)
							(end -0.2032 0.3048)
						)
						(arc
							(start 0.2032 0.3048)
							(mid 0.275042 0.275042)
							(end 0.3048 0.2032)
						)
					)
					(width 0)
					(fill yes)
				)
			)
		)
		(pad "2" smd custom
			(at 0 0.4445)
			(size 0.1524 0.1524)
			(layers "F.Cu" "F.Mask" "F.Paste")
			(net "SW_HDD4_N")
			(options
				(clearance outline)
				(anchor circle)
			)
			(primitives
				(gr_poly
					(pts
						(arc
							(start 0.3048 -0.2032)
							(mid 0.275042 -0.275042)
							(end 0.2032 -0.3048)
						)
						(arc
							(start -0.2032 -0.3048)
							(mid -0.275042 -0.275042)
							(end -0.3048 -0.2032)
						)
						(arc
							(start -0.3048 0.2032)
							(mid -0.275042 0.275042)
							(end -0.2032 0.3048)
						)
						(arc
							(start 0.2032 0.3048)
							(mid 0.275042 0.275042)
							(end 0.3048 0.2032)
						)
					)
					(width 0)
					(fill yes)
				)
			)
		)
	)
	(footprint ""
		(layer "F.Cu")
		(at 79.4512 -81.1022)
		(property "Reference" "C253"
			(at 0 0 0)
			(layer "F.SilkS")
			(hide yes)
			(effects
				(font
					(size 1.27 1.27)
				)
			)
		)
		(property "Value" "SCD1U10V2KX-5GP"
			(at 1.1811 -2.7051 0)
			(unlocked yes)
			(layer "F.Fab")
			(hide yes)
			(effects
				(font
					(size 1.016 1.016)
					(thickness 0.1524)
				)
			)
		)
		(property "Device Type" "C402H22"
			(at 1.1811 -4.2291 0)
			(unlocked yes)
			(layer "F.Fab")
			(hide yes)
			(effects
				(font
					(size 1.016 1.016)
					(thickness 0.1524)
				)
			)
		)
		(duplicate_pad_numbers_are_jumpers no)
		(fp_rect
			(start -0.4318 0.9525)
			(end 0.4318 -0.9525)
			(stroke
				(width 0)
				(type default)
			)
			(fill no)
			(layer "F.CrtYd")
		)
		(fp_rect
			(start -0.4318 0.9525)
			(end 0.4318 -0.9525)
			(stroke
				(width 0)
				(type default)
			)
			(fill no)
			(layer "F.Fab")
		)
		(pad "1" smd custom
			(at 0 -0.4445)
			(size 0.1524 0.1524)
			(layers "F.Cu" "F.Mask" "F.Paste")
			(net "P3V3")
			(options
				(clearance outline)
				(anchor circle)
			)
			(primitives
				(gr_poly
					(pts
						(arc
							(start 0.3048 -0.2032)
							(mid 0.275042 -0.275042)
							(end 0.2032 -0.3048)
						)
						(arc
							(start -0.2032 -0.3048)
							(mid -0.275042 -0.275042)
							(end -0.3048 -0.2032)
						)
						(arc
							(start -0.3048 0.2032)
							(mid -0.275042 0.275042)
							(end -0.2032 0.3048)
						)
						(arc
							(start 0.2032 0.3048)
							(mid 0.275042 0.275042)
							(end 0.3048 0.2032)
						)
					)
					(width 0)
					(fill yes)
				)
			)
		)
		(pad "2" smd custom
			(at 0 0.4445)
			(size 0.1524 0.1524)
			(layers "F.Cu" "F.Mask" "F.Paste")
			(net "GND")
			(options
				(clearance outline)
				(anchor circle)
			)
			(primitives
				(gr_poly
					(pts
						(arc
							(start 0.3048 -0.2032)
							(mid 0.275042 -0.275042)
							(end 0.2032 -0.3048)
						)
						(arc
							(start -0.2032 -0.3048)
							(mid -0.275042 -0.275042)
							(end -0.3048 -0.2032)
						)
						(arc
							(start -0.3048 0.2032)
							(mid -0.275042 0.275042)
							(end -0.2032 0.3048)
						)
						(arc
							(start 0.2032 0.3048)
							(mid 0.275042 0.275042)
							(end 0.3048 0.2032)
						)
					)
					(width 0)
					(fill yes)
				)
			)
		)
	)
	(footprint ""
		(layer "F.Cu")
		(at 89.153746 -16.3957 90)
		(property "Reference" "U43"
			(at 0 0 90)
			(layer "F.SilkS")
			(hide yes)
			(effects
				(font
					(size 1.27 1.27)
				)
			)
		)
		(property "Value" "74LVC1G08GW-1-GP"
			(at -2.3368 -8.6868 90)
			(unlocked yes)
			(layer "F.Fab")
			(hide yes)
			(effects
				(font
					(size 1.016 1.016)
					(thickness 0.1524)
				)
			)
		)
		(property "Device Type" "SC70-5H44"
			(at -2.3114 -10.414 90)
			(unlocked yes)
			(layer "F.Fab")
			(hide yes)
			(effects
				(font
					(size 1.016 1.016)
					(thickness 0.1524)
				)
			)
		)
		(duplicate_pad_numbers_are_jumpers no)
		(fp_line
			(start 1.3843 -1.8034)
			(end 1.3843 -1.1176)
			(stroke
				(width 0.3302)
				(type default)
			)
			(layer "F.SilkS")
		)
		(fp_line
			(start 0.6604 -1.8034)
			(end 1.3843 -1.8034)
			(stroke
				(width 0.3302)
				(type default)
			)
			(layer "F.SilkS")
		)
		(fp_line
			(start 1.27 -1.7018)
			(end 1.27 1.7018)
			(stroke
				(width 0.1524)
				(type default)
			)
			(layer "F.SilkS")
		)
		(fp_line
			(start -1.27 -1.7018)
			(end 1.27 -1.7018)
			(stroke
				(width 0.1524)
				(type default)
			)
			(layer "F.SilkS")
		)
		(fp_line
			(start 1.27 1.7018)
			(end -1.27 1.7018)
			(stroke
				(width 0.1524)
				(type default)
			)
			(layer "F.SilkS")
		)
		(fp_line
			(start -1.27 1.7018)
			(end -1.27 -1.7018)
			(stroke
				(width 0.1524)
				(type default)
			)
			(layer "F.SilkS")
		)
		(fp_rect
			(start -1.524 1.9558)
			(end 1.524 -1.9558)
			(stroke
				(width 0)
				(type default)
			)
			(fill no)
			(layer "F.CrtYd")
		)
		(fp_poly
			(pts
				(xy -1.524 -1.9558) (xy 1.524 -1.9558) (xy 1.524 1.9558) (xy -1.524 1.9558)
			)
			(stroke
				(width 0)
				(type default)
			)
			(fill no)
			(layer "F.Fab")
		)
		(pad "1" smd rect
			(at 0.65024 -0.8255 90)
			(size 0.4064 1.2192)
			(layers "F.Cu" "F.Mask" "F.Paste")
			(net "SAS2X28_B_HDD14_FLT")
		)
		(pad "2" smd rect
			(at 0 -0.8255 90)
			(size 0.4064 1.2192)
			(layers "F.Cu" "F.Mask" "F.Paste")
			(net "SAS2X28_A_HDD14_FLT")
		)
		(pad "3" smd rect
			(at -0.65024 -0.8255 90)
			(size 0.4064 1.2192)
			(layers "F.Cu" "F.Mask" "F.Paste")
			(net "GND")
		)
		(pad "4" smd rect
			(at -0.65024 0.8255 90)
			(size 0.4064 1.2192)
			(layers "F.Cu" "F.Mask" "F.Paste")
			(net "FLT_HDD14_DRIVE")
		)
		(pad "5" smd rect
			(at 0.65024 0.8255 90)
			(size 0.4064 1.2192)
			(layers "F.Cu" "F.Mask" "F.Paste")
			(net "P3V3")
		)
	)
	(footprint ""
		(layer "F.Cu")
		(at 60.5282 -272.17624 90)
		(property "Reference" "Q60"
			(at 0 0 90)
			(layer "F.SilkS")
			(hide yes)
			(effects
				(font
					(size 1.27 1.27)
				)
			)
		)
		(property "Value" "2N7002DW-7F-GP"
			(at -2.3622 -8.2042 90)
			(unlocked yes)
			(layer "F.Fab")
			(hide yes)
			(effects
				(font
					(size 1.016 1.016)
					(thickness 0.1524)
				)
			)
		)
		(property "Device Type" "SOT-363H44"
			(at -2.3622 -10.1092 90)
			(unlocked yes)
			(layer "F.Fab")
			(hide yes)
			(effects
				(font
					(size 1.016 1.016)
					(thickness 0.1524)
				)
			)
		)
		(duplicate_pad_numbers_are_jumpers no)
		(fp_line
			(start 1.4478 -1.7018)
			(end -1.4478 -1.7018)
			(stroke
				(width 0.1524)
				(type default)
			)
			(layer "F.SilkS")
		)
		(fp_line
			(start -1.4478 -1.7018)
			(end -1.4478 1.7018)
			(stroke
				(width 0.1524)
				(type default)
			)
			(layer "F.SilkS")
		)
		(fp_line
			(start -1.27 1.524)
			(end -1.27 0.6604)
			(stroke
				(width 0.4826)
				(type default)
			)
			(layer "F.SilkS")
		)
		(fp_line
			(start 1.4478 1.7018)
			(end 1.4478 -1.7018)
			(stroke
				(width 0.1524)
				(type default)
			)
			(layer "F.SilkS")
		)
		(fp_line
			(start -1.4478 1.7018)
			(end 1.4478 1.7018)
			(stroke
				(width 0.1524)
				(type default)
			)
			(layer "F.SilkS")
		)
		(fp_poly
			(pts
				(xy -1.524 -1.778) (xy 1.524 -1.778) (xy 1.524 1.778) (xy -1.524 1.778)
			)
			(stroke
				(width 0)
				(type default)
			)
			(fill no)
			(layer "F.CrtYd")
		)
		(fp_poly
			(pts
				(xy -1.524 -1.778) (xy 1.524 -1.778) (xy 1.524 1.778) (xy -1.524 1.778)
			)
			(stroke
				(width 0)
				(type default)
			)
			(fill no)
			(layer "F.Fab")
		)
		(pad "1" smd rect
			(at -0.65024 0.9398 90)
			(size 0.4064 1.016)
			(layers "F.Cu" "F.Mask" "F.Paste")
			(net "P3V3_HDD7_LED")
		)
		(pad "2" smd rect
			(at 0 0.9398 90)
			(size 0.4064 1.016)
			(layers "F.Cu" "F.Mask" "F.Paste")
			(net "HDD7_LED_G")
		)
		(pad "3" smd rect
			(at 0.65024 0.9398 90)
			(size 0.4064 1.016)
			(layers "F.Cu" "F.Mask" "F.Paste")
			(net "P5VB")
		)
		(pad "4" smd rect
			(at 0.65024 -0.9398 90)
			(size 0.4064 1.016)
			(layers "F.Cu" "F.Mask" "F.Paste")
			(net "P5VB_HDD7_LED")
		)
		(pad "5" smd rect
			(at 0 -0.9398 90)
			(size 0.4064 1.016)
			(layers "F.Cu" "F.Mask" "F.Paste")
			(net "HDD7_LED_G")
		)
		(pad "6" smd rect
			(at -0.65024 -0.9398 90)
			(size 0.4064 1.016)
			(layers "F.Cu" "F.Mask" "F.Paste")
			(net "P3V3")
		)
	)
	(footprint ""
		(layer "F.Cu")
		(at 29.781246 -374.9167 90)
		(property "Reference" "R322"
			(at 0 0 90)
			(layer "F.SilkS")
			(hide yes)
			(effects
				(font
					(size 1.27 1.27)
				)
			)
		)
		(property "Value" "4K7R2J-2-GP"
			(at 0.064008 -3.993896 90)
			(unlocked yes)
			(layer "F.Fab")
			(hide yes)
			(effects
				(font
					(size 1.016 1.016)
					(thickness 0.1524)
				)
			)
		)
		(property "Device Type" "R402H16"
			(at 0.064008 -5.517896 90)
			(unlocked yes)
			(layer "F.Fab")
			(hide yes)
			(effects
				(font
					(size 1.016 1.016)
					(thickness 0.1524)
				)
			)
		)
		(duplicate_pad_numbers_are_jumpers no)
		(fp_line
			(start 0.508 -0.9398)
			(end -0.508 -0.9398)
			(stroke
				(width 0.1524)
				(type default)
			)
			(layer "F.SilkS")
		)
		(fp_line
			(start -0.508 -0.9398)
			(end -0.508 0.9398)
			(stroke
				(width 0.1524)
				(type default)
			)
			(layer "F.SilkS")
		)
		(fp_rect
			(start -0.508 0.9398)
			(end 0.508 -0.9398)
			(stroke
				(width 0)
				(type default)
			)
			(fill no)
			(layer "F.CrtYd")
		)
		(fp_rect
			(start -0.508 0.9398)
			(end 0.508 -0.9398)
			(stroke
				(width 0)
				(type default)
			)
			(fill no)
			(layer "F.Fab")
		)
		(pad "1" smd custom
			(at 0 -0.4445 90)
			(size 0.1397 0.1397)
			(layers "F.Cu" "F.Mask" "F.Paste")
			(net "I2C_B_TMP1_A0")
			(options
				(clearance outline)
				(anchor circle)
			)
			(primitives
				(gr_poly
					(pts
						(arc
							(start -0.1778 -0.2794)
							(mid -0.249642 -0.249642)
							(end -0.2794 -0.1778)
						)
						(arc
							(start -0.2794 0.1778)
							(mid -0.249642 0.249642)
							(end -0.1778 0.2794)
						)
						(arc
							(start 0.1778 0.2794)
							(mid 0.249642 0.249642)
							(end 0.2794 0.1778)
						)
						(arc
							(start 0.2794 -0.1778)
							(mid 0.249642 -0.249642)
							(end 0.1778 -0.2794)
						)
					)
					(width 0)
					(fill yes)
				)
			)
		)
		(pad "2" smd custom
			(at 0 0.4445 90)
			(size 0.1397 0.1397)
			(layers "F.Cu" "F.Mask" "F.Paste")
			(net "GND")
			(options
				(clearance outline)
				(anchor circle)
			)
			(primitives
				(gr_poly
					(pts
						(arc
							(start -0.1778 -0.2794)
							(mid -0.249642 -0.249642)
							(end -0.2794 -0.1778)
						)
						(arc
							(start -0.2794 0.1778)
							(mid -0.249642 0.249642)
							(end -0.1778 0.2794)
						)
						(arc
							(start 0.1778 0.2794)
							(mid 0.249642 0.249642)
							(end 0.2794 0.1778)
						)
						(arc
							(start 0.2794 -0.1778)
							(mid 0.249642 -0.249642)
							(end 0.1778 -0.2794)
						)
					)
					(width 0)
					(fill yes)
				)
			)
		)
	)
	(footprint ""
		(layer "F.Cu")
		(at 26.288746 -330.101702 180)
		(property "Reference" "C286"
			(at 0 0 180)
			(layer "F.SilkS")
			(hide yes)
			(effects
				(font
					(size 1.27 1.27)
				)
			)
		)
		(property "Value" "SCD01U50V2KX-1GP"
			(at 1.1811 -2.7051 180)
			(unlocked yes)
			(layer "F.Fab")
			(hide yes)
			(effects
				(font
					(size 1.016 1.016)
					(thickness 0.1524)
				)
			)
		)
		(property "Device Type" "C402H22"
			(at 1.1811 -4.2291 180)
			(unlocked yes)
			(layer "F.Fab")
			(hide yes)
			(effects
				(font
					(size 1.016 1.016)
					(thickness 0.1524)
				)
			)
		)
		(duplicate_pad_numbers_are_jumpers no)
		(fp_rect
			(start -0.4318 0.9525)
			(end 0.4318 -0.9525)
			(stroke
				(width 0)
				(type default)
			)
			(fill no)
			(layer "F.CrtYd")
		)
		(fp_rect
			(start -0.4318 0.9525)
			(end 0.4318 -0.9525)
			(stroke
				(width 0)
				(type default)
			)
			(fill no)
			(layer "F.Fab")
		)
		(pad "1" smd custom
			(at 0 -0.4445 180)
			(size 0.1524 0.1524)
			(layers "F.Cu" "F.Mask" "F.Paste")
			(net "HDD_PRSNT_NET11")
			(options
				(clearance outline)
				(anchor circle)
			)
			(primitives
				(gr_poly
					(pts
						(arc
							(start 0.3048 -0.2032)
							(mid 0.275042 -0.275042)
							(end 0.2032 -0.3048)
						)
						(arc
							(start -0.2032 -0.3048)
							(mid -0.275042 -0.275042)
							(end -0.3048 -0.2032)
						)
						(arc
							(start -0.3048 0.2032)
							(mid -0.275042 0.275042)
							(end -0.2032 0.3048)
						)
						(arc
							(start 0.2032 0.3048)
							(mid 0.275042 0.275042)
							(end 0.3048 0.2032)
						)
					)
					(width 0)
					(fill yes)
				)
			)
		)
		(pad "2" smd custom
			(at 0 0.4445 180)
			(size 0.1524 0.1524)
			(layers "F.Cu" "F.Mask" "F.Paste")
			(net "GND")
			(options
				(clearance outline)
				(anchor circle)
			)
			(primitives
				(gr_poly
					(pts
						(arc
							(start 0.3048 -0.2032)
							(mid 0.275042 -0.275042)
							(end 0.2032 -0.3048)
						)
						(arc
							(start -0.2032 -0.3048)
							(mid -0.275042 -0.275042)
							(end -0.3048 -0.2032)
						)
						(arc
							(start -0.3048 0.2032)
							(mid -0.275042 0.275042)
							(end -0.2032 0.3048)
						)
						(arc
							(start 0.2032 0.3048)
							(mid 0.275042 0.275042)
							(end 0.3048 0.2032)
						)
					)
					(width 0)
					(fill yes)
				)
			)
		)
	)
	(footprint ""
		(layer "F.Cu")
		(at 28.320746 -373.4562 180)
		(property "Reference" "R312"
			(at 0 0 180)
			(layer "F.SilkS")
			(hide yes)
			(effects
				(font
					(size 1.27 1.27)
				)
			)
		)
		(property "Value" "4K7R2J-2-GP"
			(at 0.064008 -3.993896 180)
			(unlocked yes)
			(layer "F.Fab")
			(hide yes)
			(effects
				(font
					(size 1.016 1.016)
					(thickness 0.1524)
				)
			)
		)
		(property "Device Type" "R402H16"
			(at 0.064008 -5.517896 180)
			(unlocked yes)
			(layer "F.Fab")
			(hide yes)
			(effects
				(font
					(size 1.016 1.016)
					(thickness 0.1524)
				)
			)
		)
		(duplicate_pad_numbers_are_jumpers no)
		(fp_line
			(start 0.508 -0.9398)
			(end -0.508 -0.9398)
			(stroke
				(width 0.1524)
				(type default)
			)
			(layer "F.SilkS")
		)
		(fp_line
			(start -0.508 -0.9398)
			(end -0.508 0.9398)
			(stroke
				(width 0.1524)
				(type default)
			)
			(layer "F.SilkS")
		)
		(fp_rect
			(start -0.508 0.9398)
			(end 0.508 -0.9398)
			(stroke
				(width 0)
				(type default)
			)
			(fill no)
			(layer "F.CrtYd")
		)
		(fp_rect
			(start -0.508 0.9398)
			(end 0.508 -0.9398)
			(stroke
				(width 0)
				(type default)
			)
			(fill no)
			(layer "F.Fab")
		)
		(pad "1" smd custom
			(at 0 -0.4445 180)
			(size 0.1397 0.1397)
			(layers "F.Cu" "F.Mask" "F.Paste")
			(net "P3V3")
			(options
				(clearance outline)
				(anchor circle)
			)
			(primitives
				(gr_poly
					(pts
						(arc
							(start -0.1778 -0.2794)
							(mid -0.249642 -0.249642)
							(end -0.2794 -0.1778)
						)
						(arc
							(start -0.2794 0.1778)
							(mid -0.249642 0.249642)
							(end -0.1778 0.2794)
						)
						(arc
							(start 0.1778 0.2794)
							(mid 0.249642 0.249642)
							(end 0.2794 0.1778)
						)
						(arc
							(start 0.2794 -0.1778)
							(mid 0.249642 -0.249642)
							(end 0.1778 -0.2794)
						)
					)
					(width 0)
					(fill yes)
				)
			)
		)
		(pad "2" smd custom
			(at 0 0.4445 180)
			(size 0.1397 0.1397)
			(layers "F.Cu" "F.Mask" "F.Paste")
			(net "I2C_B_TMP1_A1")
			(options
				(clearance outline)
				(anchor circle)
			)
			(primitives
				(gr_poly
					(pts
						(arc
							(start -0.1778 -0.2794)
							(mid -0.249642 -0.249642)
							(end -0.2794 -0.1778)
						)
						(arc
							(start -0.2794 0.1778)
							(mid -0.249642 0.249642)
							(end -0.1778 0.2794)
						)
						(arc
							(start 0.1778 0.2794)
							(mid 0.249642 0.249642)
							(end 0.2794 0.1778)
						)
						(arc
							(start 0.2794 -0.1778)
							(mid 0.249642 -0.249642)
							(end 0.1778 -0.2794)
						)
					)
					(width 0)
					(fill yes)
				)
			)
		)
	)
	(footprint ""
		(layer "F.Cu")
		(at 212.09 -274.193 180)
		(property "Reference" "Q51"
			(at 0 0 180)
			(layer "F.SilkS")
			(hide yes)
			(effects
				(font
					(size 1.27 1.27)
				)
			)
		)
		(property "Value" "2N7002-11-GP"
			(at 0.127 -8.9662 180)
			(unlocked yes)
			(layer "F.Fab")
			(hide yes)
			(effects
				(font
					(size 1.016 1.016)
					(thickness 0.1524)
				)
			)
		)
		(property "Device Type" "SOT23DGS2D4H44"
			(at 0.127 -10.4902 180)
			(unlocked yes)
			(layer "F.Fab")
			(hide yes)
			(effects
				(font
					(size 1.016 1.016)
					(thickness 0.1524)
				)
			)
		)
		(duplicate_pad_numbers_are_jumpers no)
		(fp_line
			(start 1.651 1.778)
			(end 1.651 -1.778)
			(stroke
				(width 0.1524)
				(type default)
			)
			(layer "F.SilkS")
		)
		(fp_line
			(start 1.651 -1.778)
			(end -1.651 -1.778)
			(stroke
				(width 0.1524)
				(type default)
			)
			(layer "F.SilkS")
		)
		(fp_line
			(start -1.651 1.778)
			(end 1.651 1.778)
			(stroke
				(width 0.1524)
				(type default)
			)
			(layer "F.SilkS")
		)
		(fp_line
			(start -1.651 -1.778)
			(end -1.651 1.778)
			(stroke
				(width 0.1524)
				(type default)
			)
			(layer "F.SilkS")
		)
		(fp_poly
			(pts
				(xy -1.778 1.8796) (xy -1.778 -1.8796) (xy 1.778 -1.8796) (xy 1.778 1.8796)
			)
			(stroke
				(width 0)
				(type default)
			)
			(fill no)
			(layer "F.CrtYd")
		)
		(fp_poly
			(pts
				(xy -1.778 1.8796) (xy -1.778 -1.8796) (xy 1.778 -1.8796) (xy 1.778 1.8796)
			)
			(stroke
				(width 0)
				(type default)
			)
			(fill no)
			(layer "F.Fab")
		)
		(pad "D" smd custom
			(at 0 -0.9525 180)
			(size 0.1905 0.1905)
			(layers "F.Cu" "F.Mask" "F.Paste")
			(net "HDD2_LED_G")
			(options
				(clearance outline)
				(anchor circle)
			)
			(primitives
				(gr_poly
					(pts
						(arc
							(start -0.1778 0.5715)
							(mid -0.321484 0.511984)
							(end -0.381 0.3683)
						)
						(arc
							(start -0.381 -0.3683)
							(mid -0.321484 -0.511984)
							(end -0.1778 -0.5715)
						)
						(arc
							(start 0.1778 -0.5715)
							(mid 0.321484 -0.511984)
							(end 0.381 -0.3683)
						)
						(arc
							(start 0.381 0.3683)
							(mid 0.321484 0.511984)
							(end 0.1778 0.5715)
						)
					)
					(width 0)
					(fill yes)
				)
			)
		)
		(pad "G" smd custom
			(at -0.98425 0.9525 180)
			(size 0.1905 0.1905)
			(layers "F.Cu" "F.Mask" "F.Paste")
			(net "HDD2_LED_B")
			(options
				(clearance outline)
				(anchor circle)
			)
			(primitives
				(gr_poly
					(pts
						(arc
							(start -0.1778 0.5715)
							(mid -0.321484 0.511984)
							(end -0.381 0.3683)
						)
						(arc
							(start -0.381 -0.3683)
							(mid -0.321484 -0.511984)
							(end -0.1778 -0.5715)
						)
						(arc
							(start 0.1778 -0.5715)
							(mid 0.321484 -0.511984)
							(end 0.381 -0.3683)
						)
						(arc
							(start 0.381 0.3683)
							(mid 0.321484 0.511984)
							(end 0.1778 0.5715)
						)
					)
					(width 0)
					(fill yes)
				)
			)
		)
		(pad "S" smd custom
			(at 0.98425 0.9525 180)
			(size 0.1905 0.1905)
			(layers "F.Cu" "F.Mask" "F.Paste")
			(net "GND")
			(options
				(clearance outline)
				(anchor circle)
			)
			(primitives
				(gr_poly
					(pts
						(arc
							(start -0.1778 0.5715)
							(mid -0.321484 0.511984)
							(end -0.381 0.3683)
						)
						(arc
							(start -0.381 -0.3683)
							(mid -0.321484 -0.511984)
							(end -0.1778 -0.5715)
						)
						(arc
							(start 0.1778 -0.5715)
							(mid 0.321484 -0.511984)
							(end 0.381 -0.3683)
						)
						(arc
							(start 0.381 0.3683)
							(mid 0.321484 0.511984)
							(end 0.1778 0.5715)
						)
					)
					(width 0)
					(fill yes)
				)
			)
		)
	)
	(footprint ""
		(layer "F.Cu")
		(at 28.320746 -323.116702)
		(property "Reference" "C285"
			(at 0 0 0)
			(layer "F.SilkS")
			(hide yes)
			(effects
				(font
					(size 1.27 1.27)
				)
			)
		)
		(property "Value" "SC10U16V6KX-2GP"
			(at -0.0762 -5.1308 0)
			(unlocked yes)
			(layer "F.Fab")
			(hide yes)
			(effects
				(font
					(size 1.016 1.016)
					(thickness 0.1524)
				)
			)
		)
		(property "Device Type" "C1206H71"
			(at -0.127 -6.6548 0)
			(unlocked yes)
			(layer "F.Fab")
			(hide yes)
			(effects
				(font
					(size 1.016 1.016)
					(thickness 0.1524)
				)
			)
		)
		(duplicate_pad_numbers_are_jumpers no)
		(fp_line
			(start -1.016 -2.2352)
			(end 1.016 -2.2352)
			(stroke
				(width 0.1524)
				(type default)
			)
			(layer "F.SilkS")
		)
		(fp_line
			(start -1.016 -0.8382)
			(end -1.016 -2.2352)
			(stroke
				(width 0.1524)
				(type default)
			)
			(layer "F.SilkS")
		)
		(fp_line
			(start -1.016 2.2352)
			(end -1.016 0.8382)
			(stroke
				(width 0.1524)
				(type default)
			)
			(layer "F.SilkS")
		)
		(fp_line
			(start 1.016 -2.2352)
			(end 1.016 -0.8382)
			(stroke
				(width 0.1524)
				(type default)
			)
			(layer "F.SilkS")
		)
		(fp_line
			(start 1.016 0.8382)
			(end 1.016 2.2352)
			(stroke
				(width 0.1524)
				(type default)
			)
			(layer "F.SilkS")
		)
		(fp_line
			(start 1.016 2.2352)
			(end -1.016 2.2352)
			(stroke
				(width 0.1524)
				(type default)
			)
			(layer "F.SilkS")
		)
		(fp_rect
			(start -1.0922 2.3114)
			(end 1.0922 -2.3114)
			(stroke
				(width 0)
				(type default)
			)
			(fill no)
			(layer "F.CrtYd")
		)
		(fp_poly
			(pts
				(xy 1.0922 -2.3114) (xy 1.0922 2.3114) (xy -1.0922 2.3114) (xy -1.0922 -2.3114)
			)
			(stroke
				(width 0)
				(type default)
			)
			(fill no)
			(layer "F.Fab")
		)
		(pad "1" smd rect
			(at 0 -1.397)
			(size 1.651 1.27)
			(layers "F.Cu" "F.Mask" "F.Paste")
			(net "P5V_HDD11")
		)
		(pad "2" smd rect
			(at 0 1.397)
			(size 1.651 1.27)
			(layers "F.Cu" "F.Mask" "F.Paste")
			(net "GND")
		)
	)
	(footprint ""
		(layer "F.Cu")
		(at 36.4998 -337.0834 90)
		(property "Reference" "Q68"
			(at 0 0 90)
			(layer "F.SilkS")
			(hide yes)
			(effects
				(font
					(size 1.27 1.27)
				)
			)
		)
		(property "Value" "2N7002DW-7F-GP"
			(at -2.3622 -8.2042 90)
			(unlocked yes)
			(layer "F.Fab")
			(hide yes)
			(effects
				(font
					(size 1.016 1.016)
					(thickness 0.1524)
				)
			)
		)
		(property "Device Type" "SOT-363H44"
			(at -2.3622 -10.1092 90)
			(unlocked yes)
			(layer "F.Fab")
			(hide yes)
			(effects
				(font
					(size 1.016 1.016)
					(thickness 0.1524)
				)
			)
		)
		(duplicate_pad_numbers_are_jumpers no)
		(fp_line
			(start 1.4478 -1.7018)
			(end -1.4478 -1.7018)
			(stroke
				(width 0.1524)
				(type default)
			)
			(layer "F.SilkS")
		)
		(fp_line
			(start -1.4478 -1.7018)
			(end -1.4478 1.7018)
			(stroke
				(width 0.1524)
				(type default)
			)
			(layer "F.SilkS")
		)
		(fp_line
			(start -1.27 1.524)
			(end -1.27 0.6604)
			(stroke
				(width 0.4826)
				(type default)
			)
			(layer "F.SilkS")
		)
		(fp_line
			(start 1.4478 1.7018)
			(end 1.4478 -1.7018)
			(stroke
				(width 0.1524)
				(type default)
			)
			(layer "F.SilkS")
		)
		(fp_line
			(start -1.4478 1.7018)
			(end 1.4478 1.7018)
			(stroke
				(width 0.1524)
				(type default)
			)
			(layer "F.SilkS")
		)
		(fp_poly
			(pts
				(xy -1.524 -1.778) (xy 1.524 -1.778) (xy 1.524 1.778) (xy -1.524 1.778)
			)
			(stroke
				(width 0)
				(type default)
			)
			(fill no)
			(layer "F.CrtYd")
		)
		(fp_poly
			(pts
				(xy -1.524 -1.778) (xy 1.524 -1.778) (xy 1.524 1.778) (xy -1.524 1.778)
			)
			(stroke
				(width 0)
				(type default)
			)
			(fill no)
			(layer "F.Fab")
		)
		(pad "1" smd rect
			(at -0.65024 0.9398 90)
			(size 0.4064 1.016)
			(layers "F.Cu" "F.Mask" "F.Paste")
			(net "P3V3_HDD11_LED")
		)
		(pad "2" smd rect
			(at 0 0.9398 90)
			(size 0.4064 1.016)
			(layers "F.Cu" "F.Mask" "F.Paste")
			(net "HDD11_LED_G")
		)
		(pad "3" smd rect
			(at 0.65024 0.9398 90)
			(size 0.4064 1.016)
			(layers "F.Cu" "F.Mask" "F.Paste")
			(net "P5VC")
		)
		(pad "4" smd rect
			(at 0.65024 -0.9398 90)
			(size 0.4064 1.016)
			(layers "F.Cu" "F.Mask" "F.Paste")
			(net "P5VC_HDD11_LED")
		)
		(pad "5" smd rect
			(at 0 -0.9398 90)
			(size 0.4064 1.016)
			(layers "F.Cu" "F.Mask" "F.Paste")
			(net "HDD11_LED_G")
		)
		(pad "6" smd rect
			(at -0.65024 -0.9398 90)
			(size 0.4064 1.016)
			(layers "F.Cu" "F.Mask" "F.Paste")
			(net "P3V3")
		)
	)
	(footprint ""
		(layer "F.Cu")
		(at 80.7466 -26.7208 -90)
		(property "Reference" "R405"
			(at 0 0 270)
			(layer "F.SilkS")
			(hide yes)
			(effects
				(font
					(size 1.27 1.27)
				)
			)
		)
		(property "Value" "10KR2F-2-GP"
			(at 0.064008 -3.993896 270)
			(unlocked yes)
			(layer "F.Fab")
			(hide yes)
			(effects
				(font
					(size 1.016 1.016)
					(thickness 0.1524)
				)
			)
		)
		(property "Device Type" "R402H16"
			(at 0.064008 -5.517896 270)
			(unlocked yes)
			(layer "F.Fab")
			(hide yes)
			(effects
				(font
					(size 1.016 1.016)
					(thickness 0.1524)
				)
			)
		)
		(duplicate_pad_numbers_are_jumpers no)
		(fp_line
			(start -0.508 -0.9398)
			(end -0.508 0.9398)
			(stroke
				(width 0.1524)
				(type default)
			)
			(layer "F.SilkS")
		)
		(fp_line
			(start 0.508 -0.9398)
			(end -0.508 -0.9398)
			(stroke
				(width 0.1524)
				(type default)
			)
			(layer "F.SilkS")
		)
		(fp_rect
			(start -0.508 0.9398)
			(end 0.508 -0.9398)
			(stroke
				(width 0)
				(type default)
			)
			(fill no)
			(layer "F.CrtYd")
		)
		(fp_rect
			(start -0.508 0.9398)
			(end 0.508 -0.9398)
			(stroke
				(width 0)
				(type default)
			)
			(fill no)
			(layer "F.Fab")
		)
		(pad "1" smd custom
			(at 0 -0.4445 270)
			(size 0.1397 0.1397)
			(layers "F.Cu" "F.Mask" "F.Paste")
			(net "P12V")
			(options
				(clearance outline)
				(anchor circle)
			)
			(primitives
				(gr_poly
					(pts
						(arc
							(start -0.1778 -0.2794)
							(mid -0.249642 -0.249642)
							(end -0.2794 -0.1778)
						)
						(arc
							(start -0.2794 0.1778)
							(mid -0.249642 0.249642)
							(end -0.1778 0.2794)
						)
						(arc
							(start 0.1778 0.2794)
							(mid 0.249642 0.249642)
							(end 0.2794 0.1778)
						)
						(arc
							(start 0.2794 -0.1778)
							(mid 0.249642 -0.249642)
							(end 0.1778 -0.2794)
						)
					)
					(width 0)
					(fill yes)
				)
			)
		)
		(pad "2" smd custom
			(at 0 0.4445 270)
			(size 0.1397 0.1397)
			(layers "F.Cu" "F.Mask" "F.Paste")
			(net "HDD14_LED_G")
			(options
				(clearance outline)
				(anchor circle)
			)
			(primitives
				(gr_poly
					(pts
						(arc
							(start -0.1778 -0.2794)
							(mid -0.249642 -0.249642)
							(end -0.2794 -0.1778)
						)
						(arc
							(start -0.2794 0.1778)
							(mid -0.249642 0.249642)
							(end -0.1778 0.2794)
						)
						(arc
							(start 0.1778 0.2794)
							(mid 0.249642 0.249642)
							(end 0.2794 0.1778)
						)
						(arc
							(start 0.2794 -0.1778)
							(mid 0.249642 -0.249642)
							(end 0.1778 -0.2794)
						)
					)
					(width 0)
					(fill yes)
				)
			)
		)
	)
	(footprint ""
		(layer "F.Cu")
		(at 240.284 -375.285 -90)
		(property "Reference" "C349"
			(at 0 0 270)
			(layer "F.SilkS")
			(hide yes)
			(effects
				(font
					(size 1.27 1.27)
				)
			)
		)
		(property "Value" "SC10U25V6KX-1GP"
			(at -0.0762 -5.1308 270)
			(unlocked yes)
			(layer "F.Fab")
			(hide yes)
			(effects
				(font
					(size 1.016 1.016)
					(thickness 0.1524)
				)
			)
		)
		(property "Device Type" "C1206H71"
			(at -0.127 -6.6548 270)
			(unlocked yes)
			(layer "F.Fab")
			(hide yes)
			(effects
				(font
					(size 1.016 1.016)
					(thickness 0.1524)
				)
			)
		)
		(duplicate_pad_numbers_are_jumpers no)
		(fp_line
			(start -1.016 2.2352)
			(end -1.016 0.8382)
			(stroke
				(width 0.1524)
				(type default)
			)
			(layer "F.SilkS")
		)
		(fp_line
			(start 1.016 2.2352)
			(end -1.016 2.2352)
			(stroke
				(width 0.1524)
				(type default)
			)
			(layer "F.SilkS")
		)
		(fp_line
			(start 1.016 0.8382)
			(end 1.016 2.2352)
			(stroke
				(width 0.1524)
				(type default)
			)
			(layer "F.SilkS")
		)
		(fp_line
			(start -1.016 -0.8382)
			(end -1.016 -2.2352)
			(stroke
				(width 0.1524)
				(type default)
			)
			(layer "F.SilkS")
		)
		(fp_line
			(start -1.016 -2.2352)
			(end 1.016 -2.2352)
			(stroke
				(width 0.1524)
				(type default)
			)
			(layer "F.SilkS")
		)
		(fp_line
			(start 1.016 -2.2352)
			(end 1.016 -0.8382)
			(stroke
				(width 0.1524)
				(type default)
			)
			(layer "F.SilkS")
		)
		(fp_rect
			(start -1.0922 2.3114)
			(end 1.0922 -2.3114)
			(stroke
				(width 0)
				(type default)
			)
			(fill no)
			(layer "F.CrtYd")
		)
		(fp_poly
			(pts
				(xy 1.0922 -2.3114) (xy 1.0922 2.3114) (xy -1.0922 2.3114) (xy -1.0922 -2.3114)
			)
			(stroke
				(width 0)
				(type default)
			)
			(fill no)
			(layer "F.Fab")
		)
		(pad "1" smd rect
			(at 0 -1.397 270)
			(size 1.651 1.27)
			(layers "F.Cu" "F.Mask" "F.Paste")
			(net "P12V")
		)
		(pad "2" smd rect
			(at 0 1.397 270)
			(size 1.651 1.27)
			(layers "F.Cu" "F.Mask" "F.Paste")
			(net "GND")
		)
	)
	(footprint ""
		(layer "F.Cu")
		(at 54.355746 -10.0457)
		(property "Reference" "PL3"
			(at 0 0 0)
			(layer "F.SilkS")
			(hide yes)
			(effects
				(font
					(size 1.27 1.27)
				)
			)
		)
		(property "Value" "BLM41PG600-GP"
			(at -3.690874 -7.441184 0)
			(unlocked yes)
			(layer "F.Fab")
			(hide yes)
			(effects
				(font
					(size 1.016 1.016)
					(thickness 0.1524)
				)
			)
		)
		(property "Device Type" "L451616H71"
			(at -3.690874 -5.917184 0)
			(unlocked yes)
			(layer "F.Fab")
			(hide yes)
			(effects
				(font
					(size 1.016 1.016)
					(thickness 0.1524)
				)
			)
		)
		(duplicate_pad_numbers_are_jumpers no)
		(fp_line
			(start -2.8702 -1.2954)
			(end -2.8702 1.2954)
			(stroke
				(width 0.1524)
				(type default)
			)
			(layer "F.SilkS")
		)
		(fp_line
			(start -2.8702 -1.2954)
			(end -2.8702 1.2954)
			(stroke
				(width 0.1524)
				(type default)
			)
			(layer "F.SilkS")
		)
		(fp_line
			(start -2.8702 1.2954)
			(end 2.8702 1.2954)
			(stroke
				(width 0.1524)
				(type default)
			)
			(layer "F.SilkS")
		)
		(fp_line
			(start -2.8702 1.2954)
			(end 2.8702 1.2954)
			(stroke
				(width 0.1524)
				(type default)
			)
			(layer "F.SilkS")
		)
		(fp_line
			(start 2.8702 -1.2954)
			(end -2.8702 -1.2954)
			(stroke
				(width 0.1524)
				(type default)
			)
			(layer "F.SilkS")
		)
		(fp_line
			(start 2.8702 -1.2954)
			(end -2.8702 -1.2954)
			(stroke
				(width 0.1524)
				(type default)
			)
			(layer "F.SilkS")
		)
		(fp_line
			(start 2.8702 1.2954)
			(end 2.8702 -1.2954)
			(stroke
				(width 0.1524)
				(type default)
			)
			(layer "F.SilkS")
		)
		(fp_line
			(start 2.8702 1.2954)
			(end 2.8702 -1.2954)
			(stroke
				(width 0.1524)
				(type default)
			)
			(layer "F.SilkS")
		)
		(fp_poly
			(pts
				(xy -2.8702 1.2954) (xy 2.8702 1.2954) (xy 2.8702 -1.2954) (xy -2.8702 -1.2954)
			)
			(stroke
				(width 0)
				(type default)
			)
			(fill no)
			(layer "F.CrtYd")
		)
		(fp_poly
			(pts
				(xy -2.8702 1.2954) (xy 2.8702 1.2954) (xy 2.8702 -1.2954) (xy -2.8702 -1.2954)
			)
			(stroke
				(width 0)
				(type default)
			)
			(fill no)
			(layer "F.Fab")
		)
		(pad "1" smd rect
			(at -1.9685 0)
			(size 1.3716 1.8796)
			(layers "F.Cu" "F.Mask" "F.Paste")
			(net "P12V")
		)
		(pad "2" smd rect
			(at 1.9685 0)
			(size 1.3716 1.8796)
			(layers "F.Cu" "F.Mask" "F.Paste")
			(net "P5VB_12VIN")
		)
	)
	(footprint ""
		(layer "F.Cu")
		(at 215.265 -70.3072 -90)
		(property "Reference" "R374"
			(at 0 0 270)
			(layer "F.SilkS")
			(hide yes)
			(effects
				(font
					(size 1.27 1.27)
				)
			)
		)
		(property "Value" "0R2J-2-GP"
			(at 0.064008 -3.993896 270)
			(unlocked yes)
			(layer "F.Fab")
			(hide yes)
			(effects
				(font
					(size 1.016 1.016)
					(thickness 0.1524)
				)
			)
		)
		(property "Device Type" "R402H16"
			(at 0.064008 -5.517896 270)
			(unlocked yes)
			(layer "F.Fab")
			(hide yes)
			(effects
				(font
					(size 1.016 1.016)
					(thickness 0.1524)
				)
			)
		)
		(duplicate_pad_numbers_are_jumpers no)
		(fp_line
			(start -0.508 -0.9398)
			(end -0.508 0.9398)
			(stroke
				(width 0.1524)
				(type default)
			)
			(layer "F.SilkS")
		)
		(fp_line
			(start 0.508 -0.9398)
			(end -0.508 -0.9398)
			(stroke
				(width 0.1524)
				(type default)
			)
			(layer "F.SilkS")
		)
		(fp_rect
			(start -0.508 0.9398)
			(end 0.508 -0.9398)
			(stroke
				(width 0)
				(type default)
			)
			(fill no)
			(layer "F.CrtYd")
		)
		(fp_rect
			(start -0.508 0.9398)
			(end 0.508 -0.9398)
			(stroke
				(width 0)
				(type default)
			)
			(fill no)
			(layer "F.Fab")
		)
		(pad "1" smd custom
			(at 0 -0.4445 270)
			(size 0.1397 0.1397)
			(layers "F.Cu" "F.Mask" "F.Paste")
			(net "HDD_PRSNT_NET4")
			(options
				(clearance outline)
				(anchor circle)
			)
			(primitives
				(gr_poly
					(pts
						(arc
							(start -0.1778 -0.2794)
							(mid -0.249642 -0.249642)
							(end -0.2794 -0.1778)
						)
						(arc
							(start -0.2794 0.1778)
							(mid -0.249642 0.249642)
							(end -0.1778 0.2794)
						)
						(arc
							(start 0.1778 0.2794)
							(mid 0.249642 0.249642)
							(end 0.2794 0.1778)
						)
						(arc
							(start 0.2794 -0.1778)
							(mid 0.249642 -0.249642)
							(end 0.1778 -0.2794)
						)
					)
					(width 0)
					(fill yes)
				)
			)
		)
		(pad "2" smd custom
			(at 0 0.4445 270)
			(size 0.1397 0.1397)
			(layers "F.Cu" "F.Mask" "F.Paste")
			(net "HDD4_LED_B")
			(options
				(clearance outline)
				(anchor circle)
			)
			(primitives
				(gr_poly
					(pts
						(arc
							(start -0.1778 -0.2794)
							(mid -0.249642 -0.249642)
							(end -0.2794 -0.1778)
						)
						(arc
							(start -0.2794 0.1778)
							(mid -0.249642 0.249642)
							(end -0.1778 0.2794)
						)
						(arc
							(start 0.1778 0.2794)
							(mid 0.249642 0.249642)
							(end 0.2794 0.1778)
						)
						(arc
							(start 0.2794 -0.1778)
							(mid 0.249642 -0.249642)
							(end 0.1778 -0.2794)
						)
					)
					(width 0)
					(fill yes)
				)
			)
		)
	)
	(footprint ""
		(layer "F.Cu")
		(at 45.339 -431.673 180)
		(property "Reference" "C374"
			(at 0 0 180)
			(layer "F.SilkS")
			(hide yes)
			(effects
				(font
					(size 1.27 1.27)
				)
			)
		)
		(property "Value" "SCD033U25V2KX-GP"
			(at 1.1811 -2.7051 180)
			(unlocked yes)
			(layer "F.Fab")
			(hide yes)
			(effects
				(font
					(size 1.016 1.016)
					(thickness 0.1524)
				)
			)
		)
		(property "Device Type" "C402H22"
			(at 1.1811 -4.2291 180)
			(unlocked yes)
			(layer "F.Fab")
			(hide yes)
			(effects
				(font
					(size 1.016 1.016)
					(thickness 0.1524)
				)
			)
		)
		(duplicate_pad_numbers_are_jumpers no)
		(fp_rect
			(start -0.4318 0.9525)
			(end 0.4318 -0.9525)
			(stroke
				(width 0)
				(type default)
			)
			(fill no)
			(layer "F.CrtYd")
		)
		(fp_rect
			(start -0.4318 0.9525)
			(end 0.4318 -0.9525)
			(stroke
				(width 0)
				(type default)
			)
			(fill no)
			(layer "F.Fab")
		)
		(pad "1" smd custom
			(at 0 -0.4445 180)
			(size 0.1524 0.1524)
			(layers "F.Cu" "F.Mask" "F.Paste")
			(net "SW_HDD10_P")
			(options
				(clearance outline)
				(anchor circle)
			)
			(primitives
				(gr_poly
					(pts
						(arc
							(start 0.3048 -0.2032)
							(mid 0.275042 -0.275042)
							(end 0.2032 -0.3048)
						)
						(arc
							(start -0.2032 -0.3048)
							(mid -0.275042 -0.275042)
							(end -0.3048 -0.2032)
						)
						(arc
							(start -0.3048 0.2032)
							(mid -0.275042 0.275042)
							(end -0.2032 0.3048)
						)
						(arc
							(start 0.2032 0.3048)
							(mid 0.275042 0.275042)
							(end 0.3048 0.2032)
						)
					)
					(width 0)
					(fill yes)
				)
			)
		)
		(pad "2" smd custom
			(at 0 0.4445 180)
			(size 0.1524 0.1524)
			(layers "F.Cu" "F.Mask" "F.Paste")
			(net "GND")
			(options
				(clearance outline)
				(anchor circle)
			)
			(primitives
				(gr_poly
					(pts
						(arc
							(start 0.3048 -0.2032)
							(mid 0.275042 -0.275042)
							(end 0.2032 -0.3048)
						)
						(arc
							(start -0.2032 -0.3048)
							(mid -0.275042 -0.275042)
							(end -0.3048 -0.2032)
						)
						(arc
							(start -0.3048 0.2032)
							(mid -0.275042 0.275042)
							(end -0.2032 0.3048)
						)
						(arc
							(start 0.2032 0.3048)
							(mid 0.275042 0.275042)
							(end 0.3048 0.2032)
						)
					)
					(width 0)
					(fill yes)
				)
			)
		)
	)
	(footprint ""
		(layer "F.Cu")
		(at 238.886746 -27.9527 180)
		(property "Reference" "PR16"
			(at 0 0 180)
			(layer "F.SilkS")
			(hide yes)
			(effects
				(font
					(size 1.27 1.27)
				)
			)
		)
		(property "Value" "0R2J-2-GP"
			(at 0.064008 -3.993896 180)
			(unlocked yes)
			(layer "F.Fab")
			(hide yes)
			(effects
				(font
					(size 1.016 1.016)
					(thickness 0.1524)
				)
			)
		)
		(property "Device Type" "R402H16"
			(at 0.064008 -5.517896 180)
			(unlocked yes)
			(layer "F.Fab")
			(hide yes)
			(effects
				(font
					(size 1.016 1.016)
					(thickness 0.1524)
				)
			)
		)
		(duplicate_pad_numbers_are_jumpers no)
		(fp_line
			(start 0.508 -0.9398)
			(end -0.508 -0.9398)
			(stroke
				(width 0.1524)
				(type default)
			)
			(layer "F.SilkS")
		)
		(fp_line
			(start -0.508 -0.9398)
			(end -0.508 0.9398)
			(stroke
				(width 0.1524)
				(type default)
			)
			(layer "F.SilkS")
		)
		(fp_rect
			(start -0.508 0.9398)
			(end 0.508 -0.9398)
			(stroke
				(width 0)
				(type default)
			)
			(fill no)
			(layer "F.CrtYd")
		)
		(fp_rect
			(start -0.508 0.9398)
			(end 0.508 -0.9398)
			(stroke
				(width 0)
				(type default)
			)
			(fill no)
			(layer "F.Fab")
		)
		(pad "1" smd custom
			(at 0 -0.4445 180)
			(size 0.1397 0.1397)
			(layers "F.Cu" "F.Mask" "F.Paste")
			(net "P5VA_RF")
			(options
				(clearance outline)
				(anchor circle)
			)
			(primitives
				(gr_poly
					(pts
						(arc
							(start -0.1778 -0.2794)
							(mid -0.249642 -0.249642)
							(end -0.2794 -0.1778)
						)
						(arc
							(start -0.2794 0.1778)
							(mid -0.249642 0.249642)
							(end -0.1778 0.2794)
						)
						(arc
							(start 0.1778 0.2794)
							(mid 0.249642 0.249642)
							(end 0.2794 0.1778)
						)
						(arc
							(start 0.2794 -0.1778)
							(mid 0.249642 -0.249642)
							(end 0.1778 -0.2794)
						)
					)
					(width 0)
					(fill yes)
				)
			)
		)
		(pad "2" smd custom
			(at 0 0.4445 180)
			(size 0.1397 0.1397)
			(layers "F.Cu" "F.Mask" "F.Paste")
			(net "P5VA_AGND")
			(options
				(clearance outline)
				(anchor circle)
			)
			(primitives
				(gr_poly
					(pts
						(arc
							(start -0.1778 -0.2794)
							(mid -0.249642 -0.249642)
							(end -0.2794 -0.1778)
						)
						(arc
							(start -0.2794 0.1778)
							(mid -0.249642 0.249642)
							(end -0.1778 0.2794)
						)
						(arc
							(start 0.1778 0.2794)
							(mid 0.249642 0.249642)
							(end 0.2794 0.1778)
						)
						(arc
							(start 0.2794 -0.1778)
							(mid 0.249642 -0.249642)
							(end 0.1778 -0.2794)
						)
					)
					(width 0)
					(fill yes)
				)
			)
		)
	)
	(footprint ""
		(layer "F.Cu")
		(at 232.790746 -27.9527 180)
		(property "Reference" "PR3"
			(at 0 0 180)
			(layer "F.SilkS")
			(hide yes)
			(effects
				(font
					(size 1.27 1.27)
				)
			)
		)
		(property "Value" "2K49R2F-GP"
			(at 0.064008 -3.993896 180)
			(unlocked yes)
			(layer "F.Fab")
			(hide yes)
			(effects
				(font
					(size 1.016 1.016)
					(thickness 0.1524)
				)
			)
		)
		(property "Device Type" "R402H16"
			(at 0.064008 -5.517896 180)
			(unlocked yes)
			(layer "F.Fab")
			(hide yes)
			(effects
				(font
					(size 1.016 1.016)
					(thickness 0.1524)
				)
			)
		)
		(duplicate_pad_numbers_are_jumpers no)
		(fp_line
			(start 0.508 -0.9398)
			(end -0.508 -0.9398)
			(stroke
				(width 0.1524)
				(type default)
			)
			(layer "F.SilkS")
		)
		(fp_line
			(start -0.508 -0.9398)
			(end -0.508 0.9398)
			(stroke
				(width 0.1524)
				(type default)
			)
			(layer "F.SilkS")
		)
		(fp_rect
			(start -0.508 0.9398)
			(end 0.508 -0.9398)
			(stroke
				(width 0)
				(type default)
			)
			(fill no)
			(layer "F.CrtYd")
		)
		(fp_rect
			(start -0.508 0.9398)
			(end 0.508 -0.9398)
			(stroke
				(width 0)
				(type default)
			)
			(fill no)
			(layer "F.Fab")
		)
		(pad "1" smd custom
			(at 0 -0.4445 180)
			(size 0.1397 0.1397)
			(layers "F.Cu" "F.Mask" "F.Paste")
			(net "P5VA_EN")
			(options
				(clearance outline)
				(anchor circle)
			)
			(primitives
				(gr_poly
					(pts
						(arc
							(start -0.1778 -0.2794)
							(mid -0.249642 -0.249642)
							(end -0.2794 -0.1778)
						)
						(arc
							(start -0.2794 0.1778)
							(mid -0.249642 0.249642)
							(end -0.1778 0.2794)
						)
						(arc
							(start 0.1778 0.2794)
							(mid 0.249642 0.249642)
							(end 0.2794 0.1778)
						)
						(arc
							(start 0.2794 -0.1778)
							(mid 0.249642 -0.249642)
							(end 0.1778 -0.2794)
						)
					)
					(width 0)
					(fill yes)
				)
			)
		)
		(pad "2" smd custom
			(at 0 0.4445 180)
			(size 0.1397 0.1397)
			(layers "F.Cu" "F.Mask" "F.Paste")
			(net "GND")
			(options
				(clearance outline)
				(anchor circle)
			)
			(primitives
				(gr_poly
					(pts
						(arc
							(start -0.1778 -0.2794)
							(mid -0.249642 -0.249642)
							(end -0.2794 -0.1778)
						)
						(arc
							(start -0.2794 0.1778)
							(mid -0.249642 0.249642)
							(end -0.1778 0.2794)
						)
						(arc
							(start 0.1778 0.2794)
							(mid 0.249642 0.249642)
							(end 0.2794 0.1778)
						)
						(arc
							(start 0.2794 -0.1778)
							(mid 0.249642 -0.249642)
							(end 0.1778 -0.2794)
						)
					)
					(width 0)
					(fill yes)
				)
			)
		)
	)
	(footprint ""
		(layer "F.Cu")
		(at 28.6766 -401.955 90)
		(property "Reference" "TC1"
			(at 0 0 90)
			(layer "F.SilkS")
			(hide yes)
			(effects
				(font
					(size 1.27 1.27)
				)
			)
		)
		(property "Value" "ST15U25VDM-1-GP"
			(at 0 -9.6012 90)
			(unlocked yes)
			(layer "F.Fab")
			(hide yes)
			(effects
				(font
					(size 1.016 1.016)
					(thickness 0.1524)
				)
			)
		)
		(property "Device Type" "CT7343H79"
			(at 0 -11.1252 90)
			(unlocked yes)
			(layer "F.Fab")
			(hide yes)
			(effects
				(font
					(size 1.016 1.016)
					(thickness 0.1524)
				)
			)
		)
		(duplicate_pad_numbers_are_jumpers no)
		(fp_line
			(start 2.286 -4.8768)
			(end -2.286 -4.8768)
			(stroke
				(width 0.1524)
				(type default)
			)
			(layer "F.SilkS")
		)
		(fp_line
			(start -2.286 -4.8768)
			(end -2.286 -2.032)
			(stroke
				(width 0.1524)
				(type default)
			)
			(layer "F.SilkS")
		)
		(fp_line
			(start 2.1082 -4.699)
			(end -2.1082 -4.699)
			(stroke
				(width 0.508)
				(type default)
			)
			(layer "F.SilkS")
		)
		(fp_line
			(start 2.286 -2.032)
			(end 2.286 -4.8768)
			(stroke
				(width 0.1524)
				(type default)
			)
			(layer "F.SilkS")
		)
		(fp_line
			(start 2.286 2.032)
			(end 2.286 4.8768)
			(stroke
				(width 0.1524)
				(type default)
			)
			(layer "F.SilkS")
		)
		(fp_line
			(start 2.286 4.8768)
			(end -2.286 4.8768)
			(stroke
				(width 0.1524)
				(type default)
			)
			(layer "F.SilkS")
		)
		(fp_line
			(start -2.286 4.8768)
			(end -2.286 2.032)
			(stroke
				(width 0.1524)
				(type default)
			)
			(layer "F.SilkS")
		)
		(fp_rect
			(start -2.1463 3.6449)
			(end 2.1463 -3.6449)
			(stroke
				(width 0)
				(type default)
			)
			(fill no)
			(layer "F.CrtYd")
		)
		(fp_poly
			(pts
				(xy -2.54 4.953) (xy -2.54 4.2926) (xy -3.81 4.2926) (xy -3.81 -4.2926) (xy -2.54 -4.2926) (xy -2.54 -4.953)
				(xy 2.54 -4.953) (xy 2.54 -4.2926) (xy 3.81 -4.2926) (xy 3.81 -1.6256) (xy 2.1463 -1.6256) (xy 2.1463 -3.6449)
				(xy -2.1463 -3.6449) (xy -2.1463 3.6449) (xy 2.1463 3.6449) (xy 2.1463 -1.6129) (xy 3.81 -1.6129)
				(xy 3.81 4.2926) (xy 2.54 4.2926) (xy 2.54 4.953)
			)
			(stroke
				(width 0)
				(type default)
			)
			(fill no)
			(layer "F.CrtYd")
		)
		(fp_rect
			(start 2.54 4.2926)
			(end 3.81 -4.2926)
			(stroke
				(width 0)
				(type default)
			)
			(fill no)
			(layer "F.Fab")
		)
		(fp_rect
			(start -3.81 4.2926)
			(end -2.54 -4.2926)
			(stroke
				(width 0)
				(type default)
			)
			(fill no)
			(layer "F.Fab")
		)
		(fp_rect
			(start -2.54 4.953)
			(end 2.54 -4.953)
			(stroke
				(width 0)
				(type default)
			)
			(fill no)
			(layer "F.Fab")
		)
		(pad "1" smd rect
			(at 0 -3.1496 90)
			(size 2.413 2.286)
			(layers "F.Cu" "F.Mask" "F.Paste")
			(net "P12V")
		)
		(pad "2" smd rect
			(at 0 3.1496 90)
			(size 2.413 2.286)
			(layers "F.Cu" "F.Mask" "F.Paste")
			(net "GND")
		)
		(zone
			(layer "F.Cu")
			(hatch none 0.5)
			(connect_pads
				(clearance 0)
			)
			(min_thickness 0.25)
			(keepout
				(tracks allowed)
				(vias not_allowed)
				(pads allowed)
				(copperpour not_allowed)
				(footprints allowed)
			)
			(placement
				(enabled no)
				(sheetname "")
			)
			(fill
				(thermal_gap 0.5)
				(thermal_bridge_width 0.5)
				(island_removal_mode 0)
			)
			(polygon
				(pts
					(xy 26.9875 -403.4663) (xy 24.0792 -403.4663) (xy 24.0792 -400.4437) (xy 26.9748 -400.4437) (xy 27.305 -400.4437)
					(xy 27.305 -403.4663)
				)
			)
		)
		(zone
			(layer "F.Cu")
			(hatch none 0.5)
			(connect_pads
				(clearance 0)
			)
			(min_thickness 0.25)
			(keepout
				(tracks allowed)
				(vias not_allowed)
				(pads allowed)
				(copperpour not_allowed)
				(footprints allowed)
			)
			(placement
				(enabled no)
				(sheetname "")
			)
			(fill
				(thermal_gap 0.5)
				(thermal_bridge_width 0.5)
				(island_removal_mode 0)
			)
			(polygon
				(pts
					(xy 33.274 -400.4437) (xy 33.274 -403.4663) (xy 30.3784 -403.4663) (xy 30.0482 -403.4663) (xy 30.0482 -400.4437)
					(xy 30.3784 -400.4437)
				)
			)
		)
	)
	(footprint ""
		(layer "F.Cu")
		(at 217.483182 -291.310568 180)
		(property "Reference" "C145"
			(at 0 0 180)
			(layer "F.SilkS")
			(hide yes)
			(effects
				(font
					(size 1.27 1.27)
				)
			)
		)
		(property "Value" "SC10U25V6KX-1GP"
			(at -0.0762 -5.1308 180)
			(unlocked yes)
			(layer "F.Fab")
			(hide yes)
			(effects
				(font
					(size 1.016 1.016)
					(thickness 0.1524)
				)
			)
		)
		(property "Device Type" "C1206H71"
			(at -0.127 -6.6548 180)
			(unlocked yes)
			(layer "F.Fab")
			(hide yes)
			(effects
				(font
					(size 1.016 1.016)
					(thickness 0.1524)
				)
			)
		)
		(duplicate_pad_numbers_are_jumpers no)
		(fp_line
			(start 1.016 2.2352)
			(end -1.016 2.2352)
			(stroke
				(width 0.1524)
				(type default)
			)
			(layer "F.SilkS")
		)
		(fp_line
			(start 1.016 0.8382)
			(end 1.016 2.2352)
			(stroke
				(width 0.1524)
				(type default)
			)
			(layer "F.SilkS")
		)
		(fp_line
			(start 1.016 -2.2352)
			(end 1.016 -0.8382)
			(stroke
				(width 0.1524)
				(type default)
			)
			(layer "F.SilkS")
		)
		(fp_line
			(start -1.016 2.2352)
			(end -1.016 0.8382)
			(stroke
				(width 0.1524)
				(type default)
			)
			(layer "F.SilkS")
		)
		(fp_line
			(start -1.016 -0.8382)
			(end -1.016 -2.2352)
			(stroke
				(width 0.1524)
				(type default)
			)
			(layer "F.SilkS")
		)
		(fp_line
			(start -1.016 -2.2352)
			(end 1.016 -2.2352)
			(stroke
				(width 0.1524)
				(type default)
			)
			(layer "F.SilkS")
		)
		(fp_rect
			(start -1.0922 2.3114)
			(end 1.0922 -2.3114)
			(stroke
				(width 0)
				(type default)
			)
			(fill no)
			(layer "F.CrtYd")
		)
		(fp_poly
			(pts
				(xy 1.0922 -2.3114) (xy 1.0922 2.3114) (xy -1.0922 2.3114) (xy -1.0922 -2.3114)
			)
			(stroke
				(width 0)
				(type default)
			)
			(fill no)
			(layer "F.Fab")
		)
		(pad "1" smd rect
			(at 0 -1.397 180)
			(size 1.651 1.27)
			(layers "F.Cu" "F.Mask" "F.Paste")
			(net "P12V_HDD2")
		)
		(pad "2" smd rect
			(at 0 1.397 180)
			(size 1.651 1.27)
			(layers "F.Cu" "F.Mask" "F.Paste")
			(net "GND")
		)
	)
	(footprint ""
		(layer "F.Cu")
		(at 47.116746 -211.864702 -90)
		(property "Reference" "Q26"
			(at 0 0 270)
			(layer "F.SilkS")
			(hide yes)
			(effects
				(font
					(size 1.27 1.27)
				)
			)
		)
		(property "Value" "2N7002DW-7F-GP"
			(at -2.3622 -8.2042 270)
			(unlocked yes)
			(layer "F.Fab")
			(hide yes)
			(effects
				(font
					(size 1.016 1.016)
					(thickness 0.1524)
				)
			)
		)
		(property "Device Type" "SOT-363H44"
			(at -2.3622 -10.1092 270)
			(unlocked yes)
			(layer "F.Fab")
			(hide yes)
			(effects
				(font
					(size 1.016 1.016)
					(thickness 0.1524)
				)
			)
		)
		(duplicate_pad_numbers_are_jumpers no)
		(fp_line
			(start -1.4478 1.7018)
			(end 1.4478 1.7018)
			(stroke
				(width 0.1524)
				(type default)
			)
			(layer "F.SilkS")
		)
		(fp_line
			(start 1.4478 1.7018)
			(end 1.4478 -1.7018)
			(stroke
				(width 0.1524)
				(type default)
			)
			(layer "F.SilkS")
		)
		(fp_line
			(start -1.27 1.524)
			(end -1.27 0.6604)
			(stroke
				(width 0.4826)
				(type default)
			)
			(layer "F.SilkS")
		)
		(fp_line
			(start -1.4478 -1.7018)
			(end -1.4478 1.7018)
			(stroke
				(width 0.1524)
				(type default)
			)
			(layer "F.SilkS")
		)
		(fp_line
			(start 1.4478 -1.7018)
			(end -1.4478 -1.7018)
			(stroke
				(width 0.1524)
				(type default)
			)
			(layer "F.SilkS")
		)
		(fp_poly
			(pts
				(xy -1.524 -1.778) (xy 1.524 -1.778) (xy 1.524 1.778) (xy -1.524 1.778)
			)
			(stroke
				(width 0)
				(type default)
			)
			(fill no)
			(layer "F.CrtYd")
		)
		(fp_poly
			(pts
				(xy -1.524 -1.778) (xy 1.524 -1.778) (xy 1.524 1.778) (xy -1.524 1.778)
			)
			(stroke
				(width 0)
				(type default)
			)
			(fill no)
			(layer "F.Fab")
		)
		(pad "1" smd rect
			(at -0.65024 0.9398 270)
			(size 0.4064 1.016)
			(layers "F.Cu" "F.Mask" "F.Paste")
			(net "GND")
		)
		(pad "2" smd rect
			(at 0 0.9398 270)
			(size 0.4064 1.016)
			(layers "F.Cu" "F.Mask" "F.Paste")
			(net "SW_PWR_R_HDD12")
		)
		(pad "3" smd rect
			(at 0.65024 0.9398 270)
			(size 0.4064 1.016)
			(layers "F.Cu" "F.Mask" "F.Paste")
			(net "SW_HDD12_P")
		)
		(pad "4" smd rect
			(at 0.65024 -0.9398 270)
			(size 0.4064 1.016)
			(layers "F.Cu" "F.Mask" "F.Paste")
			(net "GND")
		)
		(pad "5" smd rect
			(at 0 -0.9398 270)
			(size 0.4064 1.016)
			(layers "F.Cu" "F.Mask" "F.Paste")
			(net "SW_HDD12_G")
		)
		(pad "6" smd rect
			(at -0.65024 -0.9398 270)
			(size 0.4064 1.016)
			(layers "F.Cu" "F.Mask" "F.Paste")
			(net "SW_HDD12_R")
		)
	)
	(footprint ""
		(layer "F.Cu")
		(at 84.581746 -189.2427 -90)
		(property "Reference" "R454"
			(at 0 0 270)
			(layer "F.SilkS")
			(hide yes)
			(effects
				(font
					(size 1.27 1.27)
				)
			)
		)
		(property "Value" "4K7R2J-2-GP"
			(at 0.064008 -3.993896 270)
			(unlocked yes)
			(layer "F.Fab")
			(hide yes)
			(effects
				(font
					(size 1.016 1.016)
					(thickness 0.1524)
				)
			)
		)
		(property "Device Type" "R402H16"
			(at 0.064008 -5.517896 270)
			(unlocked yes)
			(layer "F.Fab")
			(hide yes)
			(effects
				(font
					(size 1.016 1.016)
					(thickness 0.1524)
				)
			)
		)
		(duplicate_pad_numbers_are_jumpers no)
		(fp_line
			(start -0.508 -0.9398)
			(end -0.508 0.9398)
			(stroke
				(width 0.1524)
				(type default)
			)
			(layer "F.SilkS")
		)
		(fp_line
			(start 0.508 -0.9398)
			(end -0.508 -0.9398)
			(stroke
				(width 0.1524)
				(type default)
			)
			(layer "F.SilkS")
		)
		(fp_rect
			(start -0.508 0.9398)
			(end 0.508 -0.9398)
			(stroke
				(width 0)
				(type default)
			)
			(fill no)
			(layer "F.CrtYd")
		)
		(fp_rect
			(start -0.508 0.9398)
			(end 0.508 -0.9398)
			(stroke
				(width 0)
				(type default)
			)
			(fill no)
			(layer "F.Fab")
		)
		(pad "1" smd custom
			(at 0 -0.4445 270)
			(size 0.1397 0.1397)
			(layers "F.Cu" "F.Mask" "F.Paste")
			(net "P3V3")
			(options
				(clearance outline)
				(anchor circle)
			)
			(primitives
				(gr_poly
					(pts
						(arc
							(start -0.1778 -0.2794)
							(mid -0.249642 -0.249642)
							(end -0.2794 -0.1778)
						)
						(arc
							(start -0.2794 0.1778)
							(mid -0.249642 0.249642)
							(end -0.1778 0.2794)
						)
						(arc
							(start 0.1778 0.2794)
							(mid 0.249642 0.249642)
							(end 0.2794 0.1778)
						)
						(arc
							(start 0.2794 -0.1778)
							(mid 0.249642 -0.249642)
							(end 0.1778 -0.2794)
						)
					)
					(width 0)
					(fill yes)
				)
			)
		)
		(pad "2" smd custom
			(at 0 0.4445 270)
			(size 0.1397 0.1397)
			(layers "F.Cu" "F.Mask" "F.Paste")
			(net "SAS_EXP_A_PWR8")
			(options
				(clearance outline)
				(anchor circle)
			)
			(primitives
				(gr_poly
					(pts
						(arc
							(start -0.1778 -0.2794)
							(mid -0.249642 -0.249642)
							(end -0.2794 -0.1778)
						)
						(arc
							(start -0.2794 0.1778)
							(mid -0.249642 0.249642)
							(end -0.1778 0.2794)
						)
						(arc
							(start 0.1778 0.2794)
							(mid 0.249642 0.249642)
							(end 0.2794 0.1778)
						)
						(arc
							(start 0.2794 -0.1778)
							(mid 0.249642 -0.249642)
							(end 0.1778 -0.2794)
						)
					)
					(width 0)
					(fill yes)
				)
			)
		)
	)
	(footprint ""
		(layer "F.Cu")
		(at 218.465146 -348.5388 90)
		(property "Reference" "R489"
			(at 0 0 90)
			(layer "F.SilkS")
			(hide yes)
			(effects
				(font
					(size 1.27 1.27)
				)
			)
		)
		(property "Value" "1KR2F-3-GP"
			(at 0.064008 -3.993896 90)
			(unlocked yes)
			(layer "F.Fab")
			(hide yes)
			(effects
				(font
					(size 1.016 1.016)
					(thickness 0.1524)
				)
			)
		)
		(property "Device Type" "R402H16"
			(at 0.064008 -5.517896 90)
			(unlocked yes)
			(layer "F.Fab")
			(hide yes)
			(effects
				(font
					(size 1.016 1.016)
					(thickness 0.1524)
				)
			)
		)
		(duplicate_pad_numbers_are_jumpers no)
		(fp_line
			(start 0.508 -0.9398)
			(end -0.508 -0.9398)
			(stroke
				(width 0.1524)
				(type default)
			)
			(layer "F.SilkS")
		)
		(fp_line
			(start -0.508 -0.9398)
			(end -0.508 0.9398)
			(stroke
				(width 0.1524)
				(type default)
			)
			(layer "F.SilkS")
		)
		(fp_rect
			(start -0.508 0.9398)
			(end 0.508 -0.9398)
			(stroke
				(width 0)
				(type default)
			)
			(fill no)
			(layer "F.CrtYd")
		)
		(fp_rect
			(start -0.508 0.9398)
			(end 0.508 -0.9398)
			(stroke
				(width 0)
				(type default)
			)
			(fill no)
			(layer "F.Fab")
		)
		(pad "1" smd custom
			(at 0 -0.4445 90)
			(size 0.1397 0.1397)
			(layers "F.Cu" "F.Mask" "F.Paste")
			(net "FLT_HDD1_B")
			(options
				(clearance outline)
				(anchor circle)
			)
			(primitives
				(gr_poly
					(pts
						(arc
							(start -0.1778 -0.2794)
							(mid -0.249642 -0.249642)
							(end -0.2794 -0.1778)
						)
						(arc
							(start -0.2794 0.1778)
							(mid -0.249642 0.249642)
							(end -0.1778 0.2794)
						)
						(arc
							(start 0.1778 0.2794)
							(mid 0.249642 0.249642)
							(end 0.2794 0.1778)
						)
						(arc
							(start 0.2794 -0.1778)
							(mid 0.249642 -0.249642)
							(end 0.1778 -0.2794)
						)
					)
					(width 0)
					(fill yes)
				)
			)
		)
		(pad "2" smd custom
			(at 0 0.4445 90)
			(size 0.1397 0.1397)
			(layers "F.Cu" "F.Mask" "F.Paste")
			(net "FLT_HDD1_DRIVE")
			(options
				(clearance outline)
				(anchor circle)
			)
			(primitives
				(gr_poly
					(pts
						(arc
							(start -0.1778 -0.2794)
							(mid -0.249642 -0.249642)
							(end -0.2794 -0.1778)
						)
						(arc
							(start -0.2794 0.1778)
							(mid -0.249642 0.249642)
							(end -0.1778 0.2794)
						)
						(arc
							(start 0.1778 0.2794)
							(mid 0.249642 0.249642)
							(end 0.2794 0.1778)
						)
						(arc
							(start 0.2794 -0.1778)
							(mid 0.249642 -0.249642)
							(end 0.1778 -0.2794)
						)
					)
					(width 0)
					(fill yes)
				)
			)
		)
	)
	(footprint ""
		(layer "F.Cu")
		(at 214.743284 -175.560228 -90)
		(property "Reference" "R151"
			(at 0 0 270)
			(layer "F.SilkS")
			(hide yes)
			(effects
				(font
					(size 1.27 1.27)
				)
			)
		)
		(property "Value" "2R2010J-1-GP"
			(at 0.254 -8.0772 270)
			(unlocked yes)
			(layer "F.Fab")
			(hide yes)
			(effects
				(font
					(size 1.016 1.016)
					(thickness 0.1524)
				)
			)
		)
		(property "Device Type" "R2010H28"
			(at 0.254 -9.6774 270)
			(unlocked yes)
			(layer "F.Fab")
			(hide yes)
			(effects
				(font
					(size 1.016 1.016)
					(thickness 0.1524)
				)
			)
		)
		(duplicate_pad_numbers_are_jumpers no)
		(fp_line
			(start -1.651 3.302)
			(end 1.651 3.302)
			(stroke
				(width 0.1524)
				(type default)
			)
			(layer "F.SilkS")
		)
		(fp_line
			(start 1.651 3.302)
			(end 1.651 -3.302)
			(stroke
				(width 0.1524)
				(type default)
			)
			(layer "F.SilkS")
		)
		(fp_line
			(start -1.651 -3.302)
			(end -1.651 3.302)
			(stroke
				(width 0.1524)
				(type default)
			)
			(layer "F.SilkS")
		)
		(fp_line
			(start 1.651 -3.302)
			(end -1.651 -3.302)
			(stroke
				(width 0.1524)
				(type default)
			)
			(layer "F.SilkS")
		)
		(fp_rect
			(start -1.7272 -3.3782)
			(end 1.7272 3.3782)
			(stroke
				(width 0)
				(type default)
			)
			(fill no)
			(layer "F.CrtYd")
		)
		(fp_poly
			(pts
				(xy 1.7272 3.3782) (xy 1.7272 -3.3782) (xy -1.7272 -3.3782) (xy -1.7272 3.3782)
			)
			(stroke
				(width 0)
				(type default)
			)
			(fill no)
			(layer "F.Fab")
		)
		(pad "1" smd rect
			(at 0 -2.3495 270)
			(size 2.794 1.143)
			(layers "F.Cu" "F.Mask" "F.Paste")
			(net "5V_PRE_3")
		)
		(pad "2" smd rect
			(at 0 2.3495 270)
			(size 2.794 1.143)
			(layers "F.Cu" "F.Mask" "F.Paste")
			(net "P5V_HDD3")
		)
	)
	(footprint ""
		(layer "F.Cu")
		(at 17.500092 -155.839922)
		(property "Reference" "LED14"
			(at 0 0 0)
			(layer "F.SilkS")
			(hide yes)
			(effects
				(font
					(size 1.27 1.27)
				)
			)
		)
		(property "Value" "LED-RB-4-GP"
			(at 5.88899 1.80848 0)
			(unlocked yes)
			(layer "F.Fab")
			(hide yes)
			(effects
				(font
					(size 1.016 1.016)
					(thickness 0.1524)
				)
			)
		)
		(property "Device Type" "LED1613-4PH20"
			(at 5.88899 0.28448 0)
			(unlocked yes)
			(layer "F.Fab")
			(hide yes)
			(effects
				(font
					(size 1.016 1.016)
					(thickness 0.1524)
				)
			)
		)
		(duplicate_pad_numbers_are_jumpers no)
		(fp_line
			(start -1.4478 -0.9652)
			(end 1.4478 -0.9652)
			(stroke
				(width 0.1524)
				(type default)
			)
			(layer "F.SilkS")
		)
		(fp_line
			(start -1.4478 0.9652)
			(end -1.4478 -0.9652)
			(stroke
				(width 0.1524)
				(type default)
			)
			(layer "F.SilkS")
		)
		(fp_line
			(start -1.4478 0.9652)
			(end -1.4478 -0.9652)
			(stroke
				(width 0.508)
				(type default)
			)
			(layer "F.SilkS")
		)
		(fp_line
			(start 1.4478 -0.9652)
			(end 1.4478 0.9652)
			(stroke
				(width 0.1524)
				(type default)
			)
			(layer "F.SilkS")
		)
		(fp_line
			(start 1.4478 0.9652)
			(end -1.4478 0.9652)
			(stroke
				(width 0.1524)
				(type default)
			)
			(layer "F.SilkS")
		)
		(fp_rect
			(start -0.8001 0.6477)
			(end 0.8001 -0.6477)
			(stroke
				(width 0)
				(type default)
			)
			(fill no)
			(layer "F.CrtYd")
		)
		(fp_poly
			(pts
				(xy -1.7018 1.2192) (xy -1.7018 -0.06223) (xy -0.8001 -0.06223) (xy -0.8001 0.6477) (xy 0.8001 0.6477)
				(xy 0.8001 -0.6477) (xy -0.8001 -0.6477) (xy -0.8001 -0.0635) (xy -1.7018 -0.0635) (xy -1.7018 -1.2192)
				(xy 1.7018 -1.2192) (xy 1.7018 1.2192)
			)
			(stroke
				(width 0)
				(type default)
			)
			(fill no)
			(layer "F.CrtYd")
		)
		(fp_rect
			(start -1.7018 1.2192)
			(end 1.7018 -1.2192)
			(stroke
				(width 0)
				(type default)
			)
			(fill no)
			(layer "F.Fab")
		)
		(pad "1" smd rect
			(at -0.73025 0.4064)
			(size 0.9144 0.6096)
			(layers "F.Cu" "F.Mask" "F.Paste")
			(net "DRV_ACT_NET13")
		)
		(pad "2" smd rect
			(at -0.73025 -0.4064)
			(size 0.9144 0.6096)
			(layers "F.Cu" "F.Mask" "F.Paste")
			(net "FLT_NET_HDD13")
		)
		(pad "3" smd rect
			(at 0.73025 -0.4064)
			(size 0.9144 0.6096)
			(layers "F.Cu" "F.Mask" "F.Paste")
			(net "FLT_HDD13")
		)
		(pad "4" smd rect
			(at 0.73025 0.4064)
			(size 0.9144 0.6096)
			(layers "F.Cu" "F.Mask" "F.Paste")
			(net "DRV_ACT_13")
		)
	)
	(footprint ""
		(layer "F.Cu")
		(at 80.4418 -92.7608 -90)
		(property "Reference" "R417"
			(at 0 0 270)
			(layer "F.SilkS")
			(hide yes)
			(effects
				(font
					(size 1.27 1.27)
				)
			)
		)
		(property "Value" "0R2J-2-GP"
			(at 0.064008 -3.993896 270)
			(unlocked yes)
			(layer "F.Fab")
			(hide yes)
			(effects
				(font
					(size 1.016 1.016)
					(thickness 0.1524)
				)
			)
		)
		(property "Device Type" "R402H16"
			(at 0.064008 -5.517896 270)
			(unlocked yes)
			(layer "F.Fab")
			(hide yes)
			(effects
				(font
					(size 1.016 1.016)
					(thickness 0.1524)
				)
			)
		)
		(duplicate_pad_numbers_are_jumpers no)
		(fp_line
			(start -0.508 -0.9398)
			(end -0.508 0.9398)
			(stroke
				(width 0.1524)
				(type default)
			)
			(layer "F.SilkS")
		)
		(fp_line
			(start 0.508 -0.9398)
			(end -0.508 -0.9398)
			(stroke
				(width 0.1524)
				(type default)
			)
			(layer "F.SilkS")
		)
		(fp_rect
			(start -0.508 0.9398)
			(end 0.508 -0.9398)
			(stroke
				(width 0)
				(type default)
			)
			(fill no)
			(layer "F.CrtYd")
		)
		(fp_rect
			(start -0.508 0.9398)
			(end 0.508 -0.9398)
			(stroke
				(width 0)
				(type default)
			)
			(fill no)
			(layer "F.Fab")
		)
		(pad "1" smd custom
			(at 0 -0.4445 270)
			(size 0.1397 0.1397)
			(layers "F.Cu" "F.Mask" "F.Paste")
			(net "SW_HDD9_G")
			(options
				(clearance outline)
				(anchor circle)
			)
			(primitives
				(gr_poly
					(pts
						(arc
							(start -0.1778 -0.2794)
							(mid -0.249642 -0.249642)
							(end -0.2794 -0.1778)
						)
						(arc
							(start -0.2794 0.1778)
							(mid -0.249642 0.249642)
							(end -0.1778 0.2794)
						)
						(arc
							(start 0.1778 0.2794)
							(mid 0.249642 0.249642)
							(end 0.2794 0.1778)
						)
						(arc
							(start 0.2794 -0.1778)
							(mid 0.249642 -0.249642)
							(end 0.1778 -0.2794)
						)
					)
					(width 0)
					(fill yes)
				)
			)
		)
		(pad "2" smd custom
			(at 0 0.4445 270)
			(size 0.1397 0.1397)
			(layers "F.Cu" "F.Mask" "F.Paste")
			(net "SW_HDD9_R")
			(options
				(clearance outline)
				(anchor circle)
			)
			(primitives
				(gr_poly
					(pts
						(arc
							(start -0.1778 -0.2794)
							(mid -0.249642 -0.249642)
							(end -0.2794 -0.1778)
						)
						(arc
							(start -0.2794 0.1778)
							(mid -0.249642 0.249642)
							(end -0.1778 0.2794)
						)
						(arc
							(start 0.1778 0.2794)
							(mid 0.249642 0.249642)
							(end 0.2794 0.1778)
						)
						(arc
							(start 0.2794 -0.1778)
							(mid 0.249642 -0.249642)
							(end 0.1778 -0.2794)
						)
					)
					(width 0)
					(fill yes)
				)
			)
		)
	)
	(footprint ""
		(layer "F.Cu")
		(at 51.689 -208.534 180)
		(property "Reference" "R560"
			(at 0 0 180)
			(layer "F.SilkS")
			(hide yes)
			(effects
				(font
					(size 1.27 1.27)
				)
			)
		)
		(property "Value" "200KR2F-L-GP"
			(at 0.064008 -3.993896 180)
			(unlocked yes)
			(layer "F.Fab")
			(hide yes)
			(effects
				(font
					(size 1.016 1.016)
					(thickness 0.1524)
				)
			)
		)
		(property "Device Type" "R402H16"
			(at 0.064008 -5.517896 180)
			(unlocked yes)
			(layer "F.Fab")
			(hide yes)
			(effects
				(font
					(size 1.016 1.016)
					(thickness 0.1524)
				)
			)
		)
		(duplicate_pad_numbers_are_jumpers no)
		(fp_line
			(start 0.508 -0.9398)
			(end -0.508 -0.9398)
			(stroke
				(width 0.1524)
				(type default)
			)
			(layer "F.SilkS")
		)
		(fp_line
			(start -0.508 -0.9398)
			(end -0.508 0.9398)
			(stroke
				(width 0.1524)
				(type default)
			)
			(layer "F.SilkS")
		)
		(fp_rect
			(start -0.508 0.9398)
			(end 0.508 -0.9398)
			(stroke
				(width 0)
				(type default)
			)
			(fill no)
			(layer "F.CrtYd")
		)
		(fp_rect
			(start -0.508 0.9398)
			(end 0.508 -0.9398)
			(stroke
				(width 0)
				(type default)
			)
			(fill no)
			(layer "F.Fab")
		)
		(pad "1" smd custom
			(at 0 -0.4445 180)
			(size 0.1397 0.1397)
			(layers "F.Cu" "F.Mask" "F.Paste")
			(net "SW_HDD12_R")
			(options
				(clearance outline)
				(anchor circle)
			)
			(primitives
				(gr_poly
					(pts
						(arc
							(start -0.1778 -0.2794)
							(mid -0.249642 -0.249642)
							(end -0.2794 -0.1778)
						)
						(arc
							(start -0.2794 0.1778)
							(mid -0.249642 0.249642)
							(end -0.1778 0.2794)
						)
						(arc
							(start 0.1778 0.2794)
							(mid 0.249642 0.249642)
							(end 0.2794 0.1778)
						)
						(arc
							(start 0.2794 -0.1778)
							(mid 0.249642 -0.249642)
							(end 0.1778 -0.2794)
						)
					)
					(width 0)
					(fill yes)
				)
			)
		)
		(pad "2" smd custom
			(at 0 0.4445 180)
			(size 0.1397 0.1397)
			(layers "F.Cu" "F.Mask" "F.Paste")
			(net "SW_HDD12_N")
			(options
				(clearance outline)
				(anchor circle)
			)
			(primitives
				(gr_poly
					(pts
						(arc
							(start -0.1778 -0.2794)
							(mid -0.249642 -0.249642)
							(end -0.2794 -0.1778)
						)
						(arc
							(start -0.2794 0.1778)
							(mid -0.249642 0.249642)
							(end -0.1778 0.2794)
						)
						(arc
							(start 0.1778 0.2794)
							(mid 0.249642 0.249642)
							(end 0.2794 0.1778)
						)
						(arc
							(start 0.2794 -0.1778)
							(mid 0.249642 -0.249642)
							(end 0.1778 -0.2794)
						)
					)
					(width 0)
					(fill yes)
				)
			)
		)
	)
	(footprint ""
		(layer "F.Cu")
		(at 197.103746 -183.9087 -90)
		(property "Reference" "R437"
			(at 0 0 270)
			(layer "F.SilkS")
			(hide yes)
			(effects
				(font
					(size 1.27 1.27)
				)
			)
		)
		(property "Value" "4K7R2J-2-GP"
			(at 0.064008 -3.993896 270)
			(unlocked yes)
			(layer "F.Fab")
			(hide yes)
			(effects
				(font
					(size 1.016 1.016)
					(thickness 0.1524)
				)
			)
		)
		(property "Device Type" "R402H16"
			(at 0.064008 -5.517896 270)
			(unlocked yes)
			(layer "F.Fab")
			(hide yes)
			(effects
				(font
					(size 1.016 1.016)
					(thickness 0.1524)
				)
			)
		)
		(duplicate_pad_numbers_are_jumpers no)
		(fp_line
			(start -0.508 -0.9398)
			(end -0.508 0.9398)
			(stroke
				(width 0.1524)
				(type default)
			)
			(layer "F.SilkS")
		)
		(fp_line
			(start 0.508 -0.9398)
			(end -0.508 -0.9398)
			(stroke
				(width 0.1524)
				(type default)
			)
			(layer "F.SilkS")
		)
		(fp_rect
			(start -0.508 0.9398)
			(end 0.508 -0.9398)
			(stroke
				(width 0)
				(type default)
			)
			(fill no)
			(layer "F.CrtYd")
		)
		(fp_rect
			(start -0.508 0.9398)
			(end 0.508 -0.9398)
			(stroke
				(width 0)
				(type default)
			)
			(fill no)
			(layer "F.Fab")
		)
		(pad "1" smd custom
			(at 0 -0.4445 270)
			(size 0.1397 0.1397)
			(layers "F.Cu" "F.Mask" "F.Paste")
			(net "P3V3")
			(options
				(clearance outline)
				(anchor circle)
			)
			(primitives
				(gr_poly
					(pts
						(arc
							(start -0.1778 -0.2794)
							(mid -0.249642 -0.249642)
							(end -0.2794 -0.1778)
						)
						(arc
							(start -0.2794 0.1778)
							(mid -0.249642 0.249642)
							(end -0.1778 0.2794)
						)
						(arc
							(start 0.1778 0.2794)
							(mid 0.249642 0.249642)
							(end 0.2794 0.1778)
						)
						(arc
							(start 0.2794 -0.1778)
							(mid 0.249642 -0.249642)
							(end 0.1778 -0.2794)
						)
					)
					(width 0)
					(fill yes)
				)
			)
		)
		(pad "2" smd custom
			(at 0 0.4445 270)
			(size 0.1397 0.1397)
			(layers "F.Cu" "F.Mask" "F.Paste")
			(net "SAS_EXP_B_PWR3")
			(options
				(clearance outline)
				(anchor circle)
			)
			(primitives
				(gr_poly
					(pts
						(arc
							(start -0.1778 -0.2794)
							(mid -0.249642 -0.249642)
							(end -0.2794 -0.1778)
						)
						(arc
							(start -0.2794 0.1778)
							(mid -0.249642 0.249642)
							(end -0.1778 0.2794)
						)
						(arc
							(start 0.1778 0.2794)
							(mid 0.249642 0.249642)
							(end 0.2794 0.1778)
						)
						(arc
							(start 0.2794 -0.1778)
							(mid 0.249642 -0.249642)
							(end 0.1778 -0.2794)
						)
					)
					(width 0)
					(fill yes)
				)
			)
		)
	)
	(footprint ""
		(layer "F.Cu")
		(at 217.346784 -180.183028 180)
		(property "Reference" "C154"
			(at 0 0 180)
			(layer "F.SilkS")
			(hide yes)
			(effects
				(font
					(size 1.27 1.27)
				)
			)
		)
		(property "Value" "SC1U16V3KX-5GP"
			(at 0 -2.8194 180)
			(unlocked yes)
			(layer "F.Fab")
			(hide yes)
			(effects
				(font
					(size 1.016 1.016)
					(thickness 0.1524)
				)
			)
		)
		(property "Device Type" "C603H36"
			(at 0 -4.3434 180)
			(unlocked yes)
			(layer "F.Fab")
			(hide yes)
			(effects
				(font
					(size 1.016 1.016)
					(thickness 0.1524)
				)
			)
		)
		(duplicate_pad_numbers_are_jumpers no)
		(fp_line
			(start 0.508 0)
			(end -0.508 0)
			(stroke
				(width 0.2032)
				(type default)
			)
			(layer "F.SilkS")
		)
		(fp_rect
			(start -0.5842 1.3335)
			(end 0.5842 -1.3335)
			(stroke
				(width 0)
				(type default)
			)
			(fill no)
			(layer "F.CrtYd")
		)
		(fp_rect
			(start -0.5842 1.3335)
			(end 0.5842 -1.3335)
			(stroke
				(width 0)
				(type default)
			)
			(fill no)
			(layer "F.Fab")
		)
		(pad "1" smd custom
			(at 0 -0.762 180)
			(size 0.2159 0.2159)
			(layers "F.Cu" "F.Mask" "F.Paste")
			(net "P5V_HDD3")
			(options
				(clearance outline)
				(anchor circle)
			)
			(primitives
				(gr_poly
					(pts
						(arc
							(start -0.3302 -0.4318)
							(mid -0.402042 -0.402042)
							(end -0.4318 -0.3302)
						)
						(arc
							(start -0.4318 0.3302)
							(mid -0.402042 0.402042)
							(end -0.3302 0.4318)
						)
						(arc
							(start 0.3302 0.4318)
							(mid 0.402042 0.402042)
							(end 0.4318 0.3302)
						)
						(arc
							(start 0.4318 -0.3302)
							(mid 0.402042 -0.402042)
							(end 0.3302 -0.4318)
						)
					)
					(width 0)
					(fill yes)
				)
			)
		)
		(pad "2" smd custom
			(at 0 0.762 180)
			(size 0.2159 0.2159)
			(layers "F.Cu" "F.Mask" "F.Paste")
			(net "GND")
			(options
				(clearance outline)
				(anchor circle)
			)
			(primitives
				(gr_poly
					(pts
						(arc
							(start -0.3302 -0.4318)
							(mid -0.402042 -0.402042)
							(end -0.4318 -0.3302)
						)
						(arc
							(start -0.4318 0.3302)
							(mid -0.402042 0.402042)
							(end -0.3302 0.4318)
						)
						(arc
							(start 0.3302 0.4318)
							(mid 0.402042 0.402042)
							(end 0.4318 0.3302)
						)
						(arc
							(start 0.4318 -0.3302)
							(mid 0.402042 -0.402042)
							(end 0.3302 -0.4318)
						)
					)
					(width 0)
					(fill yes)
				)
			)
		)
	)
	(footprint ""
		(layer "F.Cu")
		(at 10.8966 -153.1874 180)
		(property "Reference" "R545"
			(at 0 0 180)
			(layer "F.SilkS")
			(hide yes)
			(effects
				(font
					(size 1.27 1.27)
				)
			)
		)
		(property "Value" "0R2J-2-GP"
			(at 0.064008 -3.993896 180)
			(unlocked yes)
			(layer "F.Fab")
			(hide yes)
			(effects
				(font
					(size 1.016 1.016)
					(thickness 0.1524)
				)
			)
		)
		(property "Device Type" "R402H16"
			(at 0.064008 -5.517896 180)
			(unlocked yes)
			(layer "F.Fab")
			(hide yes)
			(effects
				(font
					(size 1.016 1.016)
					(thickness 0.1524)
				)
			)
		)
		(duplicate_pad_numbers_are_jumpers no)
		(fp_line
			(start 0.508 -0.9398)
			(end -0.508 -0.9398)
			(stroke
				(width 0.1524)
				(type default)
			)
			(layer "F.SilkS")
		)
		(fp_line
			(start -0.508 -0.9398)
			(end -0.508 0.9398)
			(stroke
				(width 0.1524)
				(type default)
			)
			(layer "F.SilkS")
		)
		(fp_rect
			(start -0.508 0.9398)
			(end 0.508 -0.9398)
			(stroke
				(width 0)
				(type default)
			)
			(fill no)
			(layer "F.CrtYd")
		)
		(fp_rect
			(start -0.508 0.9398)
			(end 0.508 -0.9398)
			(stroke
				(width 0)
				(type default)
			)
			(fill no)
			(layer "F.Fab")
		)
		(pad "1" smd custom
			(at 0 -0.4445 180)
			(size 0.1397 0.1397)
			(layers "F.Cu" "F.Mask" "F.Paste")
			(net "I2C_B_SDA_DAMP_B")
			(options
				(clearance outline)
				(anchor circle)
			)
			(primitives
				(gr_poly
					(pts
						(arc
							(start -0.1778 -0.2794)
							(mid -0.249642 -0.249642)
							(end -0.2794 -0.1778)
						)
						(arc
							(start -0.2794 0.1778)
							(mid -0.249642 0.249642)
							(end -0.1778 0.2794)
						)
						(arc
							(start 0.1778 0.2794)
							(mid 0.249642 0.249642)
							(end 0.2794 0.1778)
						)
						(arc
							(start 0.2794 -0.1778)
							(mid 0.249642 -0.249642)
							(end 0.1778 -0.2794)
						)
					)
					(width 0)
					(fill yes)
				)
			)
		)
		(pad "2" smd custom
			(at 0 0.4445 180)
			(size 0.1397 0.1397)
			(layers "F.Cu" "F.Mask" "F.Paste")
			(net "I2C_B_SDA")
			(options
				(clearance outline)
				(anchor circle)
			)
			(primitives
				(gr_poly
					(pts
						(arc
							(start -0.1778 -0.2794)
							(mid -0.249642 -0.249642)
							(end -0.2794 -0.1778)
						)
						(arc
							(start -0.2794 0.1778)
							(mid -0.249642 0.249642)
							(end -0.1778 0.2794)
						)
						(arc
							(start 0.1778 0.2794)
							(mid 0.249642 0.249642)
							(end 0.2794 0.1778)
						)
						(arc
							(start 0.2794 -0.1778)
							(mid 0.249642 -0.249642)
							(end 0.1778 -0.2794)
						)
					)
					(width 0)
					(fill yes)
				)
			)
		)
	)
	(footprint ""
		(layer "F.Cu")
		(at 42.500042 -41.159938 180)
		(property "Reference" "LED10"
			(at 0 0 180)
			(layer "F.SilkS")
			(hide yes)
			(effects
				(font
					(size 1.27 1.27)
				)
			)
		)
		(property "Value" "LED-RB-4-GP"
			(at 5.88899 1.80848 180)
			(unlocked yes)
			(layer "F.Fab")
			(hide yes)
			(effects
				(font
					(size 1.016 1.016)
					(thickness 0.1524)
				)
			)
		)
		(property "Device Type" "LED1613-4PH20"
			(at 5.88899 0.28448 180)
			(unlocked yes)
			(layer "F.Fab")
			(hide yes)
			(effects
				(font
					(size 1.016 1.016)
					(thickness 0.1524)
				)
			)
		)
		(duplicate_pad_numbers_are_jumpers no)
		(fp_line
			(start 1.4478 0.9652)
			(end -1.4478 0.9652)
			(stroke
				(width 0.1524)
				(type default)
			)
			(layer "F.SilkS")
		)
		(fp_line
			(start 1.4478 -0.9652)
			(end 1.4478 0.9652)
			(stroke
				(width 0.1524)
				(type default)
			)
			(layer "F.SilkS")
		)
		(fp_line
			(start -1.4478 0.9652)
			(end -1.4478 -0.9652)
			(stroke
				(width 0.1524)
				(type default)
			)
			(layer "F.SilkS")
		)
		(fp_line
			(start -1.4478 0.9652)
			(end -1.4478 -0.9652)
			(stroke
				(width 0.508)
				(type default)
			)
			(layer "F.SilkS")
		)
		(fp_line
			(start -1.4478 -0.9652)
			(end 1.4478 -0.9652)
			(stroke
				(width 0.1524)
				(type default)
			)
			(layer "F.SilkS")
		)
		(fp_rect
			(start -0.8001 0.6477)
			(end 0.8001 -0.6477)
			(stroke
				(width 0)
				(type default)
			)
			(fill no)
			(layer "F.CrtYd")
		)
		(fp_poly
			(pts
				(xy -1.7018 1.2192) (xy -1.7018 -0.06223) (xy -0.8001 -0.06223) (xy -0.8001 0.6477) (xy 0.8001 0.6477)
				(xy 0.8001 -0.6477) (xy -0.8001 -0.6477) (xy -0.8001 -0.0635) (xy -1.7018 -0.0635) (xy -1.7018 -1.2192)
				(xy 1.7018 -1.2192) (xy 1.7018 1.2192)
			)
			(stroke
				(width 0)
				(type default)
			)
			(fill no)
			(layer "F.CrtYd")
		)
		(fp_rect
			(start -1.7018 1.2192)
			(end 1.7018 -1.2192)
			(stroke
				(width 0)
				(type default)
			)
			(fill no)
			(layer "F.Fab")
		)
		(pad "1" smd rect
			(at -0.73025 0.4064 180)
			(size 0.9144 0.6096)
			(layers "F.Cu" "F.Mask" "F.Paste")
			(net "DRV_ACT_NET9")
		)
		(pad "2" smd rect
			(at -0.73025 -0.4064 180)
			(size 0.9144 0.6096)
			(layers "F.Cu" "F.Mask" "F.Paste")
			(net "FLT_NET_HDD9")
		)
		(pad "3" smd rect
			(at 0.73025 -0.4064 180)
			(size 0.9144 0.6096)
			(layers "F.Cu" "F.Mask" "F.Paste")
			(net "FLT_HDD9")
		)
		(pad "4" smd rect
			(at 0.73025 0.4064 180)
			(size 0.9144 0.6096)
			(layers "F.Cu" "F.Mask" "F.Paste")
			(net "DRV_ACT_9")
		)
	)
	(footprint ""
		(layer "F.Cu")
		(at 29.082746 -329.720702 -90)
		(property "Reference" "R261"
			(at 0 0 270)
			(layer "F.SilkS")
			(hide yes)
			(effects
				(font
					(size 1.27 1.27)
				)
			)
		)
		(property "Value" "4K7R2J-2-GP"
			(at 0.064008 -3.993896 270)
			(unlocked yes)
			(layer "F.Fab")
			(hide yes)
			(effects
				(font
					(size 1.016 1.016)
					(thickness 0.1524)
				)
			)
		)
		(property "Device Type" "R402H16"
			(at 0.064008 -5.517896 270)
			(unlocked yes)
			(layer "F.Fab")
			(hide yes)
			(effects
				(font
					(size 1.016 1.016)
					(thickness 0.1524)
				)
			)
		)
		(duplicate_pad_numbers_are_jumpers no)
		(fp_line
			(start -0.508 -0.9398)
			(end -0.508 0.9398)
			(stroke
				(width 0.1524)
				(type default)
			)
			(layer "F.SilkS")
		)
		(fp_line
			(start 0.508 -0.9398)
			(end -0.508 -0.9398)
			(stroke
				(width 0.1524)
				(type default)
			)
			(layer "F.SilkS")
		)
		(fp_rect
			(start -0.508 0.9398)
			(end 0.508 -0.9398)
			(stroke
				(width 0)
				(type default)
			)
			(fill no)
			(layer "F.CrtYd")
		)
		(fp_rect
			(start -0.508 0.9398)
			(end 0.508 -0.9398)
			(stroke
				(width 0)
				(type default)
			)
			(fill no)
			(layer "F.Fab")
		)
		(pad "1" smd custom
			(at 0 -0.4445 270)
			(size 0.1397 0.1397)
			(layers "F.Cu" "F.Mask" "F.Paste")
			(net "P3V3")
			(options
				(clearance outline)
				(anchor circle)
			)
			(primitives
				(gr_poly
					(pts
						(arc
							(start -0.1778 -0.2794)
							(mid -0.249642 -0.249642)
							(end -0.2794 -0.1778)
						)
						(arc
							(start -0.2794 0.1778)
							(mid -0.249642 0.249642)
							(end -0.1778 0.2794)
						)
						(arc
							(start 0.1778 0.2794)
							(mid 0.249642 0.249642)
							(end 0.2794 0.1778)
						)
						(arc
							(start 0.2794 -0.1778)
							(mid 0.249642 -0.249642)
							(end 0.1778 -0.2794)
						)
					)
					(width 0)
					(fill yes)
				)
			)
		)
		(pad "2" smd custom
			(at 0 0.4445 270)
			(size 0.1397 0.1397)
			(layers "F.Cu" "F.Mask" "F.Paste")
			(net "HDD_PRSNT_NET11")
			(options
				(clearance outline)
				(anchor circle)
			)
			(primitives
				(gr_poly
					(pts
						(arc
							(start -0.1778 -0.2794)
							(mid -0.249642 -0.249642)
							(end -0.2794 -0.1778)
						)
						(arc
							(start -0.2794 0.1778)
							(mid -0.249642 0.249642)
							(end -0.1778 0.2794)
						)
						(arc
							(start 0.1778 0.2794)
							(mid 0.249642 0.249642)
							(end 0.2794 0.1778)
						)
						(arc
							(start 0.2794 -0.1778)
							(mid 0.249642 -0.249642)
							(end 0.1778 -0.2794)
						)
					)
					(width 0)
					(fill yes)
				)
			)
		)
	)
	(footprint ""
		(layer "F.Cu")
		(at 240.2586 -377.6726 -90)
		(property "Reference" "C348"
			(at 0 0 270)
			(layer "F.SilkS")
			(hide yes)
			(effects
				(font
					(size 1.27 1.27)
				)
			)
		)
		(property "Value" "SC10U25V6KX-1GP"
			(at -0.0762 -5.1308 270)
			(unlocked yes)
			(layer "F.Fab")
			(hide yes)
			(effects
				(font
					(size 1.016 1.016)
					(thickness 0.1524)
				)
			)
		)
		(property "Device Type" "C1206H71"
			(at -0.127 -6.6548 270)
			(unlocked yes)
			(layer "F.Fab")
			(hide yes)
			(effects
				(font
					(size 1.016 1.016)
					(thickness 0.1524)
				)
			)
		)
		(duplicate_pad_numbers_are_jumpers no)
		(fp_line
			(start -1.016 2.2352)
			(end -1.016 0.8382)
			(stroke
				(width 0.1524)
				(type default)
			)
			(layer "F.SilkS")
		)
		(fp_line
			(start 1.016 2.2352)
			(end -1.016 2.2352)
			(stroke
				(width 0.1524)
				(type default)
			)
			(layer "F.SilkS")
		)
		(fp_line
			(start 1.016 0.8382)
			(end 1.016 2.2352)
			(stroke
				(width 0.1524)
				(type default)
			)
			(layer "F.SilkS")
		)
		(fp_line
			(start -1.016 -0.8382)
			(end -1.016 -2.2352)
			(stroke
				(width 0.1524)
				(type default)
			)
			(layer "F.SilkS")
		)
		(fp_line
			(start -1.016 -2.2352)
			(end 1.016 -2.2352)
			(stroke
				(width 0.1524)
				(type default)
			)
			(layer "F.SilkS")
		)
		(fp_line
			(start 1.016 -2.2352)
			(end 1.016 -0.8382)
			(stroke
				(width 0.1524)
				(type default)
			)
			(layer "F.SilkS")
		)
		(fp_rect
			(start -1.0922 2.3114)
			(end 1.0922 -2.3114)
			(stroke
				(width 0)
				(type default)
			)
			(fill no)
			(layer "F.CrtYd")
		)
		(fp_poly
			(pts
				(xy 1.0922 -2.3114) (xy 1.0922 2.3114) (xy -1.0922 2.3114) (xy -1.0922 -2.3114)
			)
			(stroke
				(width 0)
				(type default)
			)
			(fill no)
			(layer "F.Fab")
		)
		(pad "1" smd rect
			(at 0 -1.397 270)
			(size 1.651 1.27)
			(layers "F.Cu" "F.Mask" "F.Paste")
			(net "P12V")
		)
		(pad "2" smd rect
			(at 0 1.397 270)
			(size 1.651 1.27)
			(layers "F.Cu" "F.Mask" "F.Paste")
			(net "GND")
		)
	)
	(footprint ""
		(layer "F.Cu")
		(at 38.099746 -116.487702)
		(property "Reference" "C319"
			(at 0 0 0)
			(layer "F.SilkS")
			(hide yes)
			(effects
				(font
					(size 1.27 1.27)
				)
			)
		)
		(property "Value" "SC10U25V6KX-1GP"
			(at -0.0762 -5.1308 0)
			(unlocked yes)
			(layer "F.Fab")
			(hide yes)
			(effects
				(font
					(size 1.016 1.016)
					(thickness 0.1524)
				)
			)
		)
		(property "Device Type" "C1206H71"
			(at -0.127 -6.6548 0)
			(unlocked yes)
			(layer "F.Fab")
			(hide yes)
			(effects
				(font
					(size 1.016 1.016)
					(thickness 0.1524)
				)
			)
		)
		(duplicate_pad_numbers_are_jumpers no)
		(fp_line
			(start -1.016 -2.2352)
			(end 1.016 -2.2352)
			(stroke
				(width 0.1524)
				(type default)
			)
			(layer "F.SilkS")
		)
		(fp_line
			(start -1.016 -0.8382)
			(end -1.016 -2.2352)
			(stroke
				(width 0.1524)
				(type default)
			)
			(layer "F.SilkS")
		)
		(fp_line
			(start -1.016 2.2352)
			(end -1.016 0.8382)
			(stroke
				(width 0.1524)
				(type default)
			)
			(layer "F.SilkS")
		)
		(fp_line
			(start 1.016 -2.2352)
			(end 1.016 -0.8382)
			(stroke
				(width 0.1524)
				(type default)
			)
			(layer "F.SilkS")
		)
		(fp_line
			(start 1.016 0.8382)
			(end 1.016 2.2352)
			(stroke
				(width 0.1524)
				(type default)
			)
			(layer "F.SilkS")
		)
		(fp_line
			(start 1.016 2.2352)
			(end -1.016 2.2352)
			(stroke
				(width 0.1524)
				(type default)
			)
			(layer "F.SilkS")
		)
		(fp_rect
			(start -1.0922 2.3114)
			(end 1.0922 -2.3114)
			(stroke
				(width 0)
				(type default)
			)
			(fill no)
			(layer "F.CrtYd")
		)
		(fp_poly
			(pts
				(xy 1.0922 -2.3114) (xy 1.0922 2.3114) (xy -1.0922 2.3114) (xy -1.0922 -2.3114)
			)
			(stroke
				(width 0)
				(type default)
			)
			(fill no)
			(layer "F.Fab")
		)
		(pad "1" smd rect
			(at 0 -1.397)
			(size 1.651 1.27)
			(layers "F.Cu" "F.Mask" "F.Paste")
			(net "P12V_HDD13")
		)
		(pad "2" smd rect
			(at 0 1.397)
			(size 1.651 1.27)
			(layers "F.Cu" "F.Mask" "F.Paste")
			(net "GND")
		)
	)
	(footprint ""
		(layer "F.Cu")
		(at 58.419746 -191.7827 180)
		(property "Reference" "C241"
			(at 0 0 180)
			(layer "F.SilkS")
			(hide yes)
			(effects
				(font
					(size 1.27 1.27)
				)
			)
		)
		(property "Value" "SC10U25V6KX-1GP"
			(at -0.0762 -5.1308 180)
			(unlocked yes)
			(layer "F.Fab")
			(hide yes)
			(effects
				(font
					(size 1.016 1.016)
					(thickness 0.1524)
				)
			)
		)
		(property "Device Type" "C1206H71"
			(at -0.127 -6.6548 180)
			(unlocked yes)
			(layer "F.Fab")
			(hide yes)
			(effects
				(font
					(size 1.016 1.016)
					(thickness 0.1524)
				)
			)
		)
		(duplicate_pad_numbers_are_jumpers no)
		(fp_line
			(start 1.016 2.2352)
			(end -1.016 2.2352)
			(stroke
				(width 0.1524)
				(type default)
			)
			(layer "F.SilkS")
		)
		(fp_line
			(start 1.016 0.8382)
			(end 1.016 2.2352)
			(stroke
				(width 0.1524)
				(type default)
			)
			(layer "F.SilkS")
		)
		(fp_line
			(start 1.016 -2.2352)
			(end 1.016 -0.8382)
			(stroke
				(width 0.1524)
				(type default)
			)
			(layer "F.SilkS")
		)
		(fp_line
			(start -1.016 2.2352)
			(end -1.016 0.8382)
			(stroke
				(width 0.1524)
				(type default)
			)
			(layer "F.SilkS")
		)
		(fp_line
			(start -1.016 -0.8382)
			(end -1.016 -2.2352)
			(stroke
				(width 0.1524)
				(type default)
			)
			(layer "F.SilkS")
		)
		(fp_line
			(start -1.016 -2.2352)
			(end 1.016 -2.2352)
			(stroke
				(width 0.1524)
				(type default)
			)
			(layer "F.SilkS")
		)
		(fp_rect
			(start -1.0922 2.3114)
			(end 1.0922 -2.3114)
			(stroke
				(width 0)
				(type default)
			)
			(fill no)
			(layer "F.CrtYd")
		)
		(fp_poly
			(pts
				(xy 1.0922 -2.3114) (xy 1.0922 2.3114) (xy -1.0922 2.3114) (xy -1.0922 -2.3114)
			)
			(stroke
				(width 0)
				(type default)
			)
			(fill no)
			(layer "F.Fab")
		)
		(pad "1" smd rect
			(at 0 -1.397 180)
			(size 1.651 1.27)
			(layers "F.Cu" "F.Mask" "F.Paste")
			(net "P12V_HDD8")
		)
		(pad "2" smd rect
			(at 0 1.397 180)
			(size 1.651 1.27)
			(layers "F.Cu" "F.Mask" "F.Paste")
			(net "GND")
		)
	)
	(footprint ""
		(layer "F.Cu")
		(at 85.343746 -17.0307 90)
		(property "Reference" "R475"
			(at 0 0 90)
			(layer "F.SilkS")
			(hide yes)
			(effects
				(font
					(size 1.27 1.27)
				)
			)
		)
		(property "Value" "4K7R2J-2-GP"
			(at 0.064008 -3.993896 90)
			(unlocked yes)
			(layer "F.Fab")
			(hide yes)
			(effects
				(font
					(size 1.016 1.016)
					(thickness 0.1524)
				)
			)
		)
		(property "Device Type" "R402H16"
			(at 0.064008 -5.517896 90)
			(unlocked yes)
			(layer "F.Fab")
			(hide yes)
			(effects
				(font
					(size 1.016 1.016)
					(thickness 0.1524)
				)
			)
		)
		(duplicate_pad_numbers_are_jumpers no)
		(fp_line
			(start 0.508 -0.9398)
			(end -0.508 -0.9398)
			(stroke
				(width 0.1524)
				(type default)
			)
			(layer "F.SilkS")
		)
		(fp_line
			(start -0.508 -0.9398)
			(end -0.508 0.9398)
			(stroke
				(width 0.1524)
				(type default)
			)
			(layer "F.SilkS")
		)
		(fp_rect
			(start -0.508 0.9398)
			(end 0.508 -0.9398)
			(stroke
				(width 0)
				(type default)
			)
			(fill no)
			(layer "F.CrtYd")
		)
		(fp_rect
			(start -0.508 0.9398)
			(end 0.508 -0.9398)
			(stroke
				(width 0)
				(type default)
			)
			(fill no)
			(layer "F.Fab")
		)
		(pad "1" smd custom
			(at 0 -0.4445 90)
			(size 0.1397 0.1397)
			(layers "F.Cu" "F.Mask" "F.Paste")
			(net "P3V3")
			(options
				(clearance outline)
				(anchor circle)
			)
			(primitives
				(gr_poly
					(pts
						(arc
							(start -0.1778 -0.2794)
							(mid -0.249642 -0.249642)
							(end -0.2794 -0.1778)
						)
						(arc
							(start -0.2794 0.1778)
							(mid -0.249642 0.249642)
							(end -0.1778 0.2794)
						)
						(arc
							(start 0.1778 0.2794)
							(mid 0.249642 0.249642)
							(end 0.2794 0.1778)
						)
						(arc
							(start 0.2794 -0.1778)
							(mid 0.249642 -0.249642)
							(end 0.1778 -0.2794)
						)
					)
					(width 0)
					(fill yes)
				)
			)
		)
		(pad "2" smd custom
			(at 0 0.4445 90)
			(size 0.1397 0.1397)
			(layers "F.Cu" "F.Mask" "F.Paste")
			(net "SAS2X28_B_HDD14_FLT")
			(options
				(clearance outline)
				(anchor circle)
			)
			(primitives
				(gr_poly
					(pts
						(arc
							(start -0.1778 -0.2794)
							(mid -0.249642 -0.249642)
							(end -0.2794 -0.1778)
						)
						(arc
							(start -0.2794 0.1778)
							(mid -0.249642 0.249642)
							(end -0.1778 0.2794)
						)
						(arc
							(start 0.1778 0.2794)
							(mid 0.249642 0.249642)
							(end 0.2794 0.1778)
						)
						(arc
							(start 0.2794 -0.1778)
							(mid 0.249642 -0.249642)
							(end 0.1778 -0.2794)
						)
					)
					(width 0)
					(fill yes)
				)
			)
		)
	)
	(footprint ""
		(layer "F.Cu")
		(at 42.500042 -170.669966 90)
		(property "Reference" "SKT9"
			(at 0 0 90)
			(layer "F.SilkS")
			(hide yes)
			(effects
				(font
					(size 1.27 1.27)
				)
			)
		)
		(property "Value" "SKT-SATA14P-15P-12-GP"
			(at -22.6187 8.1788 90)
			(unlocked yes)
			(layer "F.Fab")
			(hide yes)
			(effects
				(font
					(size 1.016 1.016)
					(thickness 0.1524)
				)
			)
		)
		(property "Device Type" "87945-1001"
			(at -22.6187 6.6548 90)
			(unlocked yes)
			(layer "F.Fab")
			(hide yes)
			(effects
				(font
					(size 1.016 1.016)
					(thickness 0.1524)
				)
			)
		)
		(duplicate_pad_numbers_are_jumpers no)
		(fp_line
			(start -15.3924 -5.8547)
			(end -16.3576 -5.8547)
			(stroke
				(width 0.3302)
				(type default)
			)
			(layer "F.SilkS")
		)
		(fp_line
			(start 20.4724 -5.7658)
			(end 20.4724 -2.3114)
			(stroke
				(width 0.1524)
				(type default)
			)
			(layer "F.SilkS")
		)
		(fp_line
			(start -20.4724 -5.7658)
			(end 20.4724 -5.7658)
			(stroke
				(width 0.1524)
				(type default)
			)
			(layer "F.SilkS")
		)
		(fp_line
			(start 23.7617 -2.3114)
			(end 23.7617 2.3114)
			(stroke
				(width 0.1524)
				(type default)
			)
			(layer "F.SilkS")
		)
		(fp_line
			(start 20.4724 -2.3114)
			(end 23.7617 -2.3114)
			(stroke
				(width 0.1524)
				(type default)
			)
			(layer "F.SilkS")
		)
		(fp_line
			(start -20.4724 -2.3114)
			(end -20.4724 -5.7658)
			(stroke
				(width 0.1524)
				(type default)
			)
			(layer "F.SilkS")
		)
		(fp_line
			(start -23.7617 -2.3114)
			(end -20.4724 -2.3114)
			(stroke
				(width 0.1524)
				(type default)
			)
			(layer "F.SilkS")
		)
		(fp_line
			(start 23.117556 -0.5461)
			(end 23.117556 0.5461)
			(stroke
				(width 0.3048)
				(type default)
			)
			(layer "F.SilkS")
		)
		(fp_line
			(start -20.882356 -0.5461)
			(end -20.882356 0.5461)
			(stroke
				(width 0.3048)
				(type default)
			)
			(layer "F.SilkS")
		)
		(fp_line
			(start 20.882356 0.5461)
			(end 20.882356 -0.5461)
			(stroke
				(width 0.3048)
				(type default)
			)
			(layer "F.SilkS")
		)
		(fp_line
			(start -23.117556 0.5461)
			(end -23.117556 -0.5461)
			(stroke
				(width 0.3048)
				(type default)
			)
			(layer "F.SilkS")
		)
		(fp_line
			(start 23.7617 2.3114)
			(end 20.4724 2.3114)
			(stroke
				(width 0.1524)
				(type default)
			)
			(layer "F.SilkS")
		)
		(fp_line
			(start 20.4724 2.3114)
			(end 20.4724 9.652)
			(stroke
				(width 0.1524)
				(type default)
			)
			(layer "F.SilkS")
		)
		(fp_line
			(start -20.4724 2.3114)
			(end -23.7617 2.3114)
			(stroke
				(width 0.1524)
				(type default)
			)
			(layer "F.SilkS")
		)
		(fp_line
			(start -23.7617 2.3114)
			(end -23.7617 -2.3114)
			(stroke
				(width 0.1524)
				(type default)
			)
			(layer "F.SilkS")
		)
		(fp_line
			(start 17.8435 7.9502)
			(end -17.8435 7.9502)
			(stroke
				(width 0.1524)
				(type default)
			)
			(layer "F.SilkS")
		)
		(fp_line
			(start -17.8435 7.9502)
			(end -17.8435 9.652)
			(stroke
				(width 0.1524)
				(type default)
			)
			(layer "F.SilkS")
		)
		(fp_line
			(start 20.4724 9.652)
			(end 17.8435 9.652)
			(stroke
				(width 0.1524)
				(type default)
			)
			(layer "F.SilkS")
		)
		(fp_line
			(start 17.8435 9.652)
			(end 17.8435 7.9502)
			(stroke
				(width 0.1524)
				(type default)
			)
			(layer "F.SilkS")
		)
		(fp_line
			(start -17.8435 9.652)
			(end -20.4724 9.652)
			(stroke
				(width 0.1524)
				(type default)
			)
			(layer "F.SilkS")
		)
		(fp_line
			(start -20.4724 9.652)
			(end -20.4724 2.3114)
			(stroke
				(width 0.1524)
				(type default)
			)
			(layer "F.SilkS")
		)
		(fp_arc
			(start 20.882356 -0.5461)
			(mid 21.999956 -1.6637)
			(end 23.117556 -0.5461)
			(stroke
				(width 0.3048)
				(type default)
			)
			(layer "F.SilkS")
		)
		(fp_arc
			(start -23.117556 -0.5461)
			(mid -21.999956 -1.6637)
			(end -20.882356 -0.5461)
			(stroke
				(width 0.3048)
				(type default)
			)
			(layer "F.SilkS")
		)
		(fp_arc
			(start 23.117556 0.5461)
			(mid 21.999956 1.6637)
			(end 20.882356 0.5461)
			(stroke
				(width 0.3048)
				(type default)
			)
			(layer "F.SilkS")
		)
		(fp_arc
			(start -20.882356 0.5461)
			(mid -21.999956 1.6637)
			(end -23.117556 0.5461)
			(stroke
				(width 0.3048)
				(type default)
			)
			(layer "F.SilkS")
		)
		(fp_poly
			(pts
				(xy -15.87119 -5.838698) (xy -15.23619 -6.473698) (xy -16.50619 -6.473698)
			)
			(stroke
				(width 0)
				(type default)
			)
			(fill yes)
			(layer "F.SilkS")
		)
		(fp_poly
			(pts
				(xy -20.2184 -5.5118) (xy 20.2184 -5.5118) (xy 20.2184 -2.0574) (xy 23.5077 -2.0574) (xy 23.5077 2.0574)
				(xy 20.2184 2.0574) (xy 20.2184 9.398) (xy 18.0975 9.398) (xy 18.0975 7.6962) (xy -18.0975 7.6962)
				(xy -18.0975 9.398) (xy -20.2184 9.398) (xy -20.2184 2.0574) (xy -23.5077 2.0574) (xy -23.5077 -2.0574)
				(xy -20.2184 -2.0574)
			)
			(stroke
				(width 0)
				(type default)
			)
			(fill no)
			(layer "F.CrtYd")
		)
		(fp_poly
			(pts
				(xy -20.2184 -5.5118) (xy -20.2184 -6.0198) (xy -20.7264 -6.0198) (xy -20.7264 -2.5654) (xy -24.0157 -2.5654)
				(xy -24.0157 2.5654) (xy -20.7264 2.5654) (xy -20.7264 9.906) (xy -17.5895 9.906) (xy -17.5895 8.2042)
				(xy 17.5895 8.2042) (xy 17.5895 9.906) (xy 20.7264 9.906) (xy 20.7264 2.5654) (xy 24.0157 2.5654)
				(xy 24.0157 -2.5654) (xy 20.7264 -2.5654) (xy 20.7264 -6.0198) (xy -20.21586 -6.0198) (xy -20.21586 -5.5118)
				(xy 20.2184 -5.5118) (xy 20.2184 -2.0574) (xy 23.5077 -2.0574) (xy 23.5077 2.0574) (xy 20.2184 2.0574)
				(xy 20.2184 9.398) (xy 18.0975 9.398) (xy 18.0975 7.6962) (xy -18.0975 7.6962) (xy -18.0975 9.398)
				(xy -20.2184 9.398) (xy -20.2184 2.0574) (xy -23.5077 2.0574) (xy -23.5077 -2.0574) (xy -20.2184 -2.0574)
			)
			(stroke
				(width 0)
				(type default)
			)
			(fill no)
			(layer "F.CrtYd")
		)
		(fp_poly
			(pts
				(xy -20.7264 -6.0198) (xy -20.7264 -2.5654) (xy -24.0157 -2.5654) (xy -24.0157 2.5654) (xy -20.7264 2.5654)
				(xy -20.7264 9.906) (xy -17.5895 9.906) (xy -17.5895 8.2042) (xy 17.5895 8.2042) (xy 17.5895 9.906)
				(xy 20.7264 9.906) (xy 20.7264 2.5654) (xy 24.0157 2.5654) (xy 24.0157 -2.5654) (xy 20.7264 -2.5654)
				(xy 20.7264 -6.0198)
			)
			(stroke
				(width 0)
				(type default)
			)
			(fill no)
			(layer "F.Fab")
		)
		(pad "" np_thru_hole circle
			(at -18.999962 -2.350008 90)
			(size 0.254 0.254)
			(drill 1.8542)
			(layers "*.Cu" "*.Mask")
			(clearance 1.1557)
			(thermal_gap 1.1557)
		)
		(pad "" np_thru_hole circle
			(at 18.999962 -2.350008 90)
			(size 0.254 0.254)
			(drill 1.8542)
			(layers "*.Cu" "*.Mask")
			(clearance 1.1557)
			(thermal_gap 1.1557)
		)
		(pad "H1" thru_hole oval
			(at -21.999956 0 90)
			(size 1.524 2.6162)
			(drill oval 0.8128 1.905)
			(layers "*.Cu" "*.Mask")
			(remove_unused_layers no)
			(net "GND")
			(clearance 0.1524)
			(thermal_gap 0.1524)
		)
		(pad "H2" thru_hole oval
			(at 21.999956 0 90)
			(size 1.524 2.6162)
			(drill oval 0.8128 1.905)
			(layers "*.Cu" "*.Mask")
			(remove_unused_layers no)
			(net "GND")
			(clearance 0.1524)
			(thermal_gap 0.1524)
		)
		(pad "P1" smd rect
			(at -1.89992 -4.249928 90)
			(size 0.6604 2.3876)
			(layers "F.Cu" "F.Mask" "F.Paste")
			(net "Net_5")
		)
		(pad "P2" smd rect
			(at -0.62992 -4.249928 90)
			(size 0.6604 2.3876)
			(layers "F.Cu" "F.Mask" "F.Paste")
			(net "Net_4")
		)
		(pad "P3" smd rect
			(at 0.64008 -4.249928 90)
			(size 0.6604 2.3876)
			(layers "F.Cu" "F.Mask" "F.Paste")
			(net "Net_3")
		)
		(pad "P4" smd rect
			(at 1.91008 -4.249928 90)
			(size 0.6604 2.3876)
			(layers "F.Cu" "F.Mask" "F.Paste")
			(net "GND")
		)
		(pad "P5" smd rect
			(at 3.18008 -4.249928 90)
			(size 0.6604 2.3876)
			(layers "F.Cu" "F.Mask" "F.Paste")
			(net "HDD_PRSNT_NET8")
		)
		(pad "P6" smd rect
			(at 4.45008 -4.249928 90)
			(size 0.6604 2.3876)
			(layers "F.Cu" "F.Mask" "F.Paste")
			(net "GND")
		)
		(pad "P7" smd rect
			(at 5.72008 -4.249928 90)
			(size 0.6604 2.3876)
			(layers "F.Cu" "F.Mask" "F.Paste")
			(net "5V_PRE_8")
		)
		(pad "P8" smd rect
			(at 6.99008 -4.249928 90)
			(size 0.6604 2.3876)
			(layers "F.Cu" "F.Mask" "F.Paste")
			(net "P5V_HDD8")
		)
		(pad "P9" smd rect
			(at 8.26008 -4.249928 90)
			(size 0.6604 2.3876)
			(layers "F.Cu" "F.Mask" "F.Paste")
			(net "P5V_HDD8")
		)
		(pad "P10" smd rect
			(at 9.53008 -4.249928 90)
			(size 0.6604 2.3876)
			(layers "F.Cu" "F.Mask" "F.Paste")
			(net "GND")
		)
		(pad "P11" smd rect
			(at 10.80008 -4.249928 90)
			(size 0.6604 2.3876)
			(layers "F.Cu" "F.Mask" "F.Paste")
			(net "ACT_HDD8")
		)
		(pad "P12" smd rect
			(at 12.07008 -4.249928 90)
			(size 0.6604 2.3876)
			(layers "F.Cu" "F.Mask" "F.Paste")
			(net "GND")
		)
		(pad "P13" smd rect
			(at 13.34008 -4.249928 90)
			(size 0.6604 2.3876)
			(layers "F.Cu" "F.Mask" "F.Paste")
			(net "12V_PRE_8")
		)
		(pad "P14" smd rect
			(at 14.61008 -4.249928 90)
			(size 0.6604 2.3876)
			(layers "F.Cu" "F.Mask" "F.Paste")
			(net "P12V_HDD8")
		)
		(pad "P15" smd rect
			(at 15.88008 -4.249928 90)
			(size 0.6604 2.3876)
			(layers "F.Cu" "F.Mask" "F.Paste")
			(net "P12V_HDD8")
		)
		(pad "S1" smd rect
			(at -15.86992 -4.249928 90)
			(size 0.6604 2.3876)
			(layers "F.Cu" "F.Mask" "F.Paste")
			(net "GND")
		)
		(pad "S2" smd rect
			(at -14.59992 -4.249928 90)
			(size 0.6604 2.3876)
			(layers "F.Cu" "F.Mask" "F.Paste")
			(net "SAS2X28_A_HDD8_TX_+")
		)
		(pad "S3" smd rect
			(at -13.32992 -4.249928 90)
			(size 0.6604 2.3876)
			(layers "F.Cu" "F.Mask" "F.Paste")
			(net "SAS2X28_A_HDD8_TX_-")
		)
		(pad "S4" smd rect
			(at -12.05992 -4.249928 90)
			(size 0.6604 2.3876)
			(layers "F.Cu" "F.Mask" "F.Paste")
			(net "GND")
		)
		(pad "S5" smd rect
			(at -10.78992 -4.249928 90)
			(size 0.6604 2.3876)
			(layers "F.Cu" "F.Mask" "F.Paste")
			(net "SAS2X28_DRIVE_RX_N_A8")
		)
		(pad "S6" smd rect
			(at -9.51992 -4.249928 90)
			(size 0.6604 2.3876)
			(layers "F.Cu" "F.Mask" "F.Paste")
			(net "SAS2X28_DRIVE_RX_P_A8")
		)
		(pad "S7" smd rect
			(at -8.24992 -4.249928 90)
			(size 0.6604 2.3876)
			(layers "F.Cu" "F.Mask" "F.Paste")
			(net "GND")
		)
		(pad "S8" smd rect
			(at -7.480046 -2.100072 90)
			(size 0.508 1.905)
			(layers "F.Cu" "F.Mask" "F.Paste")
			(net "GND")
		)
		(pad "S9" smd rect
			(at -6.679946 -2.100072 90)
			(size 0.508 1.905)
			(layers "F.Cu" "F.Mask" "F.Paste")
			(net "SAS2X28_B_HDD8_TX_+")
		)
		(pad "S10" smd rect
			(at -5.8801 -2.100072 90)
			(size 0.508 1.905)
			(layers "F.Cu" "F.Mask" "F.Paste")
			(net "SAS2X28_B_HDD8_TX_-")
		)
		(pad "S11" smd rect
			(at -5.08 -2.100072 90)
			(size 0.508 1.905)
			(layers "F.Cu" "F.Mask" "F.Paste")
			(net "GND")
		)
		(pad "S12" smd rect
			(at -4.2799 -2.100072 90)
			(size 0.508 1.905)
			(layers "F.Cu" "F.Mask" "F.Paste")
			(net "SAS2X28_DRIVE_RX_N_B8")
		)
		(pad "S13" smd rect
			(at -3.480054 -2.100072 90)
			(size 0.508 1.905)
			(layers "F.Cu" "F.Mask" "F.Paste")
			(net "SAS2X28_DRIVE_RX_P_B8")
		)
		(pad "S14" smd rect
			(at -2.679954 -2.100072 90)
			(size 0.508 1.905)
			(layers "F.Cu" "F.Mask" "F.Paste")
			(net "GND")
		)
		(zone
			(layers "F.Cu" "B.Cu" "In1.Cu" "In2.Cu" "In3.Cu" "In4.Cu" "In5.Cu" "In6.Cu")
			(hatch none 0.5)
			(connect_pads
				(clearance 0)
			)
			(min_thickness 0.25)
			(keepout
				(tracks not_allowed)
				(vias allowed)
				(pads allowed)
				(copperpour not_allowed)
				(footprints allowed)
			)
			(placement
				(enabled no)
				(sheetname "")
			)
			(fill
				(thermal_gap 0.5)
				(thermal_bridge_width 0.5)
				(island_removal_mode 0)
			)
			(polygon
				(pts
					(arc
						(start 41.381934 -189.669928)
						(mid 38.918134 -189.669928)
						(end 41.381934 -189.669928)
					)
				)
			)
		)
		(zone
			(layers "F.Cu" "B.Cu" "In1.Cu" "In2.Cu" "In3.Cu" "In4.Cu" "In5.Cu" "In6.Cu")
			(hatch none 0.5)
			(connect_pads
				(clearance 0)
			)
			(min_thickness 0.25)
			(keepout
				(tracks not_allowed)
				(vias allowed)
				(pads allowed)
				(copperpour not_allowed)
				(footprints allowed)
			)
			(placement
				(enabled no)
				(sheetname "")
			)
			(fill
				(thermal_gap 0.5)
				(thermal_bridge_width 0.5)
				(island_removal_mode 0)
			)
			(polygon
				(pts
					(arc
						(start 41.381934 -151.670004)
						(mid 38.918134 -151.670004)
						(end 41.381934 -151.670004)
					)
				)
			)
		)
	)
	(footprint ""
		(layer "F.Cu")
		(at 53.212746 -25.2857 180)
		(property "Reference" "PR27"
			(at 0 0 180)
			(layer "F.SilkS")
			(hide yes)
			(effects
				(font
					(size 1.27 1.27)
				)
			)
		)
		(property "Value" "10KR2D-GP"
			(at 0.064008 -3.993896 180)
			(unlocked yes)
			(layer "F.Fab")
			(hide yes)
			(effects
				(font
					(size 1.016 1.016)
					(thickness 0.1524)
				)
			)
		)
		(property "Device Type" "R402H16"
			(at 0.064008 -5.517896 180)
			(unlocked yes)
			(layer "F.Fab")
			(hide yes)
			(effects
				(font
					(size 1.016 1.016)
					(thickness 0.1524)
				)
			)
		)
		(duplicate_pad_numbers_are_jumpers no)
		(fp_line
			(start 0.508 -0.9398)
			(end -0.508 -0.9398)
			(stroke
				(width 0.1524)
				(type default)
			)
			(layer "F.SilkS")
		)
		(fp_line
			(start -0.508 -0.9398)
			(end -0.508 0.9398)
			(stroke
				(width 0.1524)
				(type default)
			)
			(layer "F.SilkS")
		)
		(fp_rect
			(start -0.508 0.9398)
			(end 0.508 -0.9398)
			(stroke
				(width 0)
				(type default)
			)
			(fill no)
			(layer "F.CrtYd")
		)
		(fp_rect
			(start -0.508 0.9398)
			(end 0.508 -0.9398)
			(stroke
				(width 0)
				(type default)
			)
			(fill no)
			(layer "F.Fab")
		)
		(pad "1" smd custom
			(at 0 -0.4445 180)
			(size 0.1397 0.1397)
			(layers "F.Cu" "F.Mask" "F.Paste")
			(net "P5VB_VFB")
			(options
				(clearance outline)
				(anchor circle)
			)
			(primitives
				(gr_poly
					(pts
						(arc
							(start -0.1778 -0.2794)
							(mid -0.249642 -0.249642)
							(end -0.2794 -0.1778)
						)
						(arc
							(start -0.2794 0.1778)
							(mid -0.249642 0.249642)
							(end -0.1778 0.2794)
						)
						(arc
							(start 0.1778 0.2794)
							(mid 0.249642 0.249642)
							(end 0.2794 0.1778)
						)
						(arc
							(start 0.2794 -0.1778)
							(mid 0.249642 -0.249642)
							(end 0.1778 -0.2794)
						)
					)
					(width 0)
					(fill yes)
				)
			)
		)
		(pad "2" smd custom
			(at 0 0.4445 180)
			(size 0.1397 0.1397)
			(layers "F.Cu" "F.Mask" "F.Paste")
			(net "P5VB_AGND")
			(options
				(clearance outline)
				(anchor circle)
			)
			(primitives
				(gr_poly
					(pts
						(arc
							(start -0.1778 -0.2794)
							(mid -0.249642 -0.249642)
							(end -0.2794 -0.1778)
						)
						(arc
							(start -0.2794 0.1778)
							(mid -0.249642 0.249642)
							(end -0.1778 0.2794)
						)
						(arc
							(start 0.1778 0.2794)
							(mid 0.249642 0.249642)
							(end 0.2794 0.1778)
						)
						(arc
							(start 0.2794 -0.1778)
							(mid 0.249642 -0.249642)
							(end 0.1778 -0.2794)
						)
					)
					(width 0)
					(fill yes)
				)
			)
		)
	)
	(footprint ""
		(layer "F.Cu")
		(at 33.893252 -160.03651 -90)
		(property "Reference" "C230"
			(at 0 0 270)
			(layer "F.SilkS")
			(hide yes)
			(effects
				(font
					(size 1.27 1.27)
				)
			)
		)
		(property "Value" "SCD01U50V2KX-1GP"
			(at 1.1811 -2.7051 270)
			(unlocked yes)
			(layer "F.Fab")
			(hide yes)
			(effects
				(font
					(size 1.016 1.016)
					(thickness 0.1524)
				)
			)
		)
		(property "Device Type" "C402H22"
			(at 1.1811 -4.2291 270)
			(unlocked yes)
			(layer "F.Fab")
			(hide yes)
			(effects
				(font
					(size 1.016 1.016)
					(thickness 0.1524)
				)
			)
		)
		(duplicate_pad_numbers_are_jumpers no)
		(fp_rect
			(start -0.4318 0.9525)
			(end 0.4318 -0.9525)
			(stroke
				(width 0)
				(type default)
			)
			(fill no)
			(layer "F.CrtYd")
		)
		(fp_rect
			(start -0.4318 0.9525)
			(end 0.4318 -0.9525)
			(stroke
				(width 0)
				(type default)
			)
			(fill no)
			(layer "F.Fab")
		)
		(pad "1" smd custom
			(at 0 -0.4445 270)
			(size 0.1524 0.1524)
			(layers "F.Cu" "F.Mask" "F.Paste")
			(net "SAS2X28_DRIVE_RX_N_A8")
			(options
				(clearance outline)
				(anchor circle)
			)
			(primitives
				(gr_poly
					(pts
						(arc
							(start 0.3048 -0.2032)
							(mid 0.275042 -0.275042)
							(end 0.2032 -0.3048)
						)
						(arc
							(start -0.2032 -0.3048)
							(mid -0.275042 -0.275042)
							(end -0.3048 -0.2032)
						)
						(arc
							(start -0.3048 0.2032)
							(mid -0.275042 0.275042)
							(end -0.2032 0.3048)
						)
						(arc
							(start 0.2032 0.3048)
							(mid 0.275042 0.275042)
							(end 0.3048 0.2032)
						)
					)
					(width 0)
					(fill yes)
				)
			)
		)
		(pad "2" smd custom
			(at 0 0.4445 270)
			(size 0.1524 0.1524)
			(layers "F.Cu" "F.Mask" "F.Paste")
			(net "SAS2X28_A_HDD8_RX_-")
			(options
				(clearance outline)
				(anchor circle)
			)
			(primitives
				(gr_poly
					(pts
						(arc
							(start 0.3048 -0.2032)
							(mid 0.275042 -0.275042)
							(end 0.2032 -0.3048)
						)
						(arc
							(start -0.2032 -0.3048)
							(mid -0.275042 -0.275042)
							(end -0.3048 -0.2032)
						)
						(arc
							(start -0.3048 0.2032)
							(mid -0.275042 0.275042)
							(end -0.2032 0.3048)
						)
						(arc
							(start 0.2032 0.3048)
							(mid 0.275042 0.275042)
							(end 0.3048 0.2032)
						)
					)
					(width 0)
					(fill yes)
				)
			)
		)
	)
	(footprint ""
		(layer "F.Cu")
		(at 48.335946 -452.755 90)
		(property "Reference" "Q39"
			(at 0 0 90)
			(layer "F.SilkS")
			(hide yes)
			(effects
				(font
					(size 1.27 1.27)
				)
			)
		)
		(property "Value" "PMBS3904-1-GP"
			(at 0 -9.0932 90)
			(unlocked yes)
			(layer "F.Fab")
			(hide yes)
			(effects
				(font
					(size 1.016 1.016)
					(thickness 0.1524)
				)
			)
		)
		(property "Device Type" "SOT-23-10H44"
			(at 0 -10.6172 90)
			(unlocked yes)
			(layer "F.Fab")
			(hide yes)
			(effects
				(font
					(size 1.016 1.016)
					(thickness 0.1524)
				)
			)
		)
		(duplicate_pad_numbers_are_jumpers no)
		(fp_line
			(start 1.651 -1.778)
			(end -1.651 -1.778)
			(stroke
				(width 0.1524)
				(type default)
			)
			(layer "F.SilkS")
		)
		(fp_line
			(start -1.651 -1.778)
			(end -1.651 1.778)
			(stroke
				(width 0.1524)
				(type default)
			)
			(layer "F.SilkS")
		)
		(fp_line
			(start 1.651 1.778)
			(end 1.651 -1.778)
			(stroke
				(width 0.1524)
				(type default)
			)
			(layer "F.SilkS")
		)
		(fp_line
			(start -1.651 1.778)
			(end 1.651 1.778)
			(stroke
				(width 0.1524)
				(type default)
			)
			(layer "F.SilkS")
		)
		(fp_line
			(start -0.9906 1.86309)
			(end -0.701294 2.15265)
			(stroke
				(width 0.0127)
				(type default)
			)
			(layer "F.SilkS")
		)
		(fp_line
			(start -0.994156 1.8669)
			(end -0.987044 1.8669)
			(stroke
				(width 0.0127)
				(type default)
			)
			(layer "F.SilkS")
		)
		(fp_line
			(start -1.003808 1.876552)
			(end -0.977646 1.876552)
			(stroke
				(width 0.0127)
				(type default)
			)
			(layer "F.SilkS")
		)
		(fp_line
			(start -0.635 1.8796)
			(end -1.7526 1.8796)
			(stroke
				(width 0.3302)
				(type default)
			)
			(layer "F.SilkS")
		)
		(fp_line
			(start -1.7526 1.8796)
			(end -1.7526 0.9906)
			(stroke
				(width 0.3302)
				(type default)
			)
			(layer "F.SilkS")
		)
		(fp_line
			(start -1.013206 1.88595)
			(end -0.967994 1.88595)
			(stroke
				(width 0.0127)
				(type default)
			)
			(layer "F.SilkS")
		)
		(fp_line
			(start -1.022858 1.895602)
			(end -0.958596 1.895602)
			(stroke
				(width 0.0127)
				(type default)
			)
			(layer "F.SilkS")
		)
		(fp_line
			(start -1.032256 1.905)
			(end -0.948944 1.905)
			(stroke
				(width 0.0127)
				(type default)
			)
			(layer "F.SilkS")
		)
		(fp_line
			(start -1.041908 1.914652)
			(end -0.939546 1.914652)
			(stroke
				(width 0.0127)
				(type default)
			)
			(layer "F.SilkS")
		)
		(fp_line
			(start -1.051306 1.92405)
			(end -0.929894 1.92405)
			(stroke
				(width 0.0127)
				(type default)
			)
			(layer "F.SilkS")
		)
		(fp_line
			(start -1.060958 1.933702)
			(end -0.920496 1.933702)
			(stroke
				(width 0.0127)
				(type default)
			)
			(layer "F.SilkS")
		)
		(fp_line
			(start -1.070356 1.9431)
			(end -0.910844 1.9431)
			(stroke
				(width 0.0127)
				(type default)
			)
			(layer "F.SilkS")
		)
		(fp_line
			(start -1.080008 1.952752)
			(end -0.901446 1.952752)
			(stroke
				(width 0.0127)
				(type default)
			)
			(layer "F.SilkS")
		)
		(fp_line
			(start -1.089406 1.96215)
			(end -0.891794 1.96215)
			(stroke
				(width 0.0127)
				(type default)
			)
			(layer "F.SilkS")
		)
		(fp_line
			(start -1.099058 1.971802)
			(end -0.882396 1.971802)
			(stroke
				(width 0.0127)
				(type default)
			)
			(layer "F.SilkS")
		)
		(fp_line
			(start -1.108456 1.9812)
			(end -0.872744 1.9812)
			(stroke
				(width 0.0127)
				(type default)
			)
			(layer "F.SilkS")
		)
		(fp_line
			(start -1.118108 1.990852)
			(end -0.863346 1.990852)
			(stroke
				(width 0.0127)
				(type default)
			)
			(layer "F.SilkS")
		)
		(fp_line
			(start -1.127506 2.00025)
			(end -0.853694 2.00025)
			(stroke
				(width 0.0127)
				(type default)
			)
			(layer "F.SilkS")
		)
		(fp_line
			(start -1.137158 2.009902)
			(end -0.844296 2.009902)
			(stroke
				(width 0.0127)
				(type default)
			)
			(layer "F.SilkS")
		)
		(fp_line
			(start -1.146556 2.0193)
			(end -0.834644 2.0193)
			(stroke
				(width 0.0127)
				(type default)
			)
			(layer "F.SilkS")
		)
		(fp_line
			(start -1.156208 2.028952)
			(end -0.825246 2.028952)
			(stroke
				(width 0.0127)
				(type default)
			)
			(layer "F.SilkS")
		)
		(fp_line
			(start -1.165606 2.03835)
			(end -0.815594 2.03835)
			(stroke
				(width 0.0127)
				(type default)
			)
			(layer "F.SilkS")
		)
		(fp_line
			(start -1.175258 2.048002)
			(end -0.806196 2.048002)
			(stroke
				(width 0.0127)
				(type default)
			)
			(layer "F.SilkS")
		)
		(fp_line
			(start -1.184656 2.0574)
			(end -0.796544 2.0574)
			(stroke
				(width 0.0127)
				(type default)
			)
			(layer "F.SilkS")
		)
		(fp_line
			(start -1.194308 2.067052)
			(end -0.787146 2.067052)
			(stroke
				(width 0.0127)
				(type default)
			)
			(layer "F.SilkS")
		)
		(fp_line
			(start -1.203706 2.07645)
			(end -0.777494 2.07645)
			(stroke
				(width 0.0127)
				(type default)
			)
			(layer "F.SilkS")
		)
		(fp_line
			(start -1.213358 2.086102)
			(end -0.768096 2.086102)
			(stroke
				(width 0.0127)
				(type default)
			)
			(layer "F.SilkS")
		)
		(fp_line
			(start -1.222756 2.0955)
			(end -0.758444 2.0955)
			(stroke
				(width 0.0127)
				(type default)
			)
			(layer "F.SilkS")
		)
		(fp_line
			(start -1.232408 2.105152)
			(end -0.749046 2.105152)
			(stroke
				(width 0.0127)
				(type default)
			)
			(layer "F.SilkS")
		)
		(fp_line
			(start -1.241806 2.11455)
			(end -0.739394 2.11455)
			(stroke
				(width 0.0127)
				(type default)
			)
			(layer "F.SilkS")
		)
		(fp_line
			(start -1.251458 2.124202)
			(end -0.729996 2.124202)
			(stroke
				(width 0.0127)
				(type default)
			)
			(layer "F.SilkS")
		)
		(fp_line
			(start -1.260856 2.1336)
			(end -0.720344 2.1336)
			(stroke
				(width 0.0127)
				(type default)
			)
			(layer "F.SilkS")
		)
		(fp_line
			(start -0.719074 2.145538)
			(end -1.265936 2.14122)
			(stroke
				(width 0.0127)
				(type default)
			)
			(layer "F.SilkS")
		)
		(fp_line
			(start -1.279398 2.152142)
			(end -0.9906 1.86309)
			(stroke
				(width 0.0127)
				(type default)
			)
			(layer "F.SilkS")
		)
		(fp_line
			(start -0.71628 2.15265)
			(end -1.26492 2.15265)
			(stroke
				(width 0.0127)
				(type default)
			)
			(layer "F.SilkS")
		)
		(fp_line
			(start -1.279144 2.15265)
			(end -0.701294 2.15265)
			(stroke
				(width 0.0127)
				(type default)
			)
			(layer "F.SilkS")
		)
		(fp_poly
			(pts
				(xy -1.285748 2.159) (xy -1.285748 1.8796) (xy -1.778 1.8796) (xy -1.778 -1.8796) (xy 1.778 -1.8796)
				(xy 1.778 1.8796) (xy -0.694944 1.8796) (xy -0.694944 2.159)
			)
			(stroke
				(width 0)
				(type default)
			)
			(fill no)
			(layer "F.CrtYd")
		)
		(fp_poly
			(pts
				(xy -1.285748 2.159) (xy -1.285748 1.8796) (xy -1.778 1.8796) (xy -1.778 -1.8796) (xy 1.778 -1.8796)
				(xy 1.778 1.8796) (xy -0.694944 1.8796) (xy -0.694944 2.159)
			)
			(stroke
				(width 0)
				(type default)
			)
			(fill no)
			(layer "F.Fab")
		)
		(pad "1" smd rect
			(at -0.98425 0.9525 90)
			(size 0.762 1.143)
			(layers "F.Cu" "F.Mask" "F.Paste")
			(net "FLT_HDD5_B")
		)
		(pad "2" smd rect
			(at 0.98425 0.9525 90)
			(size 0.762 1.143)
			(layers "F.Cu" "F.Mask" "F.Paste")
			(net "GND")
		)
		(pad "3" smd rect
			(at 0 -0.9525 90)
			(size 0.762 1.143)
			(layers "F.Cu" "F.Mask" "F.Paste")
			(net "DRIVE_ACT_5")
		)
	)
	(footprint ""
		(layer "F.Cu")
		(at 218.142058 -365.962184 -90)
		(property "Reference" "C118"
			(at 0 0 270)
			(layer "F.SilkS")
			(hide yes)
			(effects
				(font
					(size 1.27 1.27)
				)
			)
		)
		(property "Value" "SCD01U50V2KX-1GP"
			(at 1.1811 -2.7051 270)
			(unlocked yes)
			(layer "F.Fab")
			(hide yes)
			(effects
				(font
					(size 1.016 1.016)
					(thickness 0.1524)
				)
			)
		)
		(property "Device Type" "C402H22"
			(at 1.1811 -4.2291 270)
			(unlocked yes)
			(layer "F.Fab")
			(hide yes)
			(effects
				(font
					(size 1.016 1.016)
					(thickness 0.1524)
				)
			)
		)
		(duplicate_pad_numbers_are_jumpers no)
		(fp_rect
			(start -0.4318 0.9525)
			(end 0.4318 -0.9525)
			(stroke
				(width 0)
				(type default)
			)
			(fill no)
			(layer "F.CrtYd")
		)
		(fp_rect
			(start -0.4318 0.9525)
			(end 0.4318 -0.9525)
			(stroke
				(width 0)
				(type default)
			)
			(fill no)
			(layer "F.Fab")
		)
		(pad "1" smd custom
			(at 0 -0.4445 270)
			(size 0.1524 0.1524)
			(layers "F.Cu" "F.Mask" "F.Paste")
			(net "SAS2X28_DRIVE_RX_N_A1")
			(options
				(clearance outline)
				(anchor circle)
			)
			(primitives
				(gr_poly
					(pts
						(arc
							(start 0.3048 -0.2032)
							(mid 0.275042 -0.275042)
							(end 0.2032 -0.3048)
						)
						(arc
							(start -0.2032 -0.3048)
							(mid -0.275042 -0.275042)
							(end -0.3048 -0.2032)
						)
						(arc
							(start -0.3048 0.2032)
							(mid -0.275042 0.275042)
							(end -0.2032 0.3048)
						)
						(arc
							(start 0.2032 0.3048)
							(mid 0.275042 0.275042)
							(end 0.3048 0.2032)
						)
					)
					(width 0)
					(fill yes)
				)
			)
		)
		(pad "2" smd custom
			(at 0 0.4445 270)
			(size 0.1524 0.1524)
			(layers "F.Cu" "F.Mask" "F.Paste")
			(net "SAS2X28_A_HDD1_RX_-")
			(options
				(clearance outline)
				(anchor circle)
			)
			(primitives
				(gr_poly
					(pts
						(arc
							(start 0.3048 -0.2032)
							(mid 0.275042 -0.275042)
							(end 0.2032 -0.3048)
						)
						(arc
							(start -0.2032 -0.3048)
							(mid -0.275042 -0.275042)
							(end -0.3048 -0.2032)
						)
						(arc
							(start -0.3048 0.2032)
							(mid -0.275042 0.275042)
							(end -0.2032 0.3048)
						)
						(arc
							(start 0.2032 0.3048)
							(mid 0.275042 0.275042)
							(end 0.3048 0.2032)
						)
					)
					(width 0)
					(fill yes)
				)
			)
		)
	)
	(footprint ""
		(layer "F.Cu")
		(at 8.127746 -501.4087)
		(property "Reference" "PR42"
			(at 0 0 0)
			(layer "F.SilkS")
			(hide yes)
			(effects
				(font
					(size 1.27 1.27)
				)
			)
		)
		(property "Value" "100KR2F-L1-GP"
			(at 0.064008 -3.993896 0)
			(unlocked yes)
			(layer "F.Fab")
			(hide yes)
			(effects
				(font
					(size 1.016 1.016)
					(thickness 0.1524)
				)
			)
		)
		(property "Device Type" "R402H16"
			(at 0.064008 -5.517896 0)
			(unlocked yes)
			(layer "F.Fab")
			(hide yes)
			(effects
				(font
					(size 1.016 1.016)
					(thickness 0.1524)
				)
			)
		)
		(duplicate_pad_numbers_are_jumpers no)
		(fp_line
			(start -0.508 -0.9398)
			(end -0.508 0.9398)
			(stroke
				(width 0.1524)
				(type default)
			)
			(layer "F.SilkS")
		)
		(fp_line
			(start 0.508 -0.9398)
			(end -0.508 -0.9398)
			(stroke
				(width 0.1524)
				(type default)
			)
			(layer "F.SilkS")
		)
		(fp_rect
			(start -0.508 0.9398)
			(end 0.508 -0.9398)
			(stroke
				(width 0)
				(type default)
			)
			(fill no)
			(layer "F.CrtYd")
		)
		(fp_rect
			(start -0.508 0.9398)
			(end 0.508 -0.9398)
			(stroke
				(width 0)
				(type default)
			)
			(fill no)
			(layer "F.Fab")
		)
		(pad "1" smd custom
			(at 0 -0.4445)
			(size 0.1397 0.1397)
			(layers "F.Cu" "F.Mask" "F.Paste")
			(net "P5VC_PGD")
			(options
				(clearance outline)
				(anchor circle)
			)
			(primitives
				(gr_poly
					(pts
						(arc
							(start -0.1778 -0.2794)
							(mid -0.249642 -0.249642)
							(end -0.2794 -0.1778)
						)
						(arc
							(start -0.2794 0.1778)
							(mid -0.249642 0.249642)
							(end -0.1778 0.2794)
						)
						(arc
							(start 0.1778 0.2794)
							(mid 0.249642 0.249642)
							(end 0.2794 0.1778)
						)
						(arc
							(start 0.2794 -0.1778)
							(mid 0.249642 -0.249642)
							(end 0.1778 -0.2794)
						)
					)
					(width 0)
					(fill yes)
				)
			)
		)
		(pad "2" smd custom
			(at 0 0.4445)
			(size 0.1397 0.1397)
			(layers "F.Cu" "F.Mask" "F.Paste")
			(net "P5VC_MODE_PG")
			(options
				(clearance outline)
				(anchor circle)
			)
			(primitives
				(gr_poly
					(pts
						(arc
							(start -0.1778 -0.2794)
							(mid -0.249642 -0.249642)
							(end -0.2794 -0.1778)
						)
						(arc
							(start -0.2794 0.1778)
							(mid -0.249642 0.249642)
							(end -0.1778 0.2794)
						)
						(arc
							(start 0.1778 0.2794)
							(mid 0.249642 0.249642)
							(end 0.2794 0.1778)
						)
						(arc
							(start 0.2794 -0.1778)
							(mid 0.249642 -0.249642)
							(end 0.1778 -0.2794)
						)
					)
					(width 0)
					(fill yes)
				)
			)
		)
	)
	(footprint ""
		(layer "F.Cu")
		(at 58.038492 -75.339956 90)
		(property "Reference" "R234"
			(at 0 0 90)
			(layer "F.SilkS")
			(hide yes)
			(effects
				(font
					(size 1.27 1.27)
				)
			)
		)
		(property "Value" "2R2010J-1-GP"
			(at 0.254 -8.0772 90)
			(unlocked yes)
			(layer "F.Fab")
			(hide yes)
			(effects
				(font
					(size 1.016 1.016)
					(thickness 0.1524)
				)
			)
		)
		(property "Device Type" "R2010H28"
			(at 0.254 -9.6774 90)
			(unlocked yes)
			(layer "F.Fab")
			(hide yes)
			(effects
				(font
					(size 1.016 1.016)
					(thickness 0.1524)
				)
			)
		)
		(duplicate_pad_numbers_are_jumpers no)
		(fp_line
			(start 1.651 -3.302)
			(end -1.651 -3.302)
			(stroke
				(width 0.1524)
				(type default)
			)
			(layer "F.SilkS")
		)
		(fp_line
			(start -1.651 -3.302)
			(end -1.651 3.302)
			(stroke
				(width 0.1524)
				(type default)
			)
			(layer "F.SilkS")
		)
		(fp_line
			(start 1.651 3.302)
			(end 1.651 -3.302)
			(stroke
				(width 0.1524)
				(type default)
			)
			(layer "F.SilkS")
		)
		(fp_line
			(start -1.651 3.302)
			(end 1.651 3.302)
			(stroke
				(width 0.1524)
				(type default)
			)
			(layer "F.SilkS")
		)
		(fp_rect
			(start -1.7272 -3.3782)
			(end 1.7272 3.3782)
			(stroke
				(width 0)
				(type default)
			)
			(fill no)
			(layer "F.CrtYd")
		)
		(fp_poly
			(pts
				(xy 1.7272 3.3782) (xy 1.7272 -3.3782) (xy -1.7272 -3.3782) (xy -1.7272 3.3782)
			)
			(stroke
				(width 0)
				(type default)
			)
			(fill no)
			(layer "F.Fab")
		)
		(pad "1" smd rect
			(at 0 -2.3495 90)
			(size 2.794 1.143)
			(layers "F.Cu" "F.Mask" "F.Paste")
			(net "5V_PRE_9")
		)
		(pad "2" smd rect
			(at 0 2.3495 90)
			(size 2.794 1.143)
			(layers "F.Cu" "F.Mask" "F.Paste")
			(net "P5V_HDD9")
		)
	)
	(footprint ""
		(layer "F.Cu")
		(at 210.609942 -459.000098 180)
		(property "Reference" "U48"
			(at 0 0 180)
			(layer "F.SilkS")
			(hide yes)
			(effects
				(font
					(size 1.27 1.27)
				)
			)
		)
		(property "Value" "TMP75AIDGKR-GP"
			(at -0.1143 -9.1948 180)
			(unlocked yes)
			(layer "F.Fab")
			(hide yes)
			(effects
				(font
					(size 1.016 1.016)
					(thickness 0.1524)
				)
			)
		)
		(property "Device Type" "MSOP8-1H44"
			(at -0.1143 -10.795 180)
			(unlocked yes)
			(layer "F.Fab")
			(hide yes)
			(effects
				(font
					(size 1.016 1.016)
					(thickness 0.1524)
				)
			)
		)
		(duplicate_pad_numbers_are_jumpers no)
		(fp_line
			(start 1.0795 1.016)
			(end 1.0795 -1.016)
			(stroke
				(width 0.1524)
				(type default)
			)
			(layer "F.SilkS")
		)
		(fp_line
			(start 1.0795 -1.016)
			(end -1.9558 -1.016)
			(stroke
				(width 0.1524)
				(type default)
			)
			(layer "F.SilkS")
		)
		(fp_line
			(start -1.4478 -0.0381)
			(end -1.9558 0.4699)
			(stroke
				(width 0.1524)
				(type default)
			)
			(layer "F.SilkS")
		)
		(fp_line
			(start -1.778 1.0922)
			(end -1.778 3.048)
			(stroke
				(width 0.508)
				(type default)
			)
			(layer "F.SilkS")
		)
		(fp_line
			(start -1.9558 1.016)
			(end 1.0795 1.016)
			(stroke
				(width 0.1524)
				(type default)
			)
			(layer "F.SilkS")
		)
		(fp_line
			(start -1.9558 -0.5461)
			(end -1.4478 -0.0381)
			(stroke
				(width 0.1524)
				(type default)
			)
			(layer "F.SilkS")
		)
		(fp_line
			(start -1.9558 -1.016)
			(end -1.9558 1.016)
			(stroke
				(width 0.1524)
				(type default)
			)
			(layer "F.SilkS")
		)
		(fp_poly
			(pts
				(xy -1.1557 -1.016) (xy -1.1557 1.016) (xy 1.1557 1.016) (xy 1.1557 -1.016)
			)
			(stroke
				(width 0)
				(type default)
			)
			(fill yes)
			(layer "F.SilkS")
		)
		(fp_rect
			(start -1.4986 2.4511)
			(end 1.4986 -2.4511)
			(stroke
				(width 0)
				(type default)
			)
			(fill no)
			(layer "F.CrtYd")
		)
		(fp_poly
			(pts
				(xy -2.032 3.302) (xy -2.032 -3.302) (xy 2.032 -3.302) (xy 2.032 -2.1209) (xy 1.4986 -2.1209) (xy 1.4986 -2.4511)
				(xy -1.4986 -2.4511) (xy -1.4986 2.4511) (xy 1.4986 2.4511) (xy 1.4986 -2.1082) (xy 2.032 -2.1082)
				(xy 2.032 3.302)
			)
			(stroke
				(width 0)
				(type default)
			)
			(fill no)
			(layer "F.CrtYd")
		)
		(fp_rect
			(start -2.032 3.302)
			(end 2.032 -3.302)
			(stroke
				(width 0)
				(type default)
			)
			(fill no)
			(layer "F.Fab")
		)
		(pad "1" smd rect
			(at -0.97536 2.05486 180)
			(size 0.3556 1.524)
			(layers "F.Cu" "F.Mask" "F.Paste")
			(net "TMP3_SDA")
		)
		(pad "2" smd rect
			(at -0.32512 2.05486 180)
			(size 0.3556 1.524)
			(layers "F.Cu" "F.Mask" "F.Paste")
			(net "TMP3_SCL")
		)
		(pad "3" smd rect
			(at 0.32512 2.05486 180)
			(size 0.3556 1.524)
			(layers "F.Cu" "F.Mask" "F.Paste")
			(net "I2C_B_TMP3_ALERT")
		)
		(pad "4" smd rect
			(at 0.97536 2.05486 180)
			(size 0.3556 1.524)
			(layers "F.Cu" "F.Mask" "F.Paste")
			(net "GND")
		)
		(pad "5" smd rect
			(at 0.97536 -2.05486 180)
			(size 0.3556 1.524)
			(layers "F.Cu" "F.Mask" "F.Paste")
			(net "I2C_B_TMP3_A2")
		)
		(pad "6" smd rect
			(at 0.32512 -2.05486 180)
			(size 0.3556 1.524)
			(layers "F.Cu" "F.Mask" "F.Paste")
			(net "I2C_B_TMP3_A1")
		)
		(pad "7" smd rect
			(at -0.32512 -2.05486 180)
			(size 0.3556 1.524)
			(layers "F.Cu" "F.Mask" "F.Paste")
			(net "I2C_B_TMP3_A0")
		)
		(pad "8" smd rect
			(at -0.97536 -2.05486 180)
			(size 0.3556 1.524)
			(layers "F.Cu" "F.Mask" "F.Paste")
			(net "P3V3")
		)
	)
	(footprint ""
		(layer "F.Cu")
		(at 221.444058 -349.452184 90)
		(property "Reference" "R117"
			(at 0 0 90)
			(layer "F.SilkS")
			(hide yes)
			(effects
				(font
					(size 1.27 1.27)
				)
			)
		)
		(property "Value" "330R2F-GP"
			(at 0.064008 -3.993896 90)
			(unlocked yes)
			(layer "F.Fab")
			(hide yes)
			(effects
				(font
					(size 1.016 1.016)
					(thickness 0.1524)
				)
			)
		)
		(property "Device Type" "R402H16"
			(at 0.064008 -5.517896 90)
			(unlocked yes)
			(layer "F.Fab")
			(hide yes)
			(effects
				(font
					(size 1.016 1.016)
					(thickness 0.1524)
				)
			)
		)
		(duplicate_pad_numbers_are_jumpers no)
		(fp_line
			(start 0.508 -0.9398)
			(end -0.508 -0.9398)
			(stroke
				(width 0.1524)
				(type default)
			)
			(layer "F.SilkS")
		)
		(fp_line
			(start -0.508 -0.9398)
			(end -0.508 0.9398)
			(stroke
				(width 0.1524)
				(type default)
			)
			(layer "F.SilkS")
		)
		(fp_rect
			(start -0.508 0.9398)
			(end 0.508 -0.9398)
			(stroke
				(width 0)
				(type default)
			)
			(fill no)
			(layer "F.CrtYd")
		)
		(fp_rect
			(start -0.508 0.9398)
			(end 0.508 -0.9398)
			(stroke
				(width 0)
				(type default)
			)
			(fill no)
			(layer "F.Fab")
		)
		(pad "1" smd custom
			(at 0 -0.4445 90)
			(size 0.1397 0.1397)
			(layers "F.Cu" "F.Mask" "F.Paste")
			(net "P3V3_HDD1_LED")
			(options
				(clearance outline)
				(anchor circle)
			)
			(primitives
				(gr_poly
					(pts
						(arc
							(start -0.1778 -0.2794)
							(mid -0.249642 -0.249642)
							(end -0.2794 -0.1778)
						)
						(arc
							(start -0.2794 0.1778)
							(mid -0.249642 0.249642)
							(end -0.1778 0.2794)
						)
						(arc
							(start 0.1778 0.2794)
							(mid 0.249642 0.249642)
							(end 0.2794 0.1778)
						)
						(arc
							(start 0.2794 -0.1778)
							(mid 0.249642 -0.249642)
							(end 0.1778 -0.2794)
						)
					)
					(width 0)
					(fill yes)
				)
			)
		)
		(pad "2" smd custom
			(at 0 0.4445 90)
			(size 0.1397 0.1397)
			(layers "F.Cu" "F.Mask" "F.Paste")
			(net "FLT_HDD1")
			(options
				(clearance outline)
				(anchor circle)
			)
			(primitives
				(gr_poly
					(pts
						(arc
							(start -0.1778 -0.2794)
							(mid -0.249642 -0.249642)
							(end -0.2794 -0.1778)
						)
						(arc
							(start -0.2794 0.1778)
							(mid -0.249642 0.249642)
							(end -0.1778 0.2794)
						)
						(arc
							(start 0.1778 0.2794)
							(mid 0.249642 0.249642)
							(end 0.2794 0.1778)
						)
						(arc
							(start 0.2794 -0.1778)
							(mid 0.249642 -0.249642)
							(end 0.1778 -0.2794)
						)
					)
					(width 0)
					(fill yes)
				)
			)
		)
	)
	(footprint ""
		(layer "F.Cu")
		(at 46.7106 -238.9632)
		(property "Reference" "Q70"
			(at 0 0 0)
			(layer "F.SilkS")
			(hide yes)
			(effects
				(font
					(size 1.27 1.27)
				)
			)
		)
		(property "Value" "2N7002DW-7F-GP"
			(at -2.3622 -8.2042 0)
			(unlocked yes)
			(layer "F.Fab")
			(hide yes)
			(effects
				(font
					(size 1.016 1.016)
					(thickness 0.1524)
				)
			)
		)
		(property "Device Type" "SOT-363H44"
			(at -2.3622 -10.1092 0)
			(unlocked yes)
			(layer "F.Fab")
			(hide yes)
			(effects
				(font
					(size 1.016 1.016)
					(thickness 0.1524)
				)
			)
		)
		(duplicate_pad_numbers_are_jumpers no)
		(fp_line
			(start -1.4478 -1.7018)
			(end -1.4478 1.7018)
			(stroke
				(width 0.1524)
				(type default)
			)
			(layer "F.SilkS")
		)
		(fp_line
			(start -1.4478 1.7018)
			(end 1.4478 1.7018)
			(stroke
				(width 0.1524)
				(type default)
			)
			(layer "F.SilkS")
		)
		(fp_line
			(start -1.27 1.524)
			(end -1.27 0.6604)
			(stroke
				(width 0.4826)
				(type default)
			)
			(layer "F.SilkS")
		)
		(fp_line
			(start 1.4478 -1.7018)
			(end -1.4478 -1.7018)
			(stroke
				(width 0.1524)
				(type default)
			)
			(layer "F.SilkS")
		)
		(fp_line
			(start 1.4478 1.7018)
			(end 1.4478 -1.7018)
			(stroke
				(width 0.1524)
				(type default)
			)
			(layer "F.SilkS")
		)
		(fp_poly
			(pts
				(xy -1.524 -1.778) (xy 1.524 -1.778) (xy 1.524 1.778) (xy -1.524 1.778)
			)
			(stroke
				(width 0)
				(type default)
			)
			(fill no)
			(layer "F.CrtYd")
		)
		(fp_poly
			(pts
				(xy -1.524 -1.778) (xy 1.524 -1.778) (xy 1.524 1.778) (xy -1.524 1.778)
			)
			(stroke
				(width 0)
				(type default)
			)
			(fill no)
			(layer "F.Fab")
		)
		(pad "1" smd rect
			(at -0.65024 0.9398)
			(size 0.4064 1.016)
			(layers "F.Cu" "F.Mask" "F.Paste")
			(net "P3V3_HDD12_LED")
		)
		(pad "2" smd rect
			(at 0 0.9398)
			(size 0.4064 1.016)
			(layers "F.Cu" "F.Mask" "F.Paste")
			(net "HDD12_LED_G")
		)
		(pad "3" smd rect
			(at 0.65024 0.9398)
			(size 0.4064 1.016)
			(layers "F.Cu" "F.Mask" "F.Paste")
			(net "P5VC")
		)
		(pad "4" smd rect
			(at 0.65024 -0.9398)
			(size 0.4064 1.016)
			(layers "F.Cu" "F.Mask" "F.Paste")
			(net "P5VC_HDD12_LED")
		)
		(pad "5" smd rect
			(at 0 -0.9398)
			(size 0.4064 1.016)
			(layers "F.Cu" "F.Mask" "F.Paste")
			(net "HDD12_LED_G")
		)
		(pad "6" smd rect
			(at -0.65024 -0.9398)
			(size 0.4064 1.016)
			(layers "F.Cu" "F.Mask" "F.Paste")
			(net "P3V3")
		)
	)
	(footprint ""
		(layer "F.Cu")
		(at 28.600146 -384.0099)
		(property "Reference" "R318"
			(at 0 0 0)
			(layer "F.SilkS")
			(hide yes)
			(effects
				(font
					(size 1.27 1.27)
				)
			)
		)
		(property "Value" "0R2J-2-GP"
			(at 0.064008 -3.993896 0)
			(unlocked yes)
			(layer "F.Fab")
			(hide yes)
			(effects
				(font
					(size 1.016 1.016)
					(thickness 0.1524)
				)
			)
		)
		(property "Device Type" "R402H16"
			(at 0.064008 -5.517896 0)
			(unlocked yes)
			(layer "F.Fab")
			(hide yes)
			(effects
				(font
					(size 1.016 1.016)
					(thickness 0.1524)
				)
			)
		)
		(duplicate_pad_numbers_are_jumpers no)
		(fp_line
			(start -0.508 -0.9398)
			(end -0.508 0.9398)
			(stroke
				(width 0.1524)
				(type default)
			)
			(layer "F.SilkS")
		)
		(fp_line
			(start 0.508 -0.9398)
			(end -0.508 -0.9398)
			(stroke
				(width 0.1524)
				(type default)
			)
			(layer "F.SilkS")
		)
		(fp_rect
			(start -0.508 0.9398)
			(end 0.508 -0.9398)
			(stroke
				(width 0)
				(type default)
			)
			(fill no)
			(layer "F.CrtYd")
		)
		(fp_rect
			(start -0.508 0.9398)
			(end 0.508 -0.9398)
			(stroke
				(width 0)
				(type default)
			)
			(fill no)
			(layer "F.Fab")
		)
		(pad "1" smd custom
			(at 0 -0.4445)
			(size 0.1397 0.1397)
			(layers "F.Cu" "F.Mask" "F.Paste")
			(net "I2C_B_SCL")
			(options
				(clearance outline)
				(anchor circle)
			)
			(primitives
				(gr_poly
					(pts
						(arc
							(start -0.1778 -0.2794)
							(mid -0.249642 -0.249642)
							(end -0.2794 -0.1778)
						)
						(arc
							(start -0.2794 0.1778)
							(mid -0.249642 0.249642)
							(end -0.1778 0.2794)
						)
						(arc
							(start 0.1778 0.2794)
							(mid 0.249642 0.249642)
							(end 0.2794 0.1778)
						)
						(arc
							(start 0.2794 -0.1778)
							(mid 0.249642 -0.249642)
							(end 0.1778 -0.2794)
						)
					)
					(width 0)
					(fill yes)
				)
			)
		)
		(pad "2" smd custom
			(at 0 0.4445)
			(size 0.1397 0.1397)
			(layers "F.Cu" "F.Mask" "F.Paste")
			(net "TMP1_SCL")
			(options
				(clearance outline)
				(anchor circle)
			)
			(primitives
				(gr_poly
					(pts
						(arc
							(start -0.1778 -0.2794)
							(mid -0.249642 -0.249642)
							(end -0.2794 -0.1778)
						)
						(arc
							(start -0.2794 0.1778)
							(mid -0.249642 0.249642)
							(end -0.1778 0.2794)
						)
						(arc
							(start 0.1778 0.2794)
							(mid 0.249642 0.249642)
							(end 0.2794 0.1778)
						)
						(arc
							(start 0.2794 -0.1778)
							(mid 0.249642 -0.249642)
							(end 0.1778 -0.2794)
						)
					)
					(width 0)
					(fill yes)
				)
			)
		)
	)
	(footprint ""
		(layer "F.Cu")
		(at 9.651746 -501.0277 180)
		(property "Reference" "PC36"
			(at 0 0 180)
			(layer "F.SilkS")
			(hide yes)
			(effects
				(font
					(size 1.27 1.27)
				)
			)
		)
		(property "Value" "SC4D7U25V5KX-GP"
			(at -0.0762 -6.1214 180)
			(unlocked yes)
			(layer "F.Fab")
			(hide yes)
			(effects
				(font
					(size 1.016 1.016)
					(thickness 0.1524)
				)
			)
		)
		(property "Device Type" "C805H54"
			(at -0.0762 -8.1534 180)
			(unlocked yes)
			(layer "F.Fab")
			(hide yes)
			(effects
				(font
					(size 1.016 1.016)
					(thickness 0.1524)
				)
			)
		)
		(duplicate_pad_numbers_are_jumpers no)
		(fp_line
			(start 0.635 0)
			(end -0.635 0)
			(stroke
				(width 0.508)
				(type default)
			)
			(layer "F.SilkS")
		)
		(fp_rect
			(start -0.9652 1.778)
			(end 0.9652 -1.778)
			(stroke
				(width 0)
				(type default)
			)
			(fill no)
			(layer "F.CrtYd")
		)
		(fp_poly
			(pts
				(xy -0.9652 -1.778) (xy 0.9652 -1.778) (xy 0.9652 1.778) (xy -0.9652 1.778)
			)
			(stroke
				(width 0)
				(type default)
			)
			(fill no)
			(layer "F.Fab")
		)
		(pad "1" smd rect
			(at 0 -0.9652 180)
			(size 1.397 1.143)
			(layers "F.Cu" "F.Mask" "F.Paste")
			(net "P5VC_VDD")
		)
		(pad "2" smd rect
			(at 0 0.9652 180)
			(size 1.397 1.143)
			(layers "F.Cu" "F.Mask" "F.Paste")
			(net "GND")
		)
	)
	(footprint ""
		(layer "F.Cu")
		(at 221.360746 -345.3257 -90)
		(property "Reference" "R114"
			(at 0 0 270)
			(layer "F.SilkS")
			(hide yes)
			(effects
				(font
					(size 1.27 1.27)
				)
			)
		)
		(property "Value" "10KR2F-2-GP"
			(at 0.064008 -3.993896 270)
			(unlocked yes)
			(layer "F.Fab")
			(hide yes)
			(effects
				(font
					(size 1.016 1.016)
					(thickness 0.1524)
				)
			)
		)
		(property "Device Type" "R402H16"
			(at 0.064008 -5.517896 270)
			(unlocked yes)
			(layer "F.Fab")
			(hide yes)
			(effects
				(font
					(size 1.016 1.016)
					(thickness 0.1524)
				)
			)
		)
		(duplicate_pad_numbers_are_jumpers no)
		(fp_line
			(start -0.508 -0.9398)
			(end -0.508 0.9398)
			(stroke
				(width 0.1524)
				(type default)
			)
			(layer "F.SilkS")
		)
		(fp_line
			(start 0.508 -0.9398)
			(end -0.508 -0.9398)
			(stroke
				(width 0.1524)
				(type default)
			)
			(layer "F.SilkS")
		)
		(fp_rect
			(start -0.508 0.9398)
			(end 0.508 -0.9398)
			(stroke
				(width 0)
				(type default)
			)
			(fill no)
			(layer "F.CrtYd")
		)
		(fp_rect
			(start -0.508 0.9398)
			(end 0.508 -0.9398)
			(stroke
				(width 0)
				(type default)
			)
			(fill no)
			(layer "F.Fab")
		)
		(pad "1" smd custom
			(at 0 -0.4445 270)
			(size 0.1397 0.1397)
			(layers "F.Cu" "F.Mask" "F.Paste")
			(net "P5VA")
			(options
				(clearance outline)
				(anchor circle)
			)
			(primitives
				(gr_poly
					(pts
						(arc
							(start -0.1778 -0.2794)
							(mid -0.249642 -0.249642)
							(end -0.2794 -0.1778)
						)
						(arc
							(start -0.2794 0.1778)
							(mid -0.249642 0.249642)
							(end -0.1778 0.2794)
						)
						(arc
							(start 0.1778 0.2794)
							(mid 0.249642 0.249642)
							(end 0.2794 0.1778)
						)
						(arc
							(start 0.2794 -0.1778)
							(mid 0.249642 -0.249642)
							(end 0.1778 -0.2794)
						)
					)
					(width 0)
					(fill yes)
				)
			)
		)
		(pad "2" smd custom
			(at 0 0.4445 270)
			(size 0.1397 0.1397)
			(layers "F.Cu" "F.Mask" "F.Paste")
			(net "DRIVE_ACT_1")
			(options
				(clearance outline)
				(anchor circle)
			)
			(primitives
				(gr_poly
					(pts
						(arc
							(start -0.1778 -0.2794)
							(mid -0.249642 -0.249642)
							(end -0.2794 -0.1778)
						)
						(arc
							(start -0.2794 0.1778)
							(mid -0.249642 0.249642)
							(end -0.1778 0.2794)
						)
						(arc
							(start 0.1778 0.2794)
							(mid 0.249642 0.249642)
							(end 0.2794 0.1778)
						)
						(arc
							(start 0.2794 -0.1778)
							(mid 0.249642 -0.249642)
							(end 0.1778 -0.2794)
						)
					)
					(width 0)
					(fill yes)
				)
			)
		)
	)
	(footprint ""
		(layer "F.Cu")
		(at 72.516746 -190.5127)
		(property "Reference" "R453"
			(at 0 0 0)
			(layer "F.SilkS")
			(hide yes)
			(effects
				(font
					(size 1.27 1.27)
				)
			)
		)
		(property "Value" "4K7R2J-2-GP"
			(at 0.064008 -3.993896 0)
			(unlocked yes)
			(layer "F.Fab")
			(hide yes)
			(effects
				(font
					(size 1.016 1.016)
					(thickness 0.1524)
				)
			)
		)
		(property "Device Type" "R402H16"
			(at 0.064008 -5.517896 0)
			(unlocked yes)
			(layer "F.Fab")
			(hide yes)
			(effects
				(font
					(size 1.016 1.016)
					(thickness 0.1524)
				)
			)
		)
		(duplicate_pad_numbers_are_jumpers no)
		(fp_line
			(start -0.508 -0.9398)
			(end -0.508 0.9398)
			(stroke
				(width 0.1524)
				(type default)
			)
			(layer "F.SilkS")
		)
		(fp_line
			(start 0.508 -0.9398)
			(end -0.508 -0.9398)
			(stroke
				(width 0.1524)
				(type default)
			)
			(layer "F.SilkS")
		)
		(fp_rect
			(start -0.508 0.9398)
			(end 0.508 -0.9398)
			(stroke
				(width 0)
				(type default)
			)
			(fill no)
			(layer "F.CrtYd")
		)
		(fp_rect
			(start -0.508 0.9398)
			(end 0.508 -0.9398)
			(stroke
				(width 0)
				(type default)
			)
			(fill no)
			(layer "F.Fab")
		)
		(pad "1" smd custom
			(at 0 -0.4445)
			(size 0.1397 0.1397)
			(layers "F.Cu" "F.Mask" "F.Paste")
			(net "P3V3")
			(options
				(clearance outline)
				(anchor circle)
			)
			(primitives
				(gr_poly
					(pts
						(arc
							(start -0.1778 -0.2794)
							(mid -0.249642 -0.249642)
							(end -0.2794 -0.1778)
						)
						(arc
							(start -0.2794 0.1778)
							(mid -0.249642 0.249642)
							(end -0.1778 0.2794)
						)
						(arc
							(start 0.1778 0.2794)
							(mid 0.249642 0.249642)
							(end 0.2794 0.1778)
						)
						(arc
							(start 0.2794 -0.1778)
							(mid 0.249642 -0.249642)
							(end 0.1778 -0.2794)
						)
					)
					(width 0)
					(fill yes)
				)
			)
		)
		(pad "2" smd custom
			(at 0 0.4445)
			(size 0.1397 0.1397)
			(layers "F.Cu" "F.Mask" "F.Paste")
			(net "SAS2X28_B_HDD8_FLT")
			(options
				(clearance outline)
				(anchor circle)
			)
			(primitives
				(gr_poly
					(pts
						(arc
							(start -0.1778 -0.2794)
							(mid -0.249642 -0.249642)
							(end -0.2794 -0.1778)
						)
						(arc
							(start -0.2794 0.1778)
							(mid -0.249642 0.249642)
							(end -0.1778 0.2794)
						)
						(arc
							(start 0.1778 0.2794)
							(mid 0.249642 0.249642)
							(end 0.2794 0.1778)
						)
						(arc
							(start 0.2794 -0.1778)
							(mid 0.249642 -0.249642)
							(end 0.1778 -0.2794)
						)
					)
					(width 0)
					(fill yes)
				)
			)
		)
	)
	(footprint ""
		(layer "F.Cu")
		(at 52.196746 -25.2857)
		(property "Reference" "PR25"
			(at 0 0 0)
			(layer "F.SilkS")
			(hide yes)
			(effects
				(font
					(size 1.27 1.27)
				)
			)
		)
		(property "Value" "10KR2F-2-GP"
			(at 0.064008 -3.993896 0)
			(unlocked yes)
			(layer "F.Fab")
			(hide yes)
			(effects
				(font
					(size 1.016 1.016)
					(thickness 0.1524)
				)
			)
		)
		(property "Device Type" "R402H16"
			(at 0.064008 -5.517896 0)
			(unlocked yes)
			(layer "F.Fab")
			(hide yes)
			(effects
				(font
					(size 1.016 1.016)
					(thickness 0.1524)
				)
			)
		)
		(duplicate_pad_numbers_are_jumpers no)
		(fp_line
			(start -0.508 -0.9398)
			(end -0.508 0.9398)
			(stroke
				(width 0.1524)
				(type default)
			)
			(layer "F.SilkS")
		)
		(fp_line
			(start 0.508 -0.9398)
			(end -0.508 -0.9398)
			(stroke
				(width 0.1524)
				(type default)
			)
			(layer "F.SilkS")
		)
		(fp_rect
			(start -0.508 0.9398)
			(end 0.508 -0.9398)
			(stroke
				(width 0)
				(type default)
			)
			(fill no)
			(layer "F.CrtYd")
		)
		(fp_rect
			(start -0.508 0.9398)
			(end 0.508 -0.9398)
			(stroke
				(width 0)
				(type default)
			)
			(fill no)
			(layer "F.Fab")
		)
		(pad "1" smd custom
			(at 0 -0.4445)
			(size 0.1397 0.1397)
			(layers "F.Cu" "F.Mask" "F.Paste")
			(net "P5VB_12VIN")
			(options
				(clearance outline)
				(anchor circle)
			)
			(primitives
				(gr_poly
					(pts
						(arc
							(start -0.1778 -0.2794)
							(mid -0.249642 -0.249642)
							(end -0.2794 -0.1778)
						)
						(arc
							(start -0.2794 0.1778)
							(mid -0.249642 0.249642)
							(end -0.1778 0.2794)
						)
						(arc
							(start 0.1778 0.2794)
							(mid 0.249642 0.249642)
							(end 0.2794 0.1778)
						)
						(arc
							(start 0.2794 -0.1778)
							(mid 0.249642 -0.249642)
							(end 0.1778 -0.2794)
						)
					)
					(width 0)
					(fill yes)
				)
			)
		)
		(pad "2" smd custom
			(at 0 0.4445)
			(size 0.1397 0.1397)
			(layers "F.Cu" "F.Mask" "F.Paste")
			(net "P5VB_EN")
			(options
				(clearance outline)
				(anchor circle)
			)
			(primitives
				(gr_poly
					(pts
						(arc
							(start -0.1778 -0.2794)
							(mid -0.249642 -0.249642)
							(end -0.2794 -0.1778)
						)
						(arc
							(start -0.2794 0.1778)
							(mid -0.249642 0.249642)
							(end -0.1778 0.2794)
						)
						(arc
							(start 0.1778 0.2794)
							(mid 0.249642 0.249642)
							(end 0.2794 0.1778)
						)
						(arc
							(start 0.2794 -0.1778)
							(mid 0.249642 -0.249642)
							(end 0.1778 -0.2794)
						)
					)
					(width 0)
					(fill yes)
				)
			)
		)
	)
	(footprint ""
		(layer "F.Cu")
		(at 215.518746 -184.0357 -90)
		(property "Reference" "R154"
			(at 0 0 270)
			(layer "F.SilkS")
			(hide yes)
			(effects
				(font
					(size 1.27 1.27)
				)
			)
		)
		(property "Value" "2R2010J-1-GP"
			(at 0.254 -8.0772 270)
			(unlocked yes)
			(layer "F.Fab")
			(hide yes)
			(effects
				(font
					(size 1.016 1.016)
					(thickness 0.1524)
				)
			)
		)
		(property "Device Type" "R2010H28"
			(at 0.254 -9.6774 270)
			(unlocked yes)
			(layer "F.Fab")
			(hide yes)
			(effects
				(font
					(size 1.016 1.016)
					(thickness 0.1524)
				)
			)
		)
		(duplicate_pad_numbers_are_jumpers no)
		(fp_line
			(start -1.651 3.302)
			(end 1.651 3.302)
			(stroke
				(width 0.1524)
				(type default)
			)
			(layer "F.SilkS")
		)
		(fp_line
			(start 1.651 3.302)
			(end 1.651 -3.302)
			(stroke
				(width 0.1524)
				(type default)
			)
			(layer "F.SilkS")
		)
		(fp_line
			(start -1.651 -3.302)
			(end -1.651 3.302)
			(stroke
				(width 0.1524)
				(type default)
			)
			(layer "F.SilkS")
		)
		(fp_line
			(start 1.651 -3.302)
			(end -1.651 -3.302)
			(stroke
				(width 0.1524)
				(type default)
			)
			(layer "F.SilkS")
		)
		(fp_rect
			(start -1.7272 -3.3782)
			(end 1.7272 3.3782)
			(stroke
				(width 0)
				(type default)
			)
			(fill no)
			(layer "F.CrtYd")
		)
		(fp_poly
			(pts
				(xy 1.7272 3.3782) (xy 1.7272 -3.3782) (xy -1.7272 -3.3782) (xy -1.7272 3.3782)
			)
			(stroke
				(width 0)
				(type default)
			)
			(fill no)
			(layer "F.Fab")
		)
		(pad "1" smd rect
			(at 0 -2.3495 270)
			(size 2.794 1.143)
			(layers "F.Cu" "F.Mask" "F.Paste")
			(net "12V_PRE_3")
		)
		(pad "2" smd rect
			(at 0 2.3495 270)
			(size 2.794 1.143)
			(layers "F.Cu" "F.Mask" "F.Paste")
			(net "P12V_HDD3")
		)
	)
	(footprint ""
		(layer "F.Cu")
		(at 83.82 -500.761)
		(property "Reference" "R568"
			(at 0 0 0)
			(layer "F.SilkS")
			(hide yes)
			(effects
				(font
					(size 1.27 1.27)
				)
			)
		)
		(property "Value" "300KR2F-GP"
			(at 0.064008 -3.993896 0)
			(unlocked yes)
			(layer "F.Fab")
			(hide yes)
			(effects
				(font
					(size 1.016 1.016)
					(thickness 0.1524)
				)
			)
		)
		(property "Device Type" "R402H16"
			(at 0.064008 -5.517896 0)
			(unlocked yes)
			(layer "F.Fab")
			(hide yes)
			(effects
				(font
					(size 1.016 1.016)
					(thickness 0.1524)
				)
			)
		)
		(duplicate_pad_numbers_are_jumpers no)
		(fp_line
			(start -0.508 -0.9398)
			(end -0.508 0.9398)
			(stroke
				(width 0.1524)
				(type default)
			)
			(layer "F.SilkS")
		)
		(fp_line
			(start 0.508 -0.9398)
			(end -0.508 -0.9398)
			(stroke
				(width 0.1524)
				(type default)
			)
			(layer "F.SilkS")
		)
		(fp_rect
			(start -0.508 0.9398)
			(end 0.508 -0.9398)
			(stroke
				(width 0)
				(type default)
			)
			(fill no)
			(layer "F.CrtYd")
		)
		(fp_rect
			(start -0.508 0.9398)
			(end 0.508 -0.9398)
			(stroke
				(width 0)
				(type default)
			)
			(fill no)
			(layer "F.Fab")
		)
		(pad "1" smd custom
			(at 0 -0.4445)
			(size 0.1397 0.1397)
			(layers "F.Cu" "F.Mask" "F.Paste")
			(net "SW_HDD5_N")
			(options
				(clearance outline)
				(anchor circle)
			)
			(primitives
				(gr_poly
					(pts
						(arc
							(start -0.1778 -0.2794)
							(mid -0.249642 -0.249642)
							(end -0.2794 -0.1778)
						)
						(arc
							(start -0.2794 0.1778)
							(mid -0.249642 0.249642)
							(end -0.1778 0.2794)
						)
						(arc
							(start 0.1778 0.2794)
							(mid 0.249642 0.249642)
							(end 0.2794 0.1778)
						)
						(arc
							(start 0.2794 -0.1778)
							(mid 0.249642 -0.249642)
							(end 0.1778 -0.2794)
						)
					)
					(width 0)
					(fill yes)
				)
			)
		)
		(pad "2" smd custom
			(at 0 0.4445)
			(size 0.1397 0.1397)
			(layers "F.Cu" "F.Mask" "F.Paste")
			(net "P12V")
			(options
				(clearance outline)
				(anchor circle)
			)
			(primitives
				(gr_poly
					(pts
						(arc
							(start -0.1778 -0.2794)
							(mid -0.249642 -0.249642)
							(end -0.2794 -0.1778)
						)
						(arc
							(start -0.2794 0.1778)
							(mid -0.249642 0.249642)
							(end -0.1778 0.2794)
						)
						(arc
							(start 0.1778 0.2794)
							(mid 0.249642 0.249642)
							(end 0.2794 0.1778)
						)
						(arc
							(start 0.2794 -0.1778)
							(mid 0.249642 -0.249642)
							(end 0.1778 -0.2794)
						)
					)
					(width 0)
					(fill yes)
				)
			)
		)
	)
	(footprint ""
		(layer "F.Cu")
		(at 234.753912 -42.779696 90)
		(property "Reference" "R158"
			(at 0 0 90)
			(layer "F.SilkS")
			(hide yes)
			(effects
				(font
					(size 1.27 1.27)
				)
			)
		)
		(property "Value" "0R2J-2-GP"
			(at 0.064008 -3.993896 90)
			(unlocked yes)
			(layer "F.Fab")
			(hide yes)
			(effects
				(font
					(size 1.016 1.016)
					(thickness 0.1524)
				)
			)
		)
		(property "Device Type" "R402H16"
			(at 0.064008 -5.517896 90)
			(unlocked yes)
			(layer "F.Fab")
			(hide yes)
			(effects
				(font
					(size 1.016 1.016)
					(thickness 0.1524)
				)
			)
		)
		(duplicate_pad_numbers_are_jumpers no)
		(fp_line
			(start 0.508 -0.9398)
			(end -0.508 -0.9398)
			(stroke
				(width 0.1524)
				(type default)
			)
			(layer "F.SilkS")
		)
		(fp_line
			(start -0.508 -0.9398)
			(end -0.508 0.9398)
			(stroke
				(width 0.1524)
				(type default)
			)
			(layer "F.SilkS")
		)
		(fp_rect
			(start -0.508 0.9398)
			(end 0.508 -0.9398)
			(stroke
				(width 0)
				(type default)
			)
			(fill no)
			(layer "F.CrtYd")
		)
		(fp_rect
			(start -0.508 0.9398)
			(end 0.508 -0.9398)
			(stroke
				(width 0)
				(type default)
			)
			(fill no)
			(layer "F.Fab")
		)
		(pad "1" smd custom
			(at 0 -0.4445 90)
			(size 0.1397 0.1397)
			(layers "F.Cu" "F.Mask" "F.Paste")
			(net "DRV_ACT_NET4")
			(options
				(clearance outline)
				(anchor circle)
			)
			(primitives
				(gr_poly
					(pts
						(arc
							(start -0.1778 -0.2794)
							(mid -0.249642 -0.249642)
							(end -0.2794 -0.1778)
						)
						(arc
							(start -0.2794 0.1778)
							(mid -0.249642 0.249642)
							(end -0.1778 0.2794)
						)
						(arc
							(start 0.1778 0.2794)
							(mid 0.249642 0.249642)
							(end 0.2794 0.1778)
						)
						(arc
							(start 0.2794 -0.1778)
							(mid 0.249642 -0.249642)
							(end 0.1778 -0.2794)
						)
					)
					(width 0)
					(fill yes)
				)
			)
		)
		(pad "2" smd custom
			(at 0 0.4445 90)
			(size 0.1397 0.1397)
			(layers "F.Cu" "F.Mask" "F.Paste")
			(net "DRIVE_ACT_4")
			(options
				(clearance outline)
				(anchor circle)
			)
			(primitives
				(gr_poly
					(pts
						(arc
							(start -0.1778 -0.2794)
							(mid -0.249642 -0.249642)
							(end -0.2794 -0.1778)
						)
						(arc
							(start -0.2794 0.1778)
							(mid -0.249642 0.249642)
							(end -0.1778 0.2794)
						)
						(arc
							(start 0.1778 0.2794)
							(mid 0.249642 0.249642)
							(end 0.2794 0.1778)
						)
						(arc
							(start 0.2794 -0.1778)
							(mid 0.249642 -0.249642)
							(end 0.1778 -0.2794)
						)
					)
					(width 0)
					(fill yes)
				)
			)
		)
	)
	(footprint ""
		(layer "F.Cu")
		(at 207.390746 -40.9067 180)
		(property "Reference" "R331"
			(at 0 0 180)
			(layer "F.SilkS")
			(hide yes)
			(effects
				(font
					(size 1.27 1.27)
				)
			)
		)
		(property "Value" "4K7R2J-2-GP"
			(at 0.064008 -3.993896 180)
			(unlocked yes)
			(layer "F.Fab")
			(hide yes)
			(effects
				(font
					(size 1.016 1.016)
					(thickness 0.1524)
				)
			)
		)
		(property "Device Type" "R402H16"
			(at 0.064008 -5.517896 180)
			(unlocked yes)
			(layer "F.Fab")
			(hide yes)
			(effects
				(font
					(size 1.016 1.016)
					(thickness 0.1524)
				)
			)
		)
		(duplicate_pad_numbers_are_jumpers no)
		(fp_line
			(start 0.508 -0.9398)
			(end -0.508 -0.9398)
			(stroke
				(width 0.1524)
				(type default)
			)
			(layer "F.SilkS")
		)
		(fp_line
			(start -0.508 -0.9398)
			(end -0.508 0.9398)
			(stroke
				(width 0.1524)
				(type default)
			)
			(layer "F.SilkS")
		)
		(fp_rect
			(start -0.508 0.9398)
			(end 0.508 -0.9398)
			(stroke
				(width 0)
				(type default)
			)
			(fill no)
			(layer "F.CrtYd")
		)
		(fp_rect
			(start -0.508 0.9398)
			(end 0.508 -0.9398)
			(stroke
				(width 0)
				(type default)
			)
			(fill no)
			(layer "F.Fab")
		)
		(pad "1" smd custom
			(at 0 -0.4445 180)
			(size 0.1397 0.1397)
			(layers "F.Cu" "F.Mask" "F.Paste")
			(net "P3V3")
			(options
				(clearance outline)
				(anchor circle)
			)
			(primitives
				(gr_poly
					(pts
						(arc
							(start -0.1778 -0.2794)
							(mid -0.249642 -0.249642)
							(end -0.2794 -0.1778)
						)
						(arc
							(start -0.2794 0.1778)
							(mid -0.249642 0.249642)
							(end -0.1778 0.2794)
						)
						(arc
							(start 0.1778 0.2794)
							(mid 0.249642 0.249642)
							(end 0.2794 0.1778)
						)
						(arc
							(start 0.2794 -0.1778)
							(mid 0.249642 -0.249642)
							(end 0.1778 -0.2794)
						)
					)
					(width 0)
					(fill yes)
				)
			)
		)
		(pad "2" smd custom
			(at 0 0.4445 180)
			(size 0.1397 0.1397)
			(layers "F.Cu" "F.Mask" "F.Paste")
			(net "I2C_B_TMP4_A2")
			(options
				(clearance outline)
				(anchor circle)
			)
			(primitives
				(gr_poly
					(pts
						(arc
							(start -0.1778 -0.2794)
							(mid -0.249642 -0.249642)
							(end -0.2794 -0.1778)
						)
						(arc
							(start -0.2794 0.1778)
							(mid -0.249642 0.249642)
							(end -0.1778 0.2794)
						)
						(arc
							(start 0.1778 0.2794)
							(mid 0.249642 0.249642)
							(end 0.2794 0.1778)
						)
						(arc
							(start 0.2794 -0.1778)
							(mid 0.249642 -0.249642)
							(end 0.1778 -0.2794)
						)
					)
					(width 0)
					(fill yes)
				)
			)
		)
	)
	(footprint ""
		(layer "F.Cu")
		(at 27.939746 -221.6277)
		(property "Reference" "TP37"
			(at 0 0 0)
			(layer "F.SilkS")
			(hide yes)
			(effects
				(font
					(size 1.27 1.27)
				)
			)
		)
		(property "Value" "TPAD32-GP"
			(at 0 -3.166364 0)
			(unlocked yes)
			(layer "F.Fab")
			(hide yes)
			(effects
				(font
					(size 1.016 1.016)
					(thickness 0.1524)
				)
			)
		)
		(property "Device Type" "TPAD32"
			(at 0 -4.690618 0)
			(unlocked yes)
			(layer "F.Fab")
			(hide yes)
			(effects
				(font
					(size 1.016 1.016)
					(thickness 0.1524)
				)
			)
		)
		(duplicate_pad_numbers_are_jumpers no)
		(fp_poly
			(pts
				(arc
					(start 0.4064 0)
					(mid -0.4064 0)
					(end 0.4064 0)
				)
			)
			(stroke
				(width 0)
				(type default)
			)
			(fill no)
			(layer "F.CrtYd")
		)
		(fp_poly
			(pts
				(arc
					(start 0.7112 0)
					(mid -0.7112 0)
					(end 0.7112 0)
				)
			)
			(stroke
				(width 0)
				(type default)
			)
			(fill no)
			(layer "F.Fab")
		)
		(pad "1" smd circle
			(at 0 0)
			(size 0.8128 0.8128)
			(layers "F.Cu" "F.Mask" "F.Paste")
			(net "ACT_HDD12")
		)
	)
	(footprint ""
		(layer "F.Cu")
		(at 224.0788 -440.3852 90)
		(property "Reference" "PC40"
			(at 0 0 90)
			(layer "F.SilkS")
			(hide yes)
			(effects
				(font
					(size 1.27 1.27)
				)
			)
		)
		(property "Value" "SC4D7U50V6KX-L2-GP"
			(at 0 -6.8072 90)
			(unlocked yes)
			(layer "F.Fab")
			(hide yes)
			(effects
				(font
					(size 1.016 1.016)
					(thickness 0.1524)
				)
			)
		)
		(property "Device Type" "C1206H38"
			(at 0 -8.7122 90)
			(unlocked yes)
			(layer "F.Fab")
			(hide yes)
			(effects
				(font
					(size 1.016 1.016)
					(thickness 0.1524)
				)
			)
		)
		(duplicate_pad_numbers_are_jumpers no)
		(fp_line
			(start 1.016 -2.2352)
			(end -1.016 -2.2352)
			(stroke
				(width 0.1524)
				(type default)
			)
			(layer "F.SilkS")
		)
		(fp_line
			(start 1.016 -2.2352)
			(end 1.016 -0.8382)
			(stroke
				(width 0.1524)
				(type default)
			)
			(layer "F.SilkS")
		)
		(fp_line
			(start -1.016 -2.2352)
			(end -1.016 -0.8382)
			(stroke
				(width 0.1524)
				(type default)
			)
			(layer "F.SilkS")
		)
		(fp_line
			(start 1.016 0.8382)
			(end 1.016 2.2352)
			(stroke
				(width 0.1524)
				(type default)
			)
			(layer "F.SilkS")
		)
		(fp_line
			(start 1.016 2.2352)
			(end -1.016 2.2352)
			(stroke
				(width 0.1524)
				(type default)
			)
			(layer "F.SilkS")
		)
		(fp_line
			(start -1.016 2.2352)
			(end -1.016 0.8128)
			(stroke
				(width 0.1524)
				(type default)
			)
			(layer "F.SilkS")
		)
		(fp_rect
			(start -1.0922 2.3114)
			(end 1.0922 -2.3114)
			(stroke
				(width 0)
				(type default)
			)
			(fill no)
			(layer "F.CrtYd")
		)
		(fp_poly
			(pts
				(xy -1.0922 -2.3114) (xy 1.0922 -2.3114) (xy 1.0922 2.3114) (xy -1.0922 2.3114)
			)
			(stroke
				(width 0)
				(type default)
			)
			(fill no)
			(layer "F.Fab")
		)
		(pad "1" smd rect
			(at 0 -1.397 90)
			(size 1.651 1.27)
			(layers "F.Cu" "F.Mask" "F.Paste")
			(net "P3V3_IN")
		)
		(pad "2" smd rect
			(at 0 1.397 90)
			(size 1.651 1.27)
			(layers "F.Cu" "F.Mask" "F.Paste")
			(net "GND")
		)
	)
	(footprint ""
		(layer "F.Cu")
		(at 215.259412 -71.354696 90)
		(property "Reference" "R162"
			(at 0 0 90)
			(layer "F.SilkS")
			(hide yes)
			(effects
				(font
					(size 1.27 1.27)
				)
			)
		)
		(property "Value" "4K7R2J-2-GP"
			(at 0.064008 -3.993896 90)
			(unlocked yes)
			(layer "F.Fab")
			(hide yes)
			(effects
				(font
					(size 1.016 1.016)
					(thickness 0.1524)
				)
			)
		)
		(property "Device Type" "R402H16"
			(at 0.064008 -5.517896 90)
			(unlocked yes)
			(layer "F.Fab")
			(hide yes)
			(effects
				(font
					(size 1.016 1.016)
					(thickness 0.1524)
				)
			)
		)
		(duplicate_pad_numbers_are_jumpers no)
		(fp_line
			(start 0.508 -0.9398)
			(end -0.508 -0.9398)
			(stroke
				(width 0.1524)
				(type default)
			)
			(layer "F.SilkS")
		)
		(fp_line
			(start -0.508 -0.9398)
			(end -0.508 0.9398)
			(stroke
				(width 0.1524)
				(type default)
			)
			(layer "F.SilkS")
		)
		(fp_rect
			(start -0.508 0.9398)
			(end 0.508 -0.9398)
			(stroke
				(width 0)
				(type default)
			)
			(fill no)
			(layer "F.CrtYd")
		)
		(fp_rect
			(start -0.508 0.9398)
			(end 0.508 -0.9398)
			(stroke
				(width 0)
				(type default)
			)
			(fill no)
			(layer "F.Fab")
		)
		(pad "1" smd custom
			(at 0 -0.4445 90)
			(size 0.1397 0.1397)
			(layers "F.Cu" "F.Mask" "F.Paste")
			(net "P3V3")
			(options
				(clearance outline)
				(anchor circle)
			)
			(primitives
				(gr_poly
					(pts
						(arc
							(start -0.1778 -0.2794)
							(mid -0.249642 -0.249642)
							(end -0.2794 -0.1778)
						)
						(arc
							(start -0.2794 0.1778)
							(mid -0.249642 0.249642)
							(end -0.1778 0.2794)
						)
						(arc
							(start 0.1778 0.2794)
							(mid 0.249642 0.249642)
							(end 0.2794 0.1778)
						)
						(arc
							(start 0.2794 -0.1778)
							(mid 0.249642 -0.249642)
							(end 0.1778 -0.2794)
						)
					)
					(width 0)
					(fill yes)
				)
			)
		)
		(pad "2" smd custom
			(at 0 0.4445 90)
			(size 0.1397 0.1397)
			(layers "F.Cu" "F.Mask" "F.Paste")
			(net "HDD_PRSNT_NET4")
			(options
				(clearance outline)
				(anchor circle)
			)
			(primitives
				(gr_poly
					(pts
						(arc
							(start -0.1778 -0.2794)
							(mid -0.249642 -0.249642)
							(end -0.2794 -0.1778)
						)
						(arc
							(start -0.2794 0.1778)
							(mid -0.249642 0.249642)
							(end -0.1778 0.2794)
						)
						(arc
							(start 0.1778 0.2794)
							(mid 0.249642 0.249642)
							(end 0.2794 0.1778)
						)
						(arc
							(start 0.2794 -0.1778)
							(mid 0.249642 -0.249642)
							(end 0.1778 -0.2794)
						)
					)
					(width 0)
					(fill yes)
				)
			)
		)
	)
	(footprint ""
		(layer "F.Cu")
		(at 227.499926 -144.159986 180)
		(property "Reference" "LED4"
			(at 0 0 180)
			(layer "F.SilkS")
			(hide yes)
			(effects
				(font
					(size 1.27 1.27)
				)
			)
		)
		(property "Value" "LED-RB-4-GP"
			(at 5.88899 1.80848 180)
			(unlocked yes)
			(layer "F.Fab")
			(hide yes)
			(effects
				(font
					(size 1.016 1.016)
					(thickness 0.1524)
				)
			)
		)
		(property "Device Type" "LED1613-4PH20"
			(at 5.88899 0.28448 180)
			(unlocked yes)
			(layer "F.Fab")
			(hide yes)
			(effects
				(font
					(size 1.016 1.016)
					(thickness 0.1524)
				)
			)
		)
		(duplicate_pad_numbers_are_jumpers no)
		(fp_line
			(start 1.4478 0.9652)
			(end -1.4478 0.9652)
			(stroke
				(width 0.1524)
				(type default)
			)
			(layer "F.SilkS")
		)
		(fp_line
			(start 1.4478 -0.9652)
			(end 1.4478 0.9652)
			(stroke
				(width 0.1524)
				(type default)
			)
			(layer "F.SilkS")
		)
		(fp_line
			(start -1.4478 0.9652)
			(end -1.4478 -0.9652)
			(stroke
				(width 0.1524)
				(type default)
			)
			(layer "F.SilkS")
		)
		(fp_line
			(start -1.4478 0.9652)
			(end -1.4478 -0.9652)
			(stroke
				(width 0.508)
				(type default)
			)
			(layer "F.SilkS")
		)
		(fp_line
			(start -1.4478 -0.9652)
			(end 1.4478 -0.9652)
			(stroke
				(width 0.1524)
				(type default)
			)
			(layer "F.SilkS")
		)
		(fp_rect
			(start -0.8001 0.6477)
			(end 0.8001 -0.6477)
			(stroke
				(width 0)
				(type default)
			)
			(fill no)
			(layer "F.CrtYd")
		)
		(fp_poly
			(pts
				(xy -1.7018 1.2192) (xy -1.7018 -0.06223) (xy -0.8001 -0.06223) (xy -0.8001 0.6477) (xy 0.8001 0.6477)
				(xy 0.8001 -0.6477) (xy -0.8001 -0.6477) (xy -0.8001 -0.0635) (xy -1.7018 -0.0635) (xy -1.7018 -1.2192)
				(xy 1.7018 -1.2192) (xy 1.7018 1.2192)
			)
			(stroke
				(width 0)
				(type default)
			)
			(fill no)
			(layer "F.CrtYd")
		)
		(fp_rect
			(start -1.7018 1.2192)
			(end 1.7018 -1.2192)
			(stroke
				(width 0)
				(type default)
			)
			(fill no)
			(layer "F.Fab")
		)
		(pad "1" smd rect
			(at -0.73025 0.4064 180)
			(size 0.9144 0.6096)
			(layers "F.Cu" "F.Mask" "F.Paste")
			(net "DRV_ACT_NET3")
		)
		(pad "2" smd rect
			(at -0.73025 -0.4064 180)
			(size 0.9144 0.6096)
			(layers "F.Cu" "F.Mask" "F.Paste")
			(net "FLT_NET_HDD3")
		)
		(pad "3" smd rect
			(at 0.73025 -0.4064 180)
			(size 0.9144 0.6096)
			(layers "F.Cu" "F.Mask" "F.Paste")
			(net "FLT_HDD3")
		)
		(pad "4" smd rect
			(at 0.73025 0.4064 180)
			(size 0.9144 0.6096)
			(layers "F.Cu" "F.Mask" "F.Paste")
			(net "DRV_ACT_3")
		)
	)
	(footprint ""
		(layer "F.Cu")
		(at 218.646756 -475.262702 -90)
		(property "Reference" "C104"
			(at 0 0 270)
			(layer "F.SilkS")
			(hide yes)
			(effects
				(font
					(size 1.27 1.27)
				)
			)
		)
		(property "Value" "SCD01U50V2KX-1GP"
			(at 1.1811 -2.7051 270)
			(unlocked yes)
			(layer "F.Fab")
			(hide yes)
			(effects
				(font
					(size 1.016 1.016)
					(thickness 0.1524)
				)
			)
		)
		(property "Device Type" "C402H22"
			(at 1.1811 -4.2291 270)
			(unlocked yes)
			(layer "F.Fab")
			(hide yes)
			(effects
				(font
					(size 1.016 1.016)
					(thickness 0.1524)
				)
			)
		)
		(duplicate_pad_numbers_are_jumpers no)
		(fp_rect
			(start -0.4318 0.9525)
			(end 0.4318 -0.9525)
			(stroke
				(width 0)
				(type default)
			)
			(fill no)
			(layer "F.CrtYd")
		)
		(fp_rect
			(start -0.4318 0.9525)
			(end 0.4318 -0.9525)
			(stroke
				(width 0)
				(type default)
			)
			(fill no)
			(layer "F.Fab")
		)
		(pad "1" smd custom
			(at 0 -0.4445 270)
			(size 0.1524 0.1524)
			(layers "F.Cu" "F.Mask" "F.Paste")
			(net "SAS2X28_DRIVE_RX_N_B0")
			(options
				(clearance outline)
				(anchor circle)
			)
			(primitives
				(gr_poly
					(pts
						(arc
							(start 0.3048 -0.2032)
							(mid 0.275042 -0.275042)
							(end 0.2032 -0.3048)
						)
						(arc
							(start -0.2032 -0.3048)
							(mid -0.275042 -0.275042)
							(end -0.3048 -0.2032)
						)
						(arc
							(start -0.3048 0.2032)
							(mid -0.275042 0.275042)
							(end -0.2032 0.3048)
						)
						(arc
							(start 0.2032 0.3048)
							(mid 0.275042 0.275042)
							(end 0.3048 0.2032)
						)
					)
					(width 0)
					(fill yes)
				)
			)
		)
		(pad "2" smd custom
			(at 0 0.4445 270)
			(size 0.1524 0.1524)
			(layers "F.Cu" "F.Mask" "F.Paste")
			(net "SAS2X28_B_HDD0_RX_-")
			(options
				(clearance outline)
				(anchor circle)
			)
			(primitives
				(gr_poly
					(pts
						(arc
							(start 0.3048 -0.2032)
							(mid 0.275042 -0.275042)
							(end 0.2032 -0.3048)
						)
						(arc
							(start -0.2032 -0.3048)
							(mid -0.275042 -0.275042)
							(end -0.3048 -0.2032)
						)
						(arc
							(start -0.3048 0.2032)
							(mid -0.275042 0.275042)
							(end -0.2032 0.3048)
						)
						(arc
							(start 0.2032 0.3048)
							(mid 0.275042 0.275042)
							(end 0.3048 0.2032)
						)
					)
					(width 0)
					(fill yes)
				)
			)
		)
	)
	(footprint ""
		(layer "F.Cu")
		(at 166.509446 -455.837036)
		(property "Reference" "C354"
			(at 0 0 0)
			(layer "F.SilkS")
			(hide yes)
			(effects
				(font
					(size 1.27 1.27)
				)
			)
		)
		(property "Value" "SCD1U16V2KX-3GP"
			(at 1.1811 -2.7051 0)
			(unlocked yes)
			(layer "F.Fab")
			(hide yes)
			(effects
				(font
					(size 1.016 1.016)
					(thickness 0.1524)
				)
			)
		)
		(property "Device Type" "C402H22"
			(at 1.1811 -4.2291 0)
			(unlocked yes)
			(layer "F.Fab")
			(hide yes)
			(effects
				(font
					(size 1.016 1.016)
					(thickness 0.1524)
				)
			)
		)
		(duplicate_pad_numbers_are_jumpers no)
		(fp_rect
			(start -0.4318 0.9525)
			(end 0.4318 -0.9525)
			(stroke
				(width 0)
				(type default)
			)
			(fill no)
			(layer "F.CrtYd")
		)
		(fp_rect
			(start -0.4318 0.9525)
			(end 0.4318 -0.9525)
			(stroke
				(width 0)
				(type default)
			)
			(fill no)
			(layer "F.Fab")
		)
		(pad "1" smd custom
			(at 0 -0.4445)
			(size 0.1524 0.1524)
			(layers "F.Cu" "F.Mask" "F.Paste")
			(net "P5VB_SENSE")
			(options
				(clearance outline)
				(anchor circle)
			)
			(primitives
				(gr_poly
					(pts
						(arc
							(start 0.3048 -0.2032)
							(mid 0.275042 -0.275042)
							(end 0.2032 -0.3048)
						)
						(arc
							(start -0.2032 -0.3048)
							(mid -0.275042 -0.275042)
							(end -0.3048 -0.2032)
						)
						(arc
							(start -0.3048 0.2032)
							(mid -0.275042 0.275042)
							(end -0.2032 0.3048)
						)
						(arc
							(start 0.2032 0.3048)
							(mid 0.275042 0.275042)
							(end 0.3048 0.2032)
						)
					)
					(width 0)
					(fill yes)
				)
			)
		)
		(pad "2" smd custom
			(at 0 0.4445)
			(size 0.1524 0.1524)
			(layers "F.Cu" "F.Mask" "F.Paste")
			(net "GND")
			(options
				(clearance outline)
				(anchor circle)
			)
			(primitives
				(gr_poly
					(pts
						(arc
							(start 0.3048 -0.2032)
							(mid 0.275042 -0.275042)
							(end 0.2032 -0.3048)
						)
						(arc
							(start -0.2032 -0.3048)
							(mid -0.275042 -0.275042)
							(end -0.3048 -0.2032)
						)
						(arc
							(start -0.3048 0.2032)
							(mid -0.275042 0.275042)
							(end -0.2032 0.3048)
						)
						(arc
							(start 0.2032 0.3048)
							(mid 0.275042 0.275042)
							(end 0.3048 0.2032)
						)
					)
					(width 0)
					(fill yes)
				)
			)
		)
	)
	(footprint ""
		(layer "F.Cu")
		(at 193.246756 -495.862102 -90)
		(property "Reference" "Q1"
			(at 0 0 270)
			(layer "F.SilkS")
			(hide yes)
			(effects
				(font
					(size 1.27 1.27)
				)
			)
		)
		(property "Value" "2N7002DW-7F-GP"
			(at -2.3622 -8.2042 270)
			(unlocked yes)
			(layer "F.Fab")
			(hide yes)
			(effects
				(font
					(size 1.016 1.016)
					(thickness 0.1524)
				)
			)
		)
		(property "Device Type" "SOT-363H44"
			(at -2.3622 -10.1092 270)
			(unlocked yes)
			(layer "F.Fab")
			(hide yes)
			(effects
				(font
					(size 1.016 1.016)
					(thickness 0.1524)
				)
			)
		)
		(duplicate_pad_numbers_are_jumpers no)
		(fp_line
			(start -1.4478 1.7018)
			(end 1.4478 1.7018)
			(stroke
				(width 0.1524)
				(type default)
			)
			(layer "F.SilkS")
		)
		(fp_line
			(start 1.4478 1.7018)
			(end 1.4478 -1.7018)
			(stroke
				(width 0.1524)
				(type default)
			)
			(layer "F.SilkS")
		)
		(fp_line
			(start -1.27 1.524)
			(end -1.27 0.6604)
			(stroke
				(width 0.4826)
				(type default)
			)
			(layer "F.SilkS")
		)
		(fp_line
			(start -1.4478 -1.7018)
			(end -1.4478 1.7018)
			(stroke
				(width 0.1524)
				(type default)
			)
			(layer "F.SilkS")
		)
		(fp_line
			(start 1.4478 -1.7018)
			(end -1.4478 -1.7018)
			(stroke
				(width 0.1524)
				(type default)
			)
			(layer "F.SilkS")
		)
		(fp_poly
			(pts
				(xy -1.524 -1.778) (xy 1.524 -1.778) (xy 1.524 1.778) (xy -1.524 1.778)
			)
			(stroke
				(width 0)
				(type default)
			)
			(fill no)
			(layer "F.CrtYd")
		)
		(fp_poly
			(pts
				(xy -1.524 -1.778) (xy 1.524 -1.778) (xy 1.524 1.778) (xy -1.524 1.778)
			)
			(stroke
				(width 0)
				(type default)
			)
			(fill no)
			(layer "F.Fab")
		)
		(pad "1" smd rect
			(at -0.65024 0.9398 270)
			(size 0.4064 1.016)
			(layers "F.Cu" "F.Mask" "F.Paste")
			(net "GND")
		)
		(pad "2" smd rect
			(at 0 0.9398 270)
			(size 0.4064 1.016)
			(layers "F.Cu" "F.Mask" "F.Paste")
			(net "SW_PWR_R_HDD0")
		)
		(pad "3" smd rect
			(at 0.65024 0.9398 270)
			(size 0.4064 1.016)
			(layers "F.Cu" "F.Mask" "F.Paste")
			(net "SW_HDD0_P")
		)
		(pad "4" smd rect
			(at 0.65024 -0.9398 270)
			(size 0.4064 1.016)
			(layers "F.Cu" "F.Mask" "F.Paste")
			(net "GND")
		)
		(pad "5" smd rect
			(at 0 -0.9398 270)
			(size 0.4064 1.016)
			(layers "F.Cu" "F.Mask" "F.Paste")
			(net "SW_HDD0_G")
		)
		(pad "6" smd rect
			(at -0.65024 -0.9398 270)
			(size 0.4064 1.016)
			(layers "F.Cu" "F.Mask" "F.Paste")
			(net "SW_HDD0_R")
		)
	)
	(footprint ""
		(layer "F.Cu")
		(at 99.186746 -9.9187 90)
		(property "Reference" "Q30"
			(at 0 0 90)
			(layer "F.SilkS")
			(hide yes)
			(effects
				(font
					(size 1.27 1.27)
				)
			)
		)
		(property "Value" "2N7002DW-7F-GP"
			(at -2.3622 -8.2042 90)
			(unlocked yes)
			(layer "F.Fab")
			(hide yes)
			(effects
				(font
					(size 1.016 1.016)
					(thickness 0.1524)
				)
			)
		)
		(property "Device Type" "SOT-363H44"
			(at -2.3622 -10.1092 90)
			(unlocked yes)
			(layer "F.Fab")
			(hide yes)
			(effects
				(font
					(size 1.016 1.016)
					(thickness 0.1524)
				)
			)
		)
		(duplicate_pad_numbers_are_jumpers no)
		(fp_line
			(start 1.4478 -1.7018)
			(end -1.4478 -1.7018)
			(stroke
				(width 0.1524)
				(type default)
			)
			(layer "F.SilkS")
		)
		(fp_line
			(start -1.4478 -1.7018)
			(end -1.4478 1.7018)
			(stroke
				(width 0.1524)
				(type default)
			)
			(layer "F.SilkS")
		)
		(fp_line
			(start -1.27 1.524)
			(end -1.27 0.6604)
			(stroke
				(width 0.4826)
				(type default)
			)
			(layer "F.SilkS")
		)
		(fp_line
			(start 1.4478 1.7018)
			(end 1.4478 -1.7018)
			(stroke
				(width 0.1524)
				(type default)
			)
			(layer "F.SilkS")
		)
		(fp_line
			(start -1.4478 1.7018)
			(end 1.4478 1.7018)
			(stroke
				(width 0.1524)
				(type default)
			)
			(layer "F.SilkS")
		)
		(fp_poly
			(pts
				(xy -1.524 -1.778) (xy 1.524 -1.778) (xy 1.524 1.778) (xy -1.524 1.778)
			)
			(stroke
				(width 0)
				(type default)
			)
			(fill no)
			(layer "F.CrtYd")
		)
		(fp_poly
			(pts
				(xy -1.524 -1.778) (xy 1.524 -1.778) (xy 1.524 1.778) (xy -1.524 1.778)
			)
			(stroke
				(width 0)
				(type default)
			)
			(fill no)
			(layer "F.Fab")
		)
		(pad "1" smd rect
			(at -0.65024 0.9398 90)
			(size 0.4064 1.016)
			(layers "F.Cu" "F.Mask" "F.Paste")
			(net "GND")
		)
		(pad "2" smd rect
			(at 0 0.9398 90)
			(size 0.4064 1.016)
			(layers "F.Cu" "F.Mask" "F.Paste")
			(net "SW_PWR_R_HDD14")
		)
		(pad "3" smd rect
			(at 0.65024 0.9398 90)
			(size 0.4064 1.016)
			(layers "F.Cu" "F.Mask" "F.Paste")
			(net "SW_HDD14_P")
		)
		(pad "4" smd rect
			(at 0.65024 -0.9398 90)
			(size 0.4064 1.016)
			(layers "F.Cu" "F.Mask" "F.Paste")
			(net "GND")
		)
		(pad "5" smd rect
			(at 0 -0.9398 90)
			(size 0.4064 1.016)
			(layers "F.Cu" "F.Mask" "F.Paste")
			(net "SW_HDD14_G")
		)
		(pad "6" smd rect
			(at -0.65024 -0.9398 90)
			(size 0.4064 1.016)
			(layers "F.Cu" "F.Mask" "F.Paste")
			(net "SW_HDD14_R")
		)
	)
	(footprint ""
		(layer "F.Cu")
		(at 33.02 -346.71 90)
		(property "Reference" "R257"
			(at 0 0 90)
			(layer "F.SilkS")
			(hide yes)
			(effects
				(font
					(size 1.27 1.27)
				)
			)
		)
		(property "Value" "330R2F-GP"
			(at 0.064008 -3.993896 90)
			(unlocked yes)
			(layer "F.Fab")
			(hide yes)
			(effects
				(font
					(size 1.016 1.016)
					(thickness 0.1524)
				)
			)
		)
		(property "Device Type" "R402H16"
			(at 0.064008 -5.517896 90)
			(unlocked yes)
			(layer "F.Fab")
			(hide yes)
			(effects
				(font
					(size 1.016 1.016)
					(thickness 0.1524)
				)
			)
		)
		(duplicate_pad_numbers_are_jumpers no)
		(fp_line
			(start 0.508 -0.9398)
			(end -0.508 -0.9398)
			(stroke
				(width 0.1524)
				(type default)
			)
			(layer "F.SilkS")
		)
		(fp_line
			(start -0.508 -0.9398)
			(end -0.508 0.9398)
			(stroke
				(width 0.1524)
				(type default)
			)
			(layer "F.SilkS")
		)
		(fp_rect
			(start -0.508 0.9398)
			(end 0.508 -0.9398)
			(stroke
				(width 0)
				(type default)
			)
			(fill no)
			(layer "F.CrtYd")
		)
		(fp_rect
			(start -0.508 0.9398)
			(end 0.508 -0.9398)
			(stroke
				(width 0)
				(type default)
			)
			(fill no)
			(layer "F.Fab")
		)
		(pad "1" smd custom
			(at 0 -0.4445 90)
			(size 0.1397 0.1397)
			(layers "F.Cu" "F.Mask" "F.Paste")
			(net "P3V3_HDD11_LED")
			(options
				(clearance outline)
				(anchor circle)
			)
			(primitives
				(gr_poly
					(pts
						(arc
							(start -0.1778 -0.2794)
							(mid -0.249642 -0.249642)
							(end -0.2794 -0.1778)
						)
						(arc
							(start -0.2794 0.1778)
							(mid -0.249642 0.249642)
							(end -0.1778 0.2794)
						)
						(arc
							(start 0.1778 0.2794)
							(mid 0.249642 0.249642)
							(end 0.2794 0.1778)
						)
						(arc
							(start 0.2794 -0.1778)
							(mid 0.249642 -0.249642)
							(end 0.1778 -0.2794)
						)
					)
					(width 0)
					(fill yes)
				)
			)
		)
		(pad "2" smd custom
			(at 0 0.4445 90)
			(size 0.1397 0.1397)
			(layers "F.Cu" "F.Mask" "F.Paste")
			(net "FLT_HDD11")
			(options
				(clearance outline)
				(anchor circle)
			)
			(primitives
				(gr_poly
					(pts
						(arc
							(start -0.1778 -0.2794)
							(mid -0.249642 -0.249642)
							(end -0.2794 -0.1778)
						)
						(arc
							(start -0.2794 0.1778)
							(mid -0.249642 0.249642)
							(end -0.1778 0.2794)
						)
						(arc
							(start 0.1778 0.2794)
							(mid 0.249642 0.249642)
							(end 0.2794 0.1778)
						)
						(arc
							(start 0.2794 -0.1778)
							(mid 0.249642 -0.249642)
							(end 0.1778 -0.2794)
						)
					)
					(width 0)
					(fill yes)
				)
			)
		)
	)
	(footprint ""
		(layer "F.Cu")
		(at 42.500042 -67.669918 90)
		(property "Reference" "SKT10"
			(at 0 0 90)
			(layer "F.SilkS")
			(hide yes)
			(effects
				(font
					(size 1.27 1.27)
				)
			)
		)
		(property "Value" "SKT-SATA14P-15P-12-GP"
			(at -22.6187 8.1788 90)
			(unlocked yes)
			(layer "F.Fab")
			(hide yes)
			(effects
				(font
					(size 1.016 1.016)
					(thickness 0.1524)
				)
			)
		)
		(property "Device Type" "87945-1001"
			(at -22.6187 6.6548 90)
			(unlocked yes)
			(layer "F.Fab")
			(hide yes)
			(effects
				(font
					(size 1.016 1.016)
					(thickness 0.1524)
				)
			)
		)
		(duplicate_pad_numbers_are_jumpers no)
		(fp_line
			(start -15.3924 -5.8547)
			(end -16.3576 -5.8547)
			(stroke
				(width 0.3302)
				(type default)
			)
			(layer "F.SilkS")
		)
		(fp_line
			(start 20.4724 -5.7658)
			(end 20.4724 -2.3114)
			(stroke
				(width 0.1524)
				(type default)
			)
			(layer "F.SilkS")
		)
		(fp_line
			(start -20.4724 -5.7658)
			(end 20.4724 -5.7658)
			(stroke
				(width 0.1524)
				(type default)
			)
			(layer "F.SilkS")
		)
		(fp_line
			(start 23.7617 -2.3114)
			(end 23.7617 2.3114)
			(stroke
				(width 0.1524)
				(type default)
			)
			(layer "F.SilkS")
		)
		(fp_line
			(start 20.4724 -2.3114)
			(end 23.7617 -2.3114)
			(stroke
				(width 0.1524)
				(type default)
			)
			(layer "F.SilkS")
		)
		(fp_line
			(start -20.4724 -2.3114)
			(end -20.4724 -5.7658)
			(stroke
				(width 0.1524)
				(type default)
			)
			(layer "F.SilkS")
		)
		(fp_line
			(start -23.7617 -2.3114)
			(end -20.4724 -2.3114)
			(stroke
				(width 0.1524)
				(type default)
			)
			(layer "F.SilkS")
		)
		(fp_line
			(start 23.117556 -0.5461)
			(end 23.117556 0.5461)
			(stroke
				(width 0.3048)
				(type default)
			)
			(layer "F.SilkS")
		)
		(fp_line
			(start -20.882356 -0.5461)
			(end -20.882356 0.5461)
			(stroke
				(width 0.3048)
				(type default)
			)
			(layer "F.SilkS")
		)
		(fp_line
			(start 20.882356 0.5461)
			(end 20.882356 -0.5461)
			(stroke
				(width 0.3048)
				(type default)
			)
			(layer "F.SilkS")
		)
		(fp_line
			(start -23.117556 0.5461)
			(end -23.117556 -0.5461)
			(stroke
				(width 0.3048)
				(type default)
			)
			(layer "F.SilkS")
		)
		(fp_line
			(start 23.7617 2.3114)
			(end 20.4724 2.3114)
			(stroke
				(width 0.1524)
				(type default)
			)
			(layer "F.SilkS")
		)
		(fp_line
			(start 20.4724 2.3114)
			(end 20.4724 9.652)
			(stroke
				(width 0.1524)
				(type default)
			)
			(layer "F.SilkS")
		)
		(fp_line
			(start -20.4724 2.3114)
			(end -23.7617 2.3114)
			(stroke
				(width 0.1524)
				(type default)
			)
			(layer "F.SilkS")
		)
		(fp_line
			(start -23.7617 2.3114)
			(end -23.7617 -2.3114)
			(stroke
				(width 0.1524)
				(type default)
			)
			(layer "F.SilkS")
		)
		(fp_line
			(start 17.8435 7.9502)
			(end -17.8435 7.9502)
			(stroke
				(width 0.1524)
				(type default)
			)
			(layer "F.SilkS")
		)
		(fp_line
			(start -17.8435 7.9502)
			(end -17.8435 9.652)
			(stroke
				(width 0.1524)
				(type default)
			)
			(layer "F.SilkS")
		)
		(fp_line
			(start 20.4724 9.652)
			(end 17.8435 9.652)
			(stroke
				(width 0.1524)
				(type default)
			)
			(layer "F.SilkS")
		)
		(fp_line
			(start 17.8435 9.652)
			(end 17.8435 7.9502)
			(stroke
				(width 0.1524)
				(type default)
			)
			(layer "F.SilkS")
		)
		(fp_line
			(start -17.8435 9.652)
			(end -20.4724 9.652)
			(stroke
				(width 0.1524)
				(type default)
			)
			(layer "F.SilkS")
		)
		(fp_line
			(start -20.4724 9.652)
			(end -20.4724 2.3114)
			(stroke
				(width 0.1524)
				(type default)
			)
			(layer "F.SilkS")
		)
		(fp_arc
			(start 20.882356 -0.5461)
			(mid 21.999956 -1.6637)
			(end 23.117556 -0.5461)
			(stroke
				(width 0.3048)
				(type default)
			)
			(layer "F.SilkS")
		)
		(fp_arc
			(start -23.117556 -0.5461)
			(mid -21.999956 -1.6637)
			(end -20.882356 -0.5461)
			(stroke
				(width 0.3048)
				(type default)
			)
			(layer "F.SilkS")
		)
		(fp_arc
			(start 23.117556 0.5461)
			(mid 21.999956 1.6637)
			(end 20.882356 0.5461)
			(stroke
				(width 0.3048)
				(type default)
			)
			(layer "F.SilkS")
		)
		(fp_arc
			(start -20.882356 0.5461)
			(mid -21.999956 1.6637)
			(end -23.117556 0.5461)
			(stroke
				(width 0.3048)
				(type default)
			)
			(layer "F.SilkS")
		)
		(fp_poly
			(pts
				(xy -15.87119 -5.838698) (xy -15.23619 -6.473698) (xy -16.50619 -6.473698)
			)
			(stroke
				(width 0)
				(type default)
			)
			(fill yes)
			(layer "F.SilkS")
		)
		(fp_poly
			(pts
				(xy -20.2184 -5.5118) (xy 20.2184 -5.5118) (xy 20.2184 -2.0574) (xy 23.5077 -2.0574) (xy 23.5077 2.0574)
				(xy 20.2184 2.0574) (xy 20.2184 9.398) (xy 18.0975 9.398) (xy 18.0975 7.6962) (xy -18.0975 7.6962)
				(xy -18.0975 9.398) (xy -20.2184 9.398) (xy -20.2184 2.0574) (xy -23.5077 2.0574) (xy -23.5077 -2.0574)
				(xy -20.2184 -2.0574)
			)
			(stroke
				(width 0)
				(type default)
			)
			(fill no)
			(layer "F.CrtYd")
		)
		(fp_poly
			(pts
				(xy -20.2184 -5.5118) (xy -20.2184 -6.0198) (xy -20.7264 -6.0198) (xy -20.7264 -2.5654) (xy -24.0157 -2.5654)
				(xy -24.0157 2.5654) (xy -20.7264 2.5654) (xy -20.7264 9.906) (xy -17.5895 9.906) (xy -17.5895 8.2042)
				(xy 17.5895 8.2042) (xy 17.5895 9.906) (xy 20.7264 9.906) (xy 20.7264 2.5654) (xy 24.0157 2.5654)
				(xy 24.0157 -2.5654) (xy 20.7264 -2.5654) (xy 20.7264 -6.0198) (xy -20.21586 -6.0198) (xy -20.21586 -5.5118)
				(xy 20.2184 -5.5118) (xy 20.2184 -2.0574) (xy 23.5077 -2.0574) (xy 23.5077 2.0574) (xy 20.2184 2.0574)
				(xy 20.2184 9.398) (xy 18.0975 9.398) (xy 18.0975 7.6962) (xy -18.0975 7.6962) (xy -18.0975 9.398)
				(xy -20.2184 9.398) (xy -20.2184 2.0574) (xy -23.5077 2.0574) (xy -23.5077 -2.0574) (xy -20.2184 -2.0574)
			)
			(stroke
				(width 0)
				(type default)
			)
			(fill no)
			(layer "F.CrtYd")
		)
		(fp_poly
			(pts
				(xy -20.7264 -6.0198) (xy -20.7264 -2.5654) (xy -24.0157 -2.5654) (xy -24.0157 2.5654) (xy -20.7264 2.5654)
				(xy -20.7264 9.906) (xy -17.5895 9.906) (xy -17.5895 8.2042) (xy 17.5895 8.2042) (xy 17.5895 9.906)
				(xy 20.7264 9.906) (xy 20.7264 2.5654) (xy 24.0157 2.5654) (xy 24.0157 -2.5654) (xy 20.7264 -2.5654)
				(xy 20.7264 -6.0198)
			)
			(stroke
				(width 0)
				(type default)
			)
			(fill no)
			(layer "F.Fab")
		)
		(pad "" np_thru_hole circle
			(at -18.999962 -2.350008 90)
			(size 0.254 0.254)
			(drill 1.8542)
			(layers "*.Cu" "*.Mask")
			(clearance 1.1557)
			(thermal_gap 1.1557)
		)
		(pad "" np_thru_hole circle
			(at 18.999962 -2.350008 90)
			(size 0.254 0.254)
			(drill 1.8542)
			(layers "*.Cu" "*.Mask")
			(clearance 1.1557)
			(thermal_gap 1.1557)
		)
		(pad "H1" thru_hole oval
			(at -21.999956 0 90)
			(size 1.524 2.6162)
			(drill oval 0.8128 1.905)
			(layers "*.Cu" "*.Mask")
			(remove_unused_layers no)
			(net "GND")
			(clearance 0.1524)
			(thermal_gap 0.1524)
		)
		(pad "H2" thru_hole oval
			(at 21.999956 0 90)
			(size 1.524 2.6162)
			(drill oval 0.8128 1.905)
			(layers "*.Cu" "*.Mask")
			(remove_unused_layers no)
			(net "GND")
			(clearance 0.1524)
			(thermal_gap 0.1524)
		)
		(pad "P1" smd rect
			(at -1.89992 -4.249928 90)
			(size 0.6604 2.3876)
			(layers "F.Cu" "F.Mask" "F.Paste")
			(net "Net_70")
		)
		(pad "P2" smd rect
			(at -0.62992 -4.249928 90)
			(size 0.6604 2.3876)
			(layers "F.Cu" "F.Mask" "F.Paste")
			(net "Net_69")
		)
		(pad "P3" smd rect
			(at 0.64008 -4.249928 90)
			(size 0.6604 2.3876)
			(layers "F.Cu" "F.Mask" "F.Paste")
			(net "Net_68")
		)
		(pad "P4" smd rect
			(at 1.91008 -4.249928 90)
			(size 0.6604 2.3876)
			(layers "F.Cu" "F.Mask" "F.Paste")
			(net "GND")
		)
		(pad "P5" smd rect
			(at 3.18008 -4.249928 90)
			(size 0.6604 2.3876)
			(layers "F.Cu" "F.Mask" "F.Paste")
			(net "HDD_PRSNT_NET9")
		)
		(pad "P6" smd rect
			(at 4.45008 -4.249928 90)
			(size 0.6604 2.3876)
			(layers "F.Cu" "F.Mask" "F.Paste")
			(net "GND")
		)
		(pad "P7" smd rect
			(at 5.72008 -4.249928 90)
			(size 0.6604 2.3876)
			(layers "F.Cu" "F.Mask" "F.Paste")
			(net "5V_PRE_9")
		)
		(pad "P8" smd rect
			(at 6.99008 -4.249928 90)
			(size 0.6604 2.3876)
			(layers "F.Cu" "F.Mask" "F.Paste")
			(net "P5V_HDD9")
		)
		(pad "P9" smd rect
			(at 8.26008 -4.249928 90)
			(size 0.6604 2.3876)
			(layers "F.Cu" "F.Mask" "F.Paste")
			(net "P5V_HDD9")
		)
		(pad "P10" smd rect
			(at 9.53008 -4.249928 90)
			(size 0.6604 2.3876)
			(layers "F.Cu" "F.Mask" "F.Paste")
			(net "GND")
		)
		(pad "P11" smd rect
			(at 10.80008 -4.249928 90)
			(size 0.6604 2.3876)
			(layers "F.Cu" "F.Mask" "F.Paste")
			(net "ACT_HDD9")
		)
		(pad "P12" smd rect
			(at 12.07008 -4.249928 90)
			(size 0.6604 2.3876)
			(layers "F.Cu" "F.Mask" "F.Paste")
			(net "GND")
		)
		(pad "P13" smd rect
			(at 13.34008 -4.249928 90)
			(size 0.6604 2.3876)
			(layers "F.Cu" "F.Mask" "F.Paste")
			(net "12V_PRE_9")
		)
		(pad "P14" smd rect
			(at 14.61008 -4.249928 90)
			(size 0.6604 2.3876)
			(layers "F.Cu" "F.Mask" "F.Paste")
			(net "P12V_HDD9")
		)
		(pad "P15" smd rect
			(at 15.88008 -4.249928 90)
			(size 0.6604 2.3876)
			(layers "F.Cu" "F.Mask" "F.Paste")
			(net "P12V_HDD9")
		)
		(pad "S1" smd rect
			(at -15.86992 -4.249928 90)
			(size 0.6604 2.3876)
			(layers "F.Cu" "F.Mask" "F.Paste")
			(net "GND")
		)
		(pad "S2" smd rect
			(at -14.59992 -4.249928 90)
			(size 0.6604 2.3876)
			(layers "F.Cu" "F.Mask" "F.Paste")
			(net "SAS2X28_A_HDD9_TX_+")
		)
		(pad "S3" smd rect
			(at -13.32992 -4.249928 90)
			(size 0.6604 2.3876)
			(layers "F.Cu" "F.Mask" "F.Paste")
			(net "SAS2X28_A_HDD9_TX_-")
		)
		(pad "S4" smd rect
			(at -12.05992 -4.249928 90)
			(size 0.6604 2.3876)
			(layers "F.Cu" "F.Mask" "F.Paste")
			(net "GND")
		)
		(pad "S5" smd rect
			(at -10.78992 -4.249928 90)
			(size 0.6604 2.3876)
			(layers "F.Cu" "F.Mask" "F.Paste")
			(net "SAS2X28_DRIVE_RX_N_A9")
		)
		(pad "S6" smd rect
			(at -9.51992 -4.249928 90)
			(size 0.6604 2.3876)
			(layers "F.Cu" "F.Mask" "F.Paste")
			(net "SAS2X28_DRIVE_RX_P_A9")
		)
		(pad "S7" smd rect
			(at -8.24992 -4.249928 90)
			(size 0.6604 2.3876)
			(layers "F.Cu" "F.Mask" "F.Paste")
			(net "GND")
		)
		(pad "S8" smd rect
			(at -7.480046 -2.100072 90)
			(size 0.508 1.905)
			(layers "F.Cu" "F.Mask" "F.Paste")
			(net "GND")
		)
		(pad "S9" smd rect
			(at -6.679946 -2.100072 90)
			(size 0.508 1.905)
			(layers "F.Cu" "F.Mask" "F.Paste")
			(net "SAS2X28_B_HDD9_TX_+")
		)
		(pad "S10" smd rect
			(at -5.8801 -2.100072 90)
			(size 0.508 1.905)
			(layers "F.Cu" "F.Mask" "F.Paste")
			(net "SAS2X28_B_HDD9_TX_-")
		)
		(pad "S11" smd rect
			(at -5.08 -2.100072 90)
			(size 0.508 1.905)
			(layers "F.Cu" "F.Mask" "F.Paste")
			(net "GND")
		)
		(pad "S12" smd rect
			(at -4.2799 -2.100072 90)
			(size 0.508 1.905)
			(layers "F.Cu" "F.Mask" "F.Paste")
			(net "SAS2X28_DRIVE_RX_N_B9")
		)
		(pad "S13" smd rect
			(at -3.480054 -2.100072 90)
			(size 0.508 1.905)
			(layers "F.Cu" "F.Mask" "F.Paste")
			(net "SAS2X28_DRIVE_RX_P_B9")
		)
		(pad "S14" smd rect
			(at -2.679954 -2.100072 90)
			(size 0.508 1.905)
			(layers "F.Cu" "F.Mask" "F.Paste")
			(net "GND")
		)
		(zone
			(layers "F.Cu" "B.Cu" "In1.Cu" "In2.Cu" "In3.Cu" "In4.Cu" "In5.Cu" "In6.Cu")
			(hatch none 0.5)
			(connect_pads
				(clearance 0)
			)
			(min_thickness 0.25)
			(keepout
				(tracks not_allowed)
				(vias allowed)
				(pads allowed)
				(copperpour not_allowed)
				(footprints allowed)
			)
			(placement
				(enabled no)
				(sheetname "")
			)
			(fill
				(thermal_gap 0.5)
				(thermal_bridge_width 0.5)
				(island_removal_mode 0)
			)
			(polygon
				(pts
					(arc
						(start 41.381934 -86.66988)
						(mid 38.918134 -86.66988)
						(end 41.381934 -86.66988)
					)
				)
			)
		)
		(zone
			(layers "F.Cu" "B.Cu" "In1.Cu" "In2.Cu" "In3.Cu" "In4.Cu" "In5.Cu" "In6.Cu")
			(hatch none 0.5)
			(connect_pads
				(clearance 0)
			)
			(min_thickness 0.25)
			(keepout
				(tracks not_allowed)
				(vias allowed)
				(pads allowed)
				(copperpour not_allowed)
				(footprints allowed)
			)
			(placement
				(enabled no)
				(sheetname "")
			)
			(fill
				(thermal_gap 0.5)
				(thermal_bridge_width 0.5)
				(island_removal_mode 0)
			)
			(polygon
				(pts
					(arc
						(start 41.381934 -48.669956)
						(mid 38.918134 -48.669956)
						(end 41.381934 -48.669956)
					)
				)
			)
		)
	)
	(footprint ""
		(layer "F.Cu")
		(at 74.675746 -15.014702)
		(property "Reference" "C330"
			(at 0 0 0)
			(layer "F.SilkS")
			(hide yes)
			(effects
				(font
					(size 1.27 1.27)
				)
			)
		)
		(property "Value" "SC1U16V3KX-5GP"
			(at 0 -2.8194 0)
			(unlocked yes)
			(layer "F.Fab")
			(hide yes)
			(effects
				(font
					(size 1.016 1.016)
					(thickness 0.1524)
				)
			)
		)
		(property "Device Type" "C603H36"
			(at 0 -4.3434 0)
			(unlocked yes)
			(layer "F.Fab")
			(hide yes)
			(effects
				(font
					(size 1.016 1.016)
					(thickness 0.1524)
				)
			)
		)
		(duplicate_pad_numbers_are_jumpers no)
		(fp_line
			(start 0.508 0)
			(end -0.508 0)
			(stroke
				(width 0.2032)
				(type default)
			)
			(layer "F.SilkS")
		)
		(fp_rect
			(start -0.5842 1.3335)
			(end 0.5842 -1.3335)
			(stroke
				(width 0)
				(type default)
			)
			(fill no)
			(layer "F.CrtYd")
		)
		(fp_rect
			(start -0.5842 1.3335)
			(end 0.5842 -1.3335)
			(stroke
				(width 0)
				(type default)
			)
			(fill no)
			(layer "F.Fab")
		)
		(pad "1" smd custom
			(at 0 -0.762)
			(size 0.2159 0.2159)
			(layers "F.Cu" "F.Mask" "F.Paste")
			(net "P5V_HDD14")
			(options
				(clearance outline)
				(anchor circle)
			)
			(primitives
				(gr_poly
					(pts
						(arc
							(start -0.3302 -0.4318)
							(mid -0.402042 -0.402042)
							(end -0.4318 -0.3302)
						)
						(arc
							(start -0.4318 0.3302)
							(mid -0.402042 0.402042)
							(end -0.3302 0.4318)
						)
						(arc
							(start 0.3302 0.4318)
							(mid 0.402042 0.402042)
							(end 0.4318 0.3302)
						)
						(arc
							(start 0.4318 -0.3302)
							(mid 0.402042 -0.402042)
							(end 0.3302 -0.4318)
						)
					)
					(width 0)
					(fill yes)
				)
			)
		)
		(pad "2" smd custom
			(at 0 0.762)
			(size 0.2159 0.2159)
			(layers "F.Cu" "F.Mask" "F.Paste")
			(net "GND")
			(options
				(clearance outline)
				(anchor circle)
			)
			(primitives
				(gr_poly
					(pts
						(arc
							(start -0.3302 -0.4318)
							(mid -0.402042 -0.402042)
							(end -0.4318 -0.3302)
						)
						(arc
							(start -0.4318 0.3302)
							(mid -0.402042 0.402042)
							(end -0.3302 0.4318)
						)
						(arc
							(start 0.3302 0.4318)
							(mid 0.402042 0.402042)
							(end 0.4318 0.3302)
						)
						(arc
							(start 0.4318 -0.3302)
							(mid 0.402042 -0.402042)
							(end 0.3302 -0.4318)
						)
					)
					(width 0)
					(fill yes)
				)
			)
		)
	)
	(footprint ""
		(layer "F.Cu")
		(at 93.218 -11.303 180)
		(property "Reference" "C393"
			(at 0 0 180)
			(layer "F.SilkS")
			(hide yes)
			(effects
				(font
					(size 1.27 1.27)
				)
			)
		)
		(property "Value" "SCD033U25V2KX-GP"
			(at 1.1811 -2.7051 180)
			(unlocked yes)
			(layer "F.Fab")
			(hide yes)
			(effects
				(font
					(size 1.016 1.016)
					(thickness 0.1524)
				)
			)
		)
		(property "Device Type" "C402H22"
			(at 1.1811 -4.2291 180)
			(unlocked yes)
			(layer "F.Fab")
			(hide yes)
			(effects
				(font
					(size 1.016 1.016)
					(thickness 0.1524)
				)
			)
		)
		(duplicate_pad_numbers_are_jumpers no)
		(fp_rect
			(start -0.4318 0.9525)
			(end 0.4318 -0.9525)
			(stroke
				(width 0)
				(type default)
			)
			(fill no)
			(layer "F.CrtYd")
		)
		(fp_rect
			(start -0.4318 0.9525)
			(end 0.4318 -0.9525)
			(stroke
				(width 0)
				(type default)
			)
			(fill no)
			(layer "F.Fab")
		)
		(pad "1" smd custom
			(at 0 -0.4445 180)
			(size 0.1524 0.1524)
			(layers "F.Cu" "F.Mask" "F.Paste")
			(net "P12V")
			(options
				(clearance outline)
				(anchor circle)
			)
			(primitives
				(gr_poly
					(pts
						(arc
							(start 0.3048 -0.2032)
							(mid 0.275042 -0.275042)
							(end 0.2032 -0.3048)
						)
						(arc
							(start -0.2032 -0.3048)
							(mid -0.275042 -0.275042)
							(end -0.3048 -0.2032)
						)
						(arc
							(start -0.3048 0.2032)
							(mid -0.275042 0.275042)
							(end -0.2032 0.3048)
						)
						(arc
							(start 0.2032 0.3048)
							(mid 0.275042 0.275042)
							(end 0.3048 0.2032)
						)
					)
					(width 0)
					(fill yes)
				)
			)
		)
		(pad "2" smd custom
			(at 0 0.4445 180)
			(size 0.1524 0.1524)
			(layers "F.Cu" "F.Mask" "F.Paste")
			(net "SW_HDD14_N")
			(options
				(clearance outline)
				(anchor circle)
			)
			(primitives
				(gr_poly
					(pts
						(arc
							(start 0.3048 -0.2032)
							(mid 0.275042 -0.275042)
							(end 0.2032 -0.3048)
						)
						(arc
							(start -0.2032 -0.3048)
							(mid -0.275042 -0.275042)
							(end -0.3048 -0.2032)
						)
						(arc
							(start -0.3048 0.2032)
							(mid -0.275042 0.275042)
							(end -0.2032 0.3048)
						)
						(arc
							(start 0.2032 0.3048)
							(mid 0.275042 0.275042)
							(end 0.3048 0.2032)
						)
					)
					(width 0)
					(fill yes)
				)
			)
		)
	)
	(footprint ""
		(layer "F.Cu")
		(at 10.159746 -466.8647 90)
		(property "Reference" "R391"
			(at 0 0 90)
			(layer "F.SilkS")
			(hide yes)
			(effects
				(font
					(size 1.27 1.27)
				)
			)
		)
		(property "Value" "0R2J-2-GP"
			(at 0.064008 -3.993896 90)
			(unlocked yes)
			(layer "F.Fab")
			(hide yes)
			(effects
				(font
					(size 1.016 1.016)
					(thickness 0.1524)
				)
			)
		)
		(property "Device Type" "R402H16"
			(at 0.064008 -5.517896 90)
			(unlocked yes)
			(layer "F.Fab")
			(hide yes)
			(effects
				(font
					(size 1.016 1.016)
					(thickness 0.1524)
				)
			)
		)
		(duplicate_pad_numbers_are_jumpers no)
		(fp_line
			(start 0.508 -0.9398)
			(end -0.508 -0.9398)
			(stroke
				(width 0.1524)
				(type default)
			)
			(layer "F.SilkS")
		)
		(fp_line
			(start -0.508 -0.9398)
			(end -0.508 0.9398)
			(stroke
				(width 0.1524)
				(type default)
			)
			(layer "F.SilkS")
		)
		(fp_rect
			(start -0.508 0.9398)
			(end 0.508 -0.9398)
			(stroke
				(width 0)
				(type default)
			)
			(fill no)
			(layer "F.CrtYd")
		)
		(fp_rect
			(start -0.508 0.9398)
			(end 0.508 -0.9398)
			(stroke
				(width 0)
				(type default)
			)
			(fill no)
			(layer "F.Fab")
		)
		(pad "1" smd custom
			(at 0 -0.4445 90)
			(size 0.1397 0.1397)
			(layers "F.Cu" "F.Mask" "F.Paste")
			(net "EXP_B_PRNST_RX")
			(options
				(clearance outline)
				(anchor circle)
			)
			(primitives
				(gr_poly
					(pts
						(arc
							(start -0.1778 -0.2794)
							(mid -0.249642 -0.249642)
							(end -0.2794 -0.1778)
						)
						(arc
							(start -0.2794 0.1778)
							(mid -0.249642 0.249642)
							(end -0.1778 0.2794)
						)
						(arc
							(start 0.1778 0.2794)
							(mid 0.249642 0.249642)
							(end 0.2794 0.1778)
						)
						(arc
							(start 0.2794 -0.1778)
							(mid 0.249642 -0.249642)
							(end 0.1778 -0.2794)
						)
					)
					(width 0)
					(fill yes)
				)
			)
		)
		(pad "2" smd custom
			(at 0 0.4445 90)
			(size 0.1397 0.1397)
			(layers "F.Cu" "F.Mask" "F.Paste")
			(net "EXP_B_PRNST_TX")
			(options
				(clearance outline)
				(anchor circle)
			)
			(primitives
				(gr_poly
					(pts
						(arc
							(start -0.1778 -0.2794)
							(mid -0.249642 -0.249642)
							(end -0.2794 -0.1778)
						)
						(arc
							(start -0.2794 0.1778)
							(mid -0.249642 0.249642)
							(end -0.1778 0.2794)
						)
						(arc
							(start 0.1778 0.2794)
							(mid 0.249642 0.249642)
							(end 0.2794 0.1778)
						)
						(arc
							(start 0.2794 -0.1778)
							(mid 0.249642 -0.249642)
							(end 0.1778 -0.2794)
						)
					)
					(width 0)
					(fill yes)
				)
			)
		)
	)
	(footprint ""
		(layer "F.Cu")
		(at 9.1186 -465.5058)
		(property "Reference" "TP18"
			(at 0 0 0)
			(layer "F.SilkS")
			(hide yes)
			(effects
				(font
					(size 1.27 1.27)
				)
			)
		)
		(property "Value" "TPAD32-GP"
			(at 0 -3.166364 0)
			(unlocked yes)
			(layer "F.Fab")
			(hide yes)
			(effects
				(font
					(size 1.016 1.016)
					(thickness 0.1524)
				)
			)
		)
		(property "Device Type" "TPAD32"
			(at 0 -4.690618 0)
			(unlocked yes)
			(layer "F.Fab")
			(hide yes)
			(effects
				(font
					(size 1.016 1.016)
					(thickness 0.1524)
				)
			)
		)
		(duplicate_pad_numbers_are_jumpers no)
		(fp_poly
			(pts
				(arc
					(start 0.4064 0)
					(mid -0.4064 0)
					(end 0.4064 0)
				)
			)
			(stroke
				(width 0)
				(type default)
			)
			(fill no)
			(layer "F.CrtYd")
		)
		(fp_poly
			(pts
				(arc
					(start 0.7112 0)
					(mid -0.7112 0)
					(end 0.7112 0)
				)
			)
			(stroke
				(width 0)
				(type default)
			)
			(fill no)
			(layer "F.Fab")
		)
		(pad "1" smd circle
			(at 0 0)
			(size 0.8128 0.8128)
			(layers "F.Cu" "F.Mask" "F.Paste")
			(net "SAS_EXP_A_PWR15")
		)
	)
	(footprint ""
		(layer "F.Cu")
		(at 57.276746 -381.2667)
		(property "Reference" "R189"
			(at 0 0 0)
			(layer "F.SilkS")
			(hide yes)
			(effects
				(font
					(size 1.27 1.27)
				)
			)
		)
		(property "Value" "4K7R2J-2-GP"
			(at 0.064008 -3.993896 0)
			(unlocked yes)
			(layer "F.Fab")
			(hide yes)
			(effects
				(font
					(size 1.016 1.016)
					(thickness 0.1524)
				)
			)
		)
		(property "Device Type" "R402H16"
			(at 0.064008 -5.517896 0)
			(unlocked yes)
			(layer "F.Fab")
			(hide yes)
			(effects
				(font
					(size 1.016 1.016)
					(thickness 0.1524)
				)
			)
		)
		(duplicate_pad_numbers_are_jumpers no)
		(fp_line
			(start -0.508 -0.9398)
			(end -0.508 0.9398)
			(stroke
				(width 0.1524)
				(type default)
			)
			(layer "F.SilkS")
		)
		(fp_line
			(start 0.508 -0.9398)
			(end -0.508 -0.9398)
			(stroke
				(width 0.1524)
				(type default)
			)
			(layer "F.SilkS")
		)
		(fp_rect
			(start -0.508 0.9398)
			(end 0.508 -0.9398)
			(stroke
				(width 0)
				(type default)
			)
			(fill no)
			(layer "F.CrtYd")
		)
		(fp_rect
			(start -0.508 0.9398)
			(end 0.508 -0.9398)
			(stroke
				(width 0)
				(type default)
			)
			(fill no)
			(layer "F.Fab")
		)
		(pad "1" smd custom
			(at 0 -0.4445)
			(size 0.1397 0.1397)
			(layers "F.Cu" "F.Mask" "F.Paste")
			(net "P3V3")
			(options
				(clearance outline)
				(anchor circle)
			)
			(primitives
				(gr_poly
					(pts
						(arc
							(start -0.1778 -0.2794)
							(mid -0.249642 -0.249642)
							(end -0.2794 -0.1778)
						)
						(arc
							(start -0.2794 0.1778)
							(mid -0.249642 0.249642)
							(end -0.1778 0.2794)
						)
						(arc
							(start 0.1778 0.2794)
							(mid 0.249642 0.249642)
							(end 0.2794 0.1778)
						)
						(arc
							(start 0.2794 -0.1778)
							(mid 0.249642 -0.249642)
							(end 0.1778 -0.2794)
						)
					)
					(width 0)
					(fill yes)
				)
			)
		)
		(pad "2" smd custom
			(at 0 0.4445)
			(size 0.1397 0.1397)
			(layers "F.Cu" "F.Mask" "F.Paste")
			(net "HDD_PRSNT_NET6")
			(options
				(clearance outline)
				(anchor circle)
			)
			(primitives
				(gr_poly
					(pts
						(arc
							(start -0.1778 -0.2794)
							(mid -0.249642 -0.249642)
							(end -0.2794 -0.1778)
						)
						(arc
							(start -0.2794 0.1778)
							(mid -0.249642 0.249642)
							(end -0.1778 0.2794)
						)
						(arc
							(start 0.1778 0.2794)
							(mid 0.249642 0.249642)
							(end 0.2794 0.1778)
						)
						(arc
							(start 0.2794 -0.1778)
							(mid 0.249642 -0.249642)
							(end 0.1778 -0.2794)
						)
					)
					(width 0)
					(fill yes)
				)
			)
		)
	)
	(footprint ""
		(layer "F.Cu")
		(at 44.322746 -419.446202)
		(property "Reference" "R252"
			(at 0 0 0)
			(layer "F.SilkS")
			(hide yes)
			(effects
				(font
					(size 1.27 1.27)
				)
			)
		)
		(property "Value" "0R2J-2-GP"
			(at 0.064008 -3.993896 0)
			(unlocked yes)
			(layer "F.Fab")
			(hide yes)
			(effects
				(font
					(size 1.016 1.016)
					(thickness 0.1524)
				)
			)
		)
		(property "Device Type" "R402H16"
			(at 0.064008 -5.517896 0)
			(unlocked yes)
			(layer "F.Fab")
			(hide yes)
			(effects
				(font
					(size 1.016 1.016)
					(thickness 0.1524)
				)
			)
		)
		(duplicate_pad_numbers_are_jumpers no)
		(fp_line
			(start -0.508 -0.9398)
			(end -0.508 0.9398)
			(stroke
				(width 0.1524)
				(type default)
			)
			(layer "F.SilkS")
		)
		(fp_line
			(start 0.508 -0.9398)
			(end -0.508 -0.9398)
			(stroke
				(width 0.1524)
				(type default)
			)
			(layer "F.SilkS")
		)
		(fp_rect
			(start -0.508 0.9398)
			(end 0.508 -0.9398)
			(stroke
				(width 0)
				(type default)
			)
			(fill no)
			(layer "F.CrtYd")
		)
		(fp_rect
			(start -0.508 0.9398)
			(end 0.508 -0.9398)
			(stroke
				(width 0)
				(type default)
			)
			(fill no)
			(layer "F.Fab")
		)
		(pad "1" smd custom
			(at 0 -0.4445)
			(size 0.1397 0.1397)
			(layers "F.Cu" "F.Mask" "F.Paste")
			(net "SW_PWR_HDD10")
			(options
				(clearance outline)
				(anchor circle)
			)
			(primitives
				(gr_poly
					(pts
						(arc
							(start -0.1778 -0.2794)
							(mid -0.249642 -0.249642)
							(end -0.2794 -0.1778)
						)
						(arc
							(start -0.2794 0.1778)
							(mid -0.249642 0.249642)
							(end -0.1778 0.2794)
						)
						(arc
							(start 0.1778 0.2794)
							(mid 0.249642 0.249642)
							(end 0.2794 0.1778)
						)
						(arc
							(start 0.2794 -0.1778)
							(mid 0.249642 -0.249642)
							(end 0.1778 -0.2794)
						)
					)
					(width 0)
					(fill yes)
				)
			)
		)
		(pad "2" smd custom
			(at 0 0.4445)
			(size 0.1397 0.1397)
			(layers "F.Cu" "F.Mask" "F.Paste")
			(net "SW_PWR_R_HDD10")
			(options
				(clearance outline)
				(anchor circle)
			)
			(primitives
				(gr_poly
					(pts
						(arc
							(start -0.1778 -0.2794)
							(mid -0.249642 -0.249642)
							(end -0.2794 -0.1778)
						)
						(arc
							(start -0.2794 0.1778)
							(mid -0.249642 0.249642)
							(end -0.1778 0.2794)
						)
						(arc
							(start 0.1778 0.2794)
							(mid 0.249642 0.249642)
							(end 0.2794 0.1778)
						)
						(arc
							(start 0.2794 -0.1778)
							(mid 0.249642 -0.249642)
							(end 0.1778 -0.2794)
						)
					)
					(width 0)
					(fill yes)
				)
			)
		)
	)
	(footprint ""
		(layer "F.Cu")
		(at 93.091 -21.463)
		(property "Reference" "C378"
			(at 0 0 0)
			(layer "F.SilkS")
			(hide yes)
			(effects
				(font
					(size 1.27 1.27)
				)
			)
		)
		(property "Value" "SCD033U25V2KX-GP"
			(at 1.1811 -2.7051 0)
			(unlocked yes)
			(layer "F.Fab")
			(hide yes)
			(effects
				(font
					(size 1.016 1.016)
					(thickness 0.1524)
				)
			)
		)
		(property "Device Type" "C402H22"
			(at 1.1811 -4.2291 0)
			(unlocked yes)
			(layer "F.Fab")
			(hide yes)
			(effects
				(font
					(size 1.016 1.016)
					(thickness 0.1524)
				)
			)
		)
		(duplicate_pad_numbers_are_jumpers no)
		(fp_rect
			(start -0.4318 0.9525)
			(end 0.4318 -0.9525)
			(stroke
				(width 0)
				(type default)
			)
			(fill no)
			(layer "F.CrtYd")
		)
		(fp_rect
			(start -0.4318 0.9525)
			(end 0.4318 -0.9525)
			(stroke
				(width 0)
				(type default)
			)
			(fill no)
			(layer "F.Fab")
		)
		(pad "1" smd custom
			(at 0 -0.4445)
			(size 0.1524 0.1524)
			(layers "F.Cu" "F.Mask" "F.Paste")
			(net "SW_HDD14_P")
			(options
				(clearance outline)
				(anchor circle)
			)
			(primitives
				(gr_poly
					(pts
						(arc
							(start 0.3048 -0.2032)
							(mid 0.275042 -0.275042)
							(end 0.2032 -0.3048)
						)
						(arc
							(start -0.2032 -0.3048)
							(mid -0.275042 -0.275042)
							(end -0.3048 -0.2032)
						)
						(arc
							(start -0.3048 0.2032)
							(mid -0.275042 0.275042)
							(end -0.2032 0.3048)
						)
						(arc
							(start 0.2032 0.3048)
							(mid 0.275042 0.275042)
							(end 0.3048 0.2032)
						)
					)
					(width 0)
					(fill yes)
				)
			)
		)
		(pad "2" smd custom
			(at 0 0.4445)
			(size 0.1524 0.1524)
			(layers "F.Cu" "F.Mask" "F.Paste")
			(net "GND")
			(options
				(clearance outline)
				(anchor circle)
			)
			(primitives
				(gr_poly
					(pts
						(arc
							(start 0.3048 -0.2032)
							(mid 0.275042 -0.275042)
							(end 0.2032 -0.3048)
						)
						(arc
							(start -0.2032 -0.3048)
							(mid -0.275042 -0.275042)
							(end -0.3048 -0.2032)
						)
						(arc
							(start -0.3048 0.2032)
							(mid -0.275042 0.275042)
							(end -0.2032 0.3048)
						)
						(arc
							(start 0.2032 0.3048)
							(mid 0.275042 0.275042)
							(end 0.3048 0.2032)
						)
					)
					(width 0)
					(fill yes)
				)
			)
		)
	)
	(footprint ""
		(layer "F.Cu")
		(at 233.806746 -27.9527)
		(property "Reference" "PR2"
			(at 0 0 0)
			(layer "F.SilkS")
			(hide yes)
			(effects
				(font
					(size 1.27 1.27)
				)
			)
		)
		(property "Value" "10KR2F-2-GP"
			(at 0.064008 -3.993896 0)
			(unlocked yes)
			(layer "F.Fab")
			(hide yes)
			(effects
				(font
					(size 1.016 1.016)
					(thickness 0.1524)
				)
			)
		)
		(property "Device Type" "R402H16"
			(at 0.064008 -5.517896 0)
			(unlocked yes)
			(layer "F.Fab")
			(hide yes)
			(effects
				(font
					(size 1.016 1.016)
					(thickness 0.1524)
				)
			)
		)
		(duplicate_pad_numbers_are_jumpers no)
		(fp_line
			(start -0.508 -0.9398)
			(end -0.508 0.9398)
			(stroke
				(width 0.1524)
				(type default)
			)
			(layer "F.SilkS")
		)
		(fp_line
			(start 0.508 -0.9398)
			(end -0.508 -0.9398)
			(stroke
				(width 0.1524)
				(type default)
			)
			(layer "F.SilkS")
		)
		(fp_rect
			(start -0.508 0.9398)
			(end 0.508 -0.9398)
			(stroke
				(width 0)
				(type default)
			)
			(fill no)
			(layer "F.CrtYd")
		)
		(fp_rect
			(start -0.508 0.9398)
			(end 0.508 -0.9398)
			(stroke
				(width 0)
				(type default)
			)
			(fill no)
			(layer "F.Fab")
		)
		(pad "1" smd custom
			(at 0 -0.4445)
			(size 0.1397 0.1397)
			(layers "F.Cu" "F.Mask" "F.Paste")
			(net "P5VA_12VIN")
			(options
				(clearance outline)
				(anchor circle)
			)
			(primitives
				(gr_poly
					(pts
						(arc
							(start -0.1778 -0.2794)
							(mid -0.249642 -0.249642)
							(end -0.2794 -0.1778)
						)
						(arc
							(start -0.2794 0.1778)
							(mid -0.249642 0.249642)
							(end -0.1778 0.2794)
						)
						(arc
							(start 0.1778 0.2794)
							(mid 0.249642 0.249642)
							(end 0.2794 0.1778)
						)
						(arc
							(start 0.2794 -0.1778)
							(mid 0.249642 -0.249642)
							(end 0.1778 -0.2794)
						)
					)
					(width 0)
					(fill yes)
				)
			)
		)
		(pad "2" smd custom
			(at 0 0.4445)
			(size 0.1397 0.1397)
			(layers "F.Cu" "F.Mask" "F.Paste")
			(net "P5VA_EN")
			(options
				(clearance outline)
				(anchor circle)
			)
			(primitives
				(gr_poly
					(pts
						(arc
							(start -0.1778 -0.2794)
							(mid -0.249642 -0.249642)
							(end -0.2794 -0.1778)
						)
						(arc
							(start -0.2794 0.1778)
							(mid -0.249642 0.249642)
							(end -0.1778 0.2794)
						)
						(arc
							(start 0.1778 0.2794)
							(mid 0.249642 0.249642)
							(end 0.2794 0.1778)
						)
						(arc
							(start 0.2794 -0.1778)
							(mid 0.249642 -0.249642)
							(end 0.1778 -0.2794)
						)
					)
					(width 0)
					(fill yes)
				)
			)
		)
	)
	(footprint ""
		(layer "F.Cu")
		(at 6.248146 -268.2367 -90)
		(property "Reference" "Q46"
			(at 0 0 270)
			(layer "F.SilkS")
			(hide yes)
			(effects
				(font
					(size 1.27 1.27)
				)
			)
		)
		(property "Value" "PMBS3904-1-GP"
			(at 0 -9.0932 270)
			(unlocked yes)
			(layer "F.Fab")
			(hide yes)
			(effects
				(font
					(size 1.016 1.016)
					(thickness 0.1524)
				)
			)
		)
		(property "Device Type" "SOT-23-10H44"
			(at 0 -10.6172 270)
			(unlocked yes)
			(layer "F.Fab")
			(hide yes)
			(effects
				(font
					(size 1.016 1.016)
					(thickness 0.1524)
				)
			)
		)
		(duplicate_pad_numbers_are_jumpers no)
		(fp_line
			(start -1.279144 2.15265)
			(end -0.701294 2.15265)
			(stroke
				(width 0.0127)
				(type default)
			)
			(layer "F.SilkS")
		)
		(fp_line
			(start -0.71628 2.15265)
			(end -1.26492 2.15265)
			(stroke
				(width 0.0127)
				(type default)
			)
			(layer "F.SilkS")
		)
		(fp_line
			(start -1.279398 2.152142)
			(end -0.9906 1.86309)
			(stroke
				(width 0.0127)
				(type default)
			)
			(layer "F.SilkS")
		)
		(fp_line
			(start -0.719074 2.145538)
			(end -1.265936 2.14122)
			(stroke
				(width 0.0127)
				(type default)
			)
			(layer "F.SilkS")
		)
		(fp_line
			(start -1.260856 2.1336)
			(end -0.720344 2.1336)
			(stroke
				(width 0.0127)
				(type default)
			)
			(layer "F.SilkS")
		)
		(fp_line
			(start -1.251458 2.124202)
			(end -0.729996 2.124202)
			(stroke
				(width 0.0127)
				(type default)
			)
			(layer "F.SilkS")
		)
		(fp_line
			(start -1.241806 2.11455)
			(end -0.739394 2.11455)
			(stroke
				(width 0.0127)
				(type default)
			)
			(layer "F.SilkS")
		)
		(fp_line
			(start -1.232408 2.105152)
			(end -0.749046 2.105152)
			(stroke
				(width 0.0127)
				(type default)
			)
			(layer "F.SilkS")
		)
		(fp_line
			(start -1.222756 2.0955)
			(end -0.758444 2.0955)
			(stroke
				(width 0.0127)
				(type default)
			)
			(layer "F.SilkS")
		)
		(fp_line
			(start -1.213358 2.086102)
			(end -0.768096 2.086102)
			(stroke
				(width 0.0127)
				(type default)
			)
			(layer "F.SilkS")
		)
		(fp_line
			(start -1.203706 2.07645)
			(end -0.777494 2.07645)
			(stroke
				(width 0.0127)
				(type default)
			)
			(layer "F.SilkS")
		)
		(fp_line
			(start -1.194308 2.067052)
			(end -0.787146 2.067052)
			(stroke
				(width 0.0127)
				(type default)
			)
			(layer "F.SilkS")
		)
		(fp_line
			(start -1.184656 2.0574)
			(end -0.796544 2.0574)
			(stroke
				(width 0.0127)
				(type default)
			)
			(layer "F.SilkS")
		)
		(fp_line
			(start -1.175258 2.048002)
			(end -0.806196 2.048002)
			(stroke
				(width 0.0127)
				(type default)
			)
			(layer "F.SilkS")
		)
		(fp_line
			(start -1.165606 2.03835)
			(end -0.815594 2.03835)
			(stroke
				(width 0.0127)
				(type default)
			)
			(layer "F.SilkS")
		)
		(fp_line
			(start -1.156208 2.028952)
			(end -0.825246 2.028952)
			(stroke
				(width 0.0127)
				(type default)
			)
			(layer "F.SilkS")
		)
		(fp_line
			(start -1.146556 2.0193)
			(end -0.834644 2.0193)
			(stroke
				(width 0.0127)
				(type default)
			)
			(layer "F.SilkS")
		)
		(fp_line
			(start -1.137158 2.009902)
			(end -0.844296 2.009902)
			(stroke
				(width 0.0127)
				(type default)
			)
			(layer "F.SilkS")
		)
		(fp_line
			(start -1.127506 2.00025)
			(end -0.853694 2.00025)
			(stroke
				(width 0.0127)
				(type default)
			)
			(layer "F.SilkS")
		)
		(fp_line
			(start -1.118108 1.990852)
			(end -0.863346 1.990852)
			(stroke
				(width 0.0127)
				(type default)
			)
			(layer "F.SilkS")
		)
		(fp_line
			(start -1.108456 1.9812)
			(end -0.872744 1.9812)
			(stroke
				(width 0.0127)
				(type default)
			)
			(layer "F.SilkS")
		)
		(fp_line
			(start -1.099058 1.971802)
			(end -0.882396 1.971802)
			(stroke
				(width 0.0127)
				(type default)
			)
			(layer "F.SilkS")
		)
		(fp_line
			(start -1.089406 1.96215)
			(end -0.891794 1.96215)
			(stroke
				(width 0.0127)
				(type default)
			)
			(layer "F.SilkS")
		)
		(fp_line
			(start -1.080008 1.952752)
			(end -0.901446 1.952752)
			(stroke
				(width 0.0127)
				(type default)
			)
			(layer "F.SilkS")
		)
		(fp_line
			(start -1.070356 1.9431)
			(end -0.910844 1.9431)
			(stroke
				(width 0.0127)
				(type default)
			)
			(layer "F.SilkS")
		)
		(fp_line
			(start -1.060958 1.933702)
			(end -0.920496 1.933702)
			(stroke
				(width 0.0127)
				(type default)
			)
			(layer "F.SilkS")
		)
		(fp_line
			(start -1.051306 1.92405)
			(end -0.929894 1.92405)
			(stroke
				(width 0.0127)
				(type default)
			)
			(layer "F.SilkS")
		)
		(fp_line
			(start -1.041908 1.914652)
			(end -0.939546 1.914652)
			(stroke
				(width 0.0127)
				(type default)
			)
			(layer "F.SilkS")
		)
		(fp_line
			(start -1.032256 1.905)
			(end -0.948944 1.905)
			(stroke
				(width 0.0127)
				(type default)
			)
			(layer "F.SilkS")
		)
		(fp_line
			(start -1.022858 1.895602)
			(end -0.958596 1.895602)
			(stroke
				(width 0.0127)
				(type default)
			)
			(layer "F.SilkS")
		)
		(fp_line
			(start -1.013206 1.88595)
			(end -0.967994 1.88595)
			(stroke
				(width 0.0127)
				(type default)
			)
			(layer "F.SilkS")
		)
		(fp_line
			(start -1.7526 1.8796)
			(end -1.7526 0.9906)
			(stroke
				(width 0.3302)
				(type default)
			)
			(layer "F.SilkS")
		)
		(fp_line
			(start -0.635 1.8796)
			(end -1.7526 1.8796)
			(stroke
				(width 0.3302)
				(type default)
			)
			(layer "F.SilkS")
		)
		(fp_line
			(start -1.003808 1.876552)
			(end -0.977646 1.876552)
			(stroke
				(width 0.0127)
				(type default)
			)
			(layer "F.SilkS")
		)
		(fp_line
			(start -0.994156 1.8669)
			(end -0.987044 1.8669)
			(stroke
				(width 0.0127)
				(type default)
			)
			(layer "F.SilkS")
		)
		(fp_line
			(start -0.9906 1.86309)
			(end -0.701294 2.15265)
			(stroke
				(width 0.0127)
				(type default)
			)
			(layer "F.SilkS")
		)
		(fp_line
			(start -1.651 1.778)
			(end 1.651 1.778)
			(stroke
				(width 0.1524)
				(type default)
			)
			(layer "F.SilkS")
		)
		(fp_line
			(start 1.651 1.778)
			(end 1.651 -1.778)
			(stroke
				(width 0.1524)
				(type default)
			)
			(layer "F.SilkS")
		)
		(fp_line
			(start -1.651 -1.778)
			(end -1.651 1.778)
			(stroke
				(width 0.1524)
				(type default)
			)
			(layer "F.SilkS")
		)
		(fp_line
			(start 1.651 -1.778)
			(end -1.651 -1.778)
			(stroke
				(width 0.1524)
				(type default)
			)
			(layer "F.SilkS")
		)
		(fp_poly
			(pts
				(xy -1.285748 2.159) (xy -1.285748 1.8796) (xy -1.778 1.8796) (xy -1.778 -1.8796) (xy 1.778 -1.8796)
				(xy 1.778 1.8796) (xy -0.694944 1.8796) (xy -0.694944 2.159)
			)
			(stroke
				(width 0)
				(type default)
			)
			(fill no)
			(layer "F.CrtYd")
		)
		(fp_poly
			(pts
				(xy -1.285748 2.159) (xy -1.285748 1.8796) (xy -1.778 1.8796) (xy -1.778 -1.8796) (xy 1.778 -1.8796)
				(xy 1.778 1.8796) (xy -0.694944 1.8796) (xy -0.694944 2.159)
			)
			(stroke
				(width 0)
				(type default)
			)
			(fill no)
			(layer "F.Fab")
		)
		(pad "1" smd rect
			(at -0.98425 0.9525 270)
			(size 0.762 1.143)
			(layers "F.Cu" "F.Mask" "F.Paste")
			(net "FLT_HDD12_B")
		)
		(pad "2" smd rect
			(at 0.98425 0.9525 270)
			(size 0.762 1.143)
			(layers "F.Cu" "F.Mask" "F.Paste")
			(net "GND")
		)
		(pad "3" smd rect
			(at 0 -0.9525 270)
			(size 0.762 1.143)
			(layers "F.Cu" "F.Mask" "F.Paste")
			(net "DRIVE_ACT_12")
		)
	)
	(footprint ""
		(layer "F.Cu")
		(at 193.167 -396.494 90)
		(property "Reference" "R479"
			(at 0 0 90)
			(layer "F.SilkS")
			(hide yes)
			(effects
				(font
					(size 1.27 1.27)
				)
			)
		)
		(property "Value" "200KR2F-L-GP"
			(at 0.064008 -3.993896 90)
			(unlocked yes)
			(layer "F.Fab")
			(hide yes)
			(effects
				(font
					(size 1.016 1.016)
					(thickness 0.1524)
				)
			)
		)
		(property "Device Type" "R402H16"
			(at 0.064008 -5.517896 90)
			(unlocked yes)
			(layer "F.Fab")
			(hide yes)
			(effects
				(font
					(size 1.016 1.016)
					(thickness 0.1524)
				)
			)
		)
		(duplicate_pad_numbers_are_jumpers no)
		(fp_line
			(start 0.508 -0.9398)
			(end -0.508 -0.9398)
			(stroke
				(width 0.1524)
				(type default)
			)
			(layer "F.SilkS")
		)
		(fp_line
			(start -0.508 -0.9398)
			(end -0.508 0.9398)
			(stroke
				(width 0.1524)
				(type default)
			)
			(layer "F.SilkS")
		)
		(fp_rect
			(start -0.508 0.9398)
			(end 0.508 -0.9398)
			(stroke
				(width 0)
				(type default)
			)
			(fill no)
			(layer "F.CrtYd")
		)
		(fp_rect
			(start -0.508 0.9398)
			(end 0.508 -0.9398)
			(stroke
				(width 0)
				(type default)
			)
			(fill no)
			(layer "F.Fab")
		)
		(pad "1" smd custom
			(at 0 -0.4445 90)
			(size 0.1397 0.1397)
			(layers "F.Cu" "F.Mask" "F.Paste")
			(net "SW_HDD1_R")
			(options
				(clearance outline)
				(anchor circle)
			)
			(primitives
				(gr_poly
					(pts
						(arc
							(start -0.1778 -0.2794)
							(mid -0.249642 -0.249642)
							(end -0.2794 -0.1778)
						)
						(arc
							(start -0.2794 0.1778)
							(mid -0.249642 0.249642)
							(end -0.1778 0.2794)
						)
						(arc
							(start 0.1778 0.2794)
							(mid 0.249642 0.249642)
							(end 0.2794 0.1778)
						)
						(arc
							(start 0.2794 -0.1778)
							(mid 0.249642 -0.249642)
							(end 0.1778 -0.2794)
						)
					)
					(width 0)
					(fill yes)
				)
			)
		)
		(pad "2" smd custom
			(at 0 0.4445 90)
			(size 0.1397 0.1397)
			(layers "F.Cu" "F.Mask" "F.Paste")
			(net "SW_HDD1_N")
			(options
				(clearance outline)
				(anchor circle)
			)
			(primitives
				(gr_poly
					(pts
						(arc
							(start -0.1778 -0.2794)
							(mid -0.249642 -0.249642)
							(end -0.2794 -0.1778)
						)
						(arc
							(start -0.2794 0.1778)
							(mid -0.249642 0.249642)
							(end -0.1778 0.2794)
						)
						(arc
							(start 0.1778 0.2794)
							(mid 0.249642 0.249642)
							(end 0.2794 0.1778)
						)
						(arc
							(start 0.2794 -0.1778)
							(mid 0.249642 -0.249642)
							(end 0.1778 -0.2794)
						)
					)
					(width 0)
					(fill yes)
				)
			)
		)
	)
	(footprint ""
		(layer "F.Cu")
		(at 84.200492 -84.610956 -90)
		(property "Reference" "R459"
			(at 0 0 270)
			(layer "F.SilkS")
			(hide yes)
			(effects
				(font
					(size 1.27 1.27)
				)
			)
		)
		(property "Value" "4K7R2J-2-GP"
			(at 0.064008 -3.993896 270)
			(unlocked yes)
			(layer "F.Fab")
			(hide yes)
			(effects
				(font
					(size 1.016 1.016)
					(thickness 0.1524)
				)
			)
		)
		(property "Device Type" "R402H16"
			(at 0.064008 -5.517896 270)
			(unlocked yes)
			(layer "F.Fab")
			(hide yes)
			(effects
				(font
					(size 1.016 1.016)
					(thickness 0.1524)
				)
			)
		)
		(duplicate_pad_numbers_are_jumpers no)
		(fp_line
			(start -0.508 -0.9398)
			(end -0.508 0.9398)
			(stroke
				(width 0.1524)
				(type default)
			)
			(layer "F.SilkS")
		)
		(fp_line
			(start 0.508 -0.9398)
			(end -0.508 -0.9398)
			(stroke
				(width 0.1524)
				(type default)
			)
			(layer "F.SilkS")
		)
		(fp_rect
			(start -0.508 0.9398)
			(end 0.508 -0.9398)
			(stroke
				(width 0)
				(type default)
			)
			(fill no)
			(layer "F.CrtYd")
		)
		(fp_rect
			(start -0.508 0.9398)
			(end 0.508 -0.9398)
			(stroke
				(width 0)
				(type default)
			)
			(fill no)
			(layer "F.Fab")
		)
		(pad "1" smd custom
			(at 0 -0.4445 270)
			(size 0.1397 0.1397)
			(layers "F.Cu" "F.Mask" "F.Paste")
			(net "P3V3")
			(options
				(clearance outline)
				(anchor circle)
			)
			(primitives
				(gr_poly
					(pts
						(arc
							(start -0.1778 -0.2794)
							(mid -0.249642 -0.249642)
							(end -0.2794 -0.1778)
						)
						(arc
							(start -0.2794 0.1778)
							(mid -0.249642 0.249642)
							(end -0.1778 0.2794)
						)
						(arc
							(start 0.1778 0.2794)
							(mid 0.249642 0.249642)
							(end 0.2794 0.1778)
						)
						(arc
							(start 0.2794 -0.1778)
							(mid 0.249642 -0.249642)
							(end 0.1778 -0.2794)
						)
					)
					(width 0)
					(fill yes)
				)
			)
		)
		(pad "2" smd custom
			(at 0 0.4445 270)
			(size 0.1397 0.1397)
			(layers "F.Cu" "F.Mask" "F.Paste")
			(net "SAS_EXP_B_PWR9")
			(options
				(clearance outline)
				(anchor circle)
			)
			(primitives
				(gr_poly
					(pts
						(arc
							(start -0.1778 -0.2794)
							(mid -0.249642 -0.249642)
							(end -0.2794 -0.1778)
						)
						(arc
							(start -0.2794 0.1778)
							(mid -0.249642 0.249642)
							(end -0.1778 0.2794)
						)
						(arc
							(start 0.1778 0.2794)
							(mid 0.249642 0.249642)
							(end 0.2794 0.1778)
						)
						(arc
							(start 0.2794 -0.1778)
							(mid 0.249642 -0.249642)
							(end 0.1778 -0.2794)
						)
					)
					(width 0)
					(fill yes)
				)
			)
		)
	)
	(footprint ""
		(layer "F.Cu")
		(at 33.019746 -57.9247 -90)
		(property "Reference" "C247"
			(at 0 0 270)
			(layer "F.SilkS")
			(hide yes)
			(effects
				(font
					(size 1.27 1.27)
				)
			)
		)
		(property "Value" "SCD01U50V2KX-1GP"
			(at 1.1811 -2.7051 270)
			(unlocked yes)
			(layer "F.Fab")
			(hide yes)
			(effects
				(font
					(size 1.016 1.016)
					(thickness 0.1524)
				)
			)
		)
		(property "Device Type" "C402H22"
			(at 1.1811 -4.2291 270)
			(unlocked yes)
			(layer "F.Fab")
			(hide yes)
			(effects
				(font
					(size 1.016 1.016)
					(thickness 0.1524)
				)
			)
		)
		(duplicate_pad_numbers_are_jumpers no)
		(fp_rect
			(start -0.4318 0.9525)
			(end 0.4318 -0.9525)
			(stroke
				(width 0)
				(type default)
			)
			(fill no)
			(layer "F.CrtYd")
		)
		(fp_rect
			(start -0.4318 0.9525)
			(end 0.4318 -0.9525)
			(stroke
				(width 0)
				(type default)
			)
			(fill no)
			(layer "F.Fab")
		)
		(pad "1" smd custom
			(at 0 -0.4445 270)
			(size 0.1524 0.1524)
			(layers "F.Cu" "F.Mask" "F.Paste")
			(net "SAS2X28_DRIVE_RX_P_A9")
			(options
				(clearance outline)
				(anchor circle)
			)
			(primitives
				(gr_poly
					(pts
						(arc
							(start 0.3048 -0.2032)
							(mid 0.275042 -0.275042)
							(end 0.2032 -0.3048)
						)
						(arc
							(start -0.2032 -0.3048)
							(mid -0.275042 -0.275042)
							(end -0.3048 -0.2032)
						)
						(arc
							(start -0.3048 0.2032)
							(mid -0.275042 0.275042)
							(end -0.2032 0.3048)
						)
						(arc
							(start 0.2032 0.3048)
							(mid 0.275042 0.275042)
							(end 0.3048 0.2032)
						)
					)
					(width 0)
					(fill yes)
				)
			)
		)
		(pad "2" smd custom
			(at 0 0.4445 270)
			(size 0.1524 0.1524)
			(layers "F.Cu" "F.Mask" "F.Paste")
			(net "SAS2X28_A_HDD9_RX_+")
			(options
				(clearance outline)
				(anchor circle)
			)
			(primitives
				(gr_poly
					(pts
						(arc
							(start 0.3048 -0.2032)
							(mid 0.275042 -0.275042)
							(end 0.2032 -0.3048)
						)
						(arc
							(start -0.2032 -0.3048)
							(mid -0.275042 -0.275042)
							(end -0.3048 -0.2032)
						)
						(arc
							(start -0.3048 0.2032)
							(mid -0.275042 0.275042)
							(end -0.2032 0.3048)
						)
						(arc
							(start 0.2032 0.3048)
							(mid 0.275042 0.275042)
							(end 0.3048 0.2032)
						)
					)
					(width 0)
					(fill yes)
				)
			)
		)
	)
	(footprint ""
		(layer "F.Cu")
		(at 57.912 -175.133 90)
		(property "Reference" "R393"
			(at 0 0 90)
			(layer "F.SilkS")
			(hide yes)
			(effects
				(font
					(size 1.27 1.27)
				)
			)
		)
		(property "Value" "0R2J-2-GP"
			(at 0.064008 -3.993896 90)
			(unlocked yes)
			(layer "F.Fab")
			(hide yes)
			(effects
				(font
					(size 1.016 1.016)
					(thickness 0.1524)
				)
			)
		)
		(property "Device Type" "R402H16"
			(at 0.064008 -5.517896 90)
			(unlocked yes)
			(layer "F.Fab")
			(hide yes)
			(effects
				(font
					(size 1.016 1.016)
					(thickness 0.1524)
				)
			)
		)
		(duplicate_pad_numbers_are_jumpers no)
		(fp_line
			(start 0.508 -0.9398)
			(end -0.508 -0.9398)
			(stroke
				(width 0.1524)
				(type default)
			)
			(layer "F.SilkS")
		)
		(fp_line
			(start -0.508 -0.9398)
			(end -0.508 0.9398)
			(stroke
				(width 0.1524)
				(type default)
			)
			(layer "F.SilkS")
		)
		(fp_rect
			(start -0.508 0.9398)
			(end 0.508 -0.9398)
			(stroke
				(width 0)
				(type default)
			)
			(fill no)
			(layer "F.CrtYd")
		)
		(fp_rect
			(start -0.508 0.9398)
			(end 0.508 -0.9398)
			(stroke
				(width 0)
				(type default)
			)
			(fill no)
			(layer "F.Fab")
		)
		(pad "1" smd custom
			(at 0 -0.4445 90)
			(size 0.1397 0.1397)
			(layers "F.Cu" "F.Mask" "F.Paste")
			(net "HDD_PRSNT_NET8")
			(options
				(clearance outline)
				(anchor circle)
			)
			(primitives
				(gr_poly
					(pts
						(arc
							(start -0.1778 -0.2794)
							(mid -0.249642 -0.249642)
							(end -0.2794 -0.1778)
						)
						(arc
							(start -0.2794 0.1778)
							(mid -0.249642 0.249642)
							(end -0.1778 0.2794)
						)
						(arc
							(start 0.1778 0.2794)
							(mid 0.249642 0.249642)
							(end 0.2794 0.1778)
						)
						(arc
							(start 0.2794 -0.1778)
							(mid 0.249642 -0.249642)
							(end 0.1778 -0.2794)
						)
					)
					(width 0)
					(fill yes)
				)
			)
		)
		(pad "2" smd custom
			(at 0 0.4445 90)
			(size 0.1397 0.1397)
			(layers "F.Cu" "F.Mask" "F.Paste")
			(net "HDD8_LED_B")
			(options
				(clearance outline)
				(anchor circle)
			)
			(primitives
				(gr_poly
					(pts
						(arc
							(start -0.1778 -0.2794)
							(mid -0.249642 -0.249642)
							(end -0.2794 -0.1778)
						)
						(arc
							(start -0.2794 0.1778)
							(mid -0.249642 0.249642)
							(end -0.1778 0.2794)
						)
						(arc
							(start 0.1778 0.2794)
							(mid 0.249642 0.249642)
							(end 0.2794 0.1778)
						)
						(arc
							(start 0.2794 -0.1778)
							(mid 0.249642 -0.249642)
							(end 0.1778 -0.2794)
						)
					)
					(width 0)
					(fill yes)
				)
			)
		)
	)
	(footprint ""
		(layer "F.Cu")
		(at 80.01 -405.638 -90)
		(property "Reference" "D21"
			(at 0 0 270)
			(layer "F.SilkS")
			(hide yes)
			(effects
				(font
					(size 1.27 1.27)
				)
			)
		)
		(property "Value" "RB551V30-1-GP"
			(at 0 -6.7818 270)
			(unlocked yes)
			(layer "F.Fab")
			(hide yes)
			(effects
				(font
					(size 1.016 1.016)
					(thickness 0.1524)
				)
			)
		)
		(property "Device Type" "SOD323AKH44"
			(at 0 -8.6868 270)
			(unlocked yes)
			(layer "F.Fab")
			(hide yes)
			(effects
				(font
					(size 1.016 1.016)
					(thickness 0.1524)
				)
			)
		)
		(duplicate_pad_numbers_are_jumpers no)
		(fp_line
			(start -0.889 2.159)
			(end -0.889 -1.9304)
			(stroke
				(width 0.1524)
				(type default)
			)
			(layer "F.SilkS")
		)
		(fp_line
			(start 0.889 2.159)
			(end -0.889 2.159)
			(stroke
				(width 0.1524)
				(type default)
			)
			(layer "F.SilkS")
		)
		(fp_line
			(start 0.762 2.0574)
			(end -0.762 2.0574)
			(stroke
				(width 0.508)
				(type default)
			)
			(layer "F.SilkS")
		)
		(fp_line
			(start -0.889 -1.9304)
			(end 0.889 -1.9304)
			(stroke
				(width 0.1524)
				(type default)
			)
			(layer "F.SilkS")
		)
		(fp_line
			(start 0.889 -1.9304)
			(end 0.889 2.159)
			(stroke
				(width 0.1524)
				(type default)
			)
			(layer "F.SilkS")
		)
		(fp_rect
			(start -1.016 2.3114)
			(end 1.016 -2.0066)
			(stroke
				(width 0)
				(type default)
			)
			(fill no)
			(layer "F.CrtYd")
		)
		(fp_poly
			(pts
				(xy -1.016 -2.0066) (xy 1.016 -2.0066) (xy 1.016 2.3114) (xy -1.016 2.3114)
			)
			(stroke
				(width 0)
				(type default)
			)
			(fill no)
			(layer "F.Fab")
		)
		(pad "A" smd rect
			(at 0 -1.143 270)
			(size 0.5588 1.016)
			(layers "F.Cu" "F.Mask" "F.Paste")
			(net "SW_HDD6_R")
		)
		(pad "K" smd rect
			(at 0 1.143 270)
			(size 0.5588 1.016)
			(layers "F.Cu" "F.Mask" "F.Paste")
			(net "SW_HDD6_N")
		)
	)
	(footprint ""
		(layer "F.Cu")
		(at 30.987746 -341.1347 90)
		(property "Reference" "R258"
			(at 0 0 90)
			(layer "F.SilkS")
			(hide yes)
			(effects
				(font
					(size 1.27 1.27)
				)
			)
		)
		(property "Value" "0R2J-2-GP"
			(at 0.064008 -3.993896 90)
			(unlocked yes)
			(layer "F.Fab")
			(hide yes)
			(effects
				(font
					(size 1.016 1.016)
					(thickness 0.1524)
				)
			)
		)
		(property "Device Type" "R402H16"
			(at 0.064008 -5.517896 90)
			(unlocked yes)
			(layer "F.Fab")
			(hide yes)
			(effects
				(font
					(size 1.016 1.016)
					(thickness 0.1524)
				)
			)
		)
		(duplicate_pad_numbers_are_jumpers no)
		(fp_line
			(start 0.508 -0.9398)
			(end -0.508 -0.9398)
			(stroke
				(width 0.1524)
				(type default)
			)
			(layer "F.SilkS")
		)
		(fp_line
			(start -0.508 -0.9398)
			(end -0.508 0.9398)
			(stroke
				(width 0.1524)
				(type default)
			)
			(layer "F.SilkS")
		)
		(fp_rect
			(start -0.508 0.9398)
			(end 0.508 -0.9398)
			(stroke
				(width 0)
				(type default)
			)
			(fill no)
			(layer "F.CrtYd")
		)
		(fp_rect
			(start -0.508 0.9398)
			(end 0.508 -0.9398)
			(stroke
				(width 0)
				(type default)
			)
			(fill no)
			(layer "F.Fab")
		)
		(pad "1" smd custom
			(at 0 -0.4445 90)
			(size 0.1397 0.1397)
			(layers "F.Cu" "F.Mask" "F.Paste")
			(net "FLT_NET_HDD11")
			(options
				(clearance outline)
				(anchor circle)
			)
			(primitives
				(gr_poly
					(pts
						(arc
							(start -0.1778 -0.2794)
							(mid -0.249642 -0.249642)
							(end -0.2794 -0.1778)
						)
						(arc
							(start -0.2794 0.1778)
							(mid -0.249642 0.249642)
							(end -0.1778 0.2794)
						)
						(arc
							(start 0.1778 0.2794)
							(mid 0.249642 0.249642)
							(end 0.2794 0.1778)
						)
						(arc
							(start 0.2794 -0.1778)
							(mid 0.249642 -0.249642)
							(end 0.1778 -0.2794)
						)
					)
					(width 0)
					(fill yes)
				)
			)
		)
		(pad "2" smd custom
			(at 0 0.4445 90)
			(size 0.1397 0.1397)
			(layers "F.Cu" "F.Mask" "F.Paste")
			(net "FLT_HDD11_DRIVE")
			(options
				(clearance outline)
				(anchor circle)
			)
			(primitives
				(gr_poly
					(pts
						(arc
							(start -0.1778 -0.2794)
							(mid -0.249642 -0.249642)
							(end -0.2794 -0.1778)
						)
						(arc
							(start -0.2794 0.1778)
							(mid -0.249642 0.249642)
							(end -0.1778 0.2794)
						)
						(arc
							(start 0.1778 0.2794)
							(mid 0.249642 0.249642)
							(end 0.2794 0.1778)
						)
						(arc
							(start 0.2794 -0.1778)
							(mid 0.249642 -0.249642)
							(end 0.1778 -0.2794)
						)
					)
					(width 0)
					(fill yes)
				)
			)
		)
	)
	(footprint ""
		(layer "F.Cu")
		(at 192.405 -92.075 90)
		(property "Reference" "D19"
			(at 0 0 90)
			(layer "F.SilkS")
			(hide yes)
			(effects
				(font
					(size 1.27 1.27)
				)
			)
		)
		(property "Value" "RB551V30-1-GP"
			(at 0 -6.7818 90)
			(unlocked yes)
			(layer "F.Fab")
			(hide yes)
			(effects
				(font
					(size 1.016 1.016)
					(thickness 0.1524)
				)
			)
		)
		(property "Device Type" "SOD323AKH44"
			(at 0 -8.6868 90)
			(unlocked yes)
			(layer "F.Fab")
			(hide yes)
			(effects
				(font
					(size 1.016 1.016)
					(thickness 0.1524)
				)
			)
		)
		(duplicate_pad_numbers_are_jumpers no)
		(fp_line
			(start 0.889 -1.9304)
			(end 0.889 2.159)
			(stroke
				(width 0.1524)
				(type default)
			)
			(layer "F.SilkS")
		)
		(fp_line
			(start -0.889 -1.9304)
			(end 0.889 -1.9304)
			(stroke
				(width 0.1524)
				(type default)
			)
			(layer "F.SilkS")
		)
		(fp_line
			(start 0.762 2.0574)
			(end -0.762 2.0574)
			(stroke
				(width 0.508)
				(type default)
			)
			(layer "F.SilkS")
		)
		(fp_line
			(start 0.889 2.159)
			(end -0.889 2.159)
			(stroke
				(width 0.1524)
				(type default)
			)
			(layer "F.SilkS")
		)
		(fp_line
			(start -0.889 2.159)
			(end -0.889 -1.9304)
			(stroke
				(width 0.1524)
				(type default)
			)
			(layer "F.SilkS")
		)
		(fp_rect
			(start -1.016 2.3114)
			(end 1.016 -2.0066)
			(stroke
				(width 0)
				(type default)
			)
			(fill no)
			(layer "F.CrtYd")
		)
		(fp_poly
			(pts
				(xy -1.016 -2.0066) (xy 1.016 -2.0066) (xy 1.016 2.3114) (xy -1.016 2.3114)
			)
			(stroke
				(width 0)
				(type default)
			)
			(fill no)
			(layer "F.Fab")
		)
		(pad "A" smd rect
			(at 0 -1.143 90)
			(size 0.5588 1.016)
			(layers "F.Cu" "F.Mask" "F.Paste")
			(net "SW_HDD4_R")
		)
		(pad "K" smd rect
			(at 0 1.143 90)
			(size 0.5588 1.016)
			(layers "F.Cu" "F.Mask" "F.Paste")
			(net "SW_HDD4_N")
		)
	)
	(footprint ""
		(layer "F.Cu")
		(at 200.164446 -461.425036 180)
		(property "Reference" "C347"
			(at 0 0 180)
			(layer "F.SilkS")
			(hide yes)
			(effects
				(font
					(size 1.27 1.27)
				)
			)
		)
		(property "Value" "SCD1U50V3KX-GP"
			(at 0 -2.8194 180)
			(unlocked yes)
			(layer "F.Fab")
			(hide yes)
			(effects
				(font
					(size 1.016 1.016)
					(thickness 0.1524)
				)
			)
		)
		(property "Device Type" "C603H36"
			(at 0 -4.3434 180)
			(unlocked yes)
			(layer "F.Fab")
			(hide yes)
			(effects
				(font
					(size 1.016 1.016)
					(thickness 0.1524)
				)
			)
		)
		(duplicate_pad_numbers_are_jumpers no)
		(fp_line
			(start 0.508 0)
			(end -0.508 0)
			(stroke
				(width 0.2032)
				(type default)
			)
			(layer "F.SilkS")
		)
		(fp_rect
			(start -0.5842 1.3335)
			(end 0.5842 -1.3335)
			(stroke
				(width 0)
				(type default)
			)
			(fill no)
			(layer "F.CrtYd")
		)
		(fp_rect
			(start -0.5842 1.3335)
			(end 0.5842 -1.3335)
			(stroke
				(width 0)
				(type default)
			)
			(fill no)
			(layer "F.Fab")
		)
		(pad "1" smd custom
			(at 0 -0.762 180)
			(size 0.2159 0.2159)
			(layers "F.Cu" "F.Mask" "F.Paste")
			(net "P3V3")
			(options
				(clearance outline)
				(anchor circle)
			)
			(primitives
				(gr_poly
					(pts
						(arc
							(start -0.3302 -0.4318)
							(mid -0.402042 -0.402042)
							(end -0.4318 -0.3302)
						)
						(arc
							(start -0.4318 0.3302)
							(mid -0.402042 0.402042)
							(end -0.3302 0.4318)
						)
						(arc
							(start 0.3302 0.4318)
							(mid 0.402042 0.402042)
							(end 0.4318 0.3302)
						)
						(arc
							(start 0.4318 -0.3302)
							(mid 0.402042 -0.402042)
							(end 0.3302 -0.4318)
						)
					)
					(width 0)
					(fill yes)
				)
			)
		)
		(pad "2" smd custom
			(at 0 0.762 180)
			(size 0.2159 0.2159)
			(layers "F.Cu" "F.Mask" "F.Paste")
			(net "GND")
			(options
				(clearance outline)
				(anchor circle)
			)
			(primitives
				(gr_poly
					(pts
						(arc
							(start -0.3302 -0.4318)
							(mid -0.402042 -0.402042)
							(end -0.4318 -0.3302)
						)
						(arc
							(start -0.4318 0.3302)
							(mid -0.402042 0.402042)
							(end -0.3302 0.4318)
						)
						(arc
							(start 0.3302 0.4318)
							(mid 0.402042 0.402042)
							(end 0.4318 0.3302)
						)
						(arc
							(start 0.4318 -0.3302)
							(mid 0.402042 -0.402042)
							(end 0.3302 -0.4318)
						)
					)
					(width 0)
					(fill yes)
				)
			)
		)
	)
	(footprint ""
		(layer "F.Cu")
		(at 45.847 -349.1992 180)
		(property "Reference" "R187"
			(at 0 0 180)
			(layer "F.SilkS")
			(hide yes)
			(effects
				(font
					(size 1.27 1.27)
				)
			)
		)
		(property "Value" "330R2F-GP"
			(at 0.064008 -3.993896 180)
			(unlocked yes)
			(layer "F.Fab")
			(hide yes)
			(effects
				(font
					(size 1.016 1.016)
					(thickness 0.1524)
				)
			)
		)
		(property "Device Type" "R402H16"
			(at 0.064008 -5.517896 180)
			(unlocked yes)
			(layer "F.Fab")
			(hide yes)
			(effects
				(font
					(size 1.016 1.016)
					(thickness 0.1524)
				)
			)
		)
		(duplicate_pad_numbers_are_jumpers no)
		(fp_line
			(start 0.508 -0.9398)
			(end -0.508 -0.9398)
			(stroke
				(width 0.1524)
				(type default)
			)
			(layer "F.SilkS")
		)
		(fp_line
			(start -0.508 -0.9398)
			(end -0.508 0.9398)
			(stroke
				(width 0.1524)
				(type default)
			)
			(layer "F.SilkS")
		)
		(fp_rect
			(start -0.508 0.9398)
			(end 0.508 -0.9398)
			(stroke
				(width 0)
				(type default)
			)
			(fill no)
			(layer "F.CrtYd")
		)
		(fp_rect
			(start -0.508 0.9398)
			(end 0.508 -0.9398)
			(stroke
				(width 0)
				(type default)
			)
			(fill no)
			(layer "F.Fab")
		)
		(pad "1" smd custom
			(at 0 -0.4445 180)
			(size 0.1397 0.1397)
			(layers "F.Cu" "F.Mask" "F.Paste")
			(net "P3V3_HDD6_LED")
			(options
				(clearance outline)
				(anchor circle)
			)
			(primitives
				(gr_poly
					(pts
						(arc
							(start -0.1778 -0.2794)
							(mid -0.249642 -0.249642)
							(end -0.2794 -0.1778)
						)
						(arc
							(start -0.2794 0.1778)
							(mid -0.249642 0.249642)
							(end -0.1778 0.2794)
						)
						(arc
							(start 0.1778 0.2794)
							(mid 0.249642 0.249642)
							(end 0.2794 0.1778)
						)
						(arc
							(start 0.2794 -0.1778)
							(mid 0.249642 -0.249642)
							(end 0.1778 -0.2794)
						)
					)
					(width 0)
					(fill yes)
				)
			)
		)
		(pad "2" smd custom
			(at 0 0.4445 180)
			(size 0.1397 0.1397)
			(layers "F.Cu" "F.Mask" "F.Paste")
			(net "FLT_HDD6")
			(options
				(clearance outline)
				(anchor circle)
			)
			(primitives
				(gr_poly
					(pts
						(arc
							(start -0.1778 -0.2794)
							(mid -0.249642 -0.249642)
							(end -0.2794 -0.1778)
						)
						(arc
							(start -0.2794 0.1778)
							(mid -0.249642 0.249642)
							(end -0.1778 0.2794)
						)
						(arc
							(start 0.1778 0.2794)
							(mid 0.249642 0.249642)
							(end 0.2794 0.1778)
						)
						(arc
							(start 0.2794 -0.1778)
							(mid 0.249642 -0.249642)
							(end 0.1778 -0.2794)
						)
					)
					(width 0)
					(fill yes)
				)
			)
		)
	)
	(footprint ""
		(layer "F.Cu")
		(at 6.985 -231.648)
		(property "Reference" "R609"
			(at 0 0 0)
			(layer "F.SilkS")
			(hide yes)
			(effects
				(font
					(size 1.27 1.27)
				)
			)
		)
		(property "Value" "2R2010J-1-GP"
			(at 0.254 -8.0772 0)
			(unlocked yes)
			(layer "F.Fab")
			(hide yes)
			(effects
				(font
					(size 1.016 1.016)
					(thickness 0.1524)
				)
			)
		)
		(property "Device Type" "R2010H28"
			(at 0.254 -9.6774 0)
			(unlocked yes)
			(layer "F.Fab")
			(hide yes)
			(effects
				(font
					(size 1.016 1.016)
					(thickness 0.1524)
				)
			)
		)
		(duplicate_pad_numbers_are_jumpers no)
		(fp_line
			(start -1.651 -3.302)
			(end -1.651 3.302)
			(stroke
				(width 0.1524)
				(type default)
			)
			(layer "F.SilkS")
		)
		(fp_line
			(start -1.651 3.302)
			(end 1.651 3.302)
			(stroke
				(width 0.1524)
				(type default)
			)
			(layer "F.SilkS")
		)
		(fp_line
			(start 1.651 -3.302)
			(end -1.651 -3.302)
			(stroke
				(width 0.1524)
				(type default)
			)
			(layer "F.SilkS")
		)
		(fp_line
			(start 1.651 3.302)
			(end 1.651 -3.302)
			(stroke
				(width 0.1524)
				(type default)
			)
			(layer "F.SilkS")
		)
		(fp_rect
			(start -1.7272 -3.3782)
			(end 1.7272 3.3782)
			(stroke
				(width 0)
				(type default)
			)
			(fill no)
			(layer "F.CrtYd")
		)
		(fp_poly
			(pts
				(xy 1.7272 3.3782) (xy 1.7272 -3.3782) (xy -1.7272 -3.3782) (xy -1.7272 3.3782)
			)
			(stroke
				(width 0)
				(type default)
			)
			(fill no)
			(layer "F.Fab")
		)
		(pad "1" smd rect
			(at 0 -2.3495)
			(size 2.794 1.143)
			(layers "F.Cu" "F.Mask" "F.Paste")
			(net "GND")
		)
		(pad "2" smd rect
			(at 0 2.3495)
			(size 2.794 1.143)
			(layers "F.Cu" "F.Mask" "F.Paste")
			(net "PCIE_MATED#_B")
		)
	)
	(footprint ""
		(layer "F.Cu")
		(at 4.698746 -489.3437)
		(property "Reference" "R486"
			(at 0 0 0)
			(layer "F.SilkS")
			(hide yes)
			(effects
				(font
					(size 1.27 1.27)
				)
			)
		)
		(property "Value" "0R3J-0-U-GP"
			(at -0.0254 -2.5146 0)
			(unlocked yes)
			(layer "F.Fab")
			(hide yes)
			(effects
				(font
					(size 1.016 1.016)
					(thickness 0.1524)
				)
			)
		)
		(property "Device Type" "R603H22"
			(at -0.0254 -4.0386 0)
			(unlocked yes)
			(layer "F.Fab")
			(hide yes)
			(effects
				(font
					(size 1.016 1.016)
					(thickness 0.1524)
				)
			)
		)
		(duplicate_pad_numbers_are_jumpers no)
		(fp_line
			(start -0.4826 0)
			(end -0.2032 0)
			(stroke
				(width 0.2032)
				(type default)
			)
			(layer "F.SilkS")
		)
		(fp_line
			(start 0.2032 0)
			(end 0.4826 0)
			(stroke
				(width 0.2032)
				(type default)
			)
			(layer "F.SilkS")
		)
		(fp_rect
			(start -0.5842 1.3335)
			(end 0.5842 -1.3335)
			(stroke
				(width 0)
				(type default)
			)
			(fill no)
			(layer "F.CrtYd")
		)
		(fp_rect
			(start -0.5842 1.3335)
			(end 0.5842 -1.3335)
			(stroke
				(width 0)
				(type default)
			)
			(fill no)
			(layer "F.Fab")
		)
		(pad "1" smd custom
			(at 0 -0.762)
			(size 0.2159 0.2159)
			(layers "F.Cu" "F.Mask" "F.Paste")
			(net "P5VC_VBST")
			(options
				(clearance outline)
				(anchor circle)
			)
			(primitives
				(gr_poly
					(pts
						(arc
							(start -0.3302 -0.4318)
							(mid -0.402042 -0.402042)
							(end -0.4318 -0.3302)
						)
						(arc
							(start -0.4318 0.3302)
							(mid -0.402042 0.402042)
							(end -0.3302 0.4318)
						)
						(arc
							(start 0.3302 0.4318)
							(mid 0.402042 0.402042)
							(end 0.4318 0.3302)
						)
						(arc
							(start 0.4318 -0.3302)
							(mid 0.402042 -0.402042)
							(end 0.3302 -0.4318)
						)
					)
					(width 0)
					(fill yes)
				)
			)
		)
		(pad "2" smd custom
			(at 0 0.762)
			(size 0.2159 0.2159)
			(layers "F.Cu" "F.Mask" "F.Paste")
			(net "P5VC_VBST_NET")
			(options
				(clearance outline)
				(anchor circle)
			)
			(primitives
				(gr_poly
					(pts
						(arc
							(start -0.3302 -0.4318)
							(mid -0.402042 -0.402042)
							(end -0.4318 -0.3302)
						)
						(arc
							(start -0.4318 0.3302)
							(mid -0.402042 0.402042)
							(end -0.3302 0.4318)
						)
						(arc
							(start 0.3302 0.4318)
							(mid 0.402042 0.402042)
							(end 0.4318 0.3302)
						)
						(arc
							(start 0.4318 -0.3302)
							(mid 0.402042 -0.402042)
							(end 0.3302 -0.4318)
						)
					)
					(width 0)
					(fill yes)
				)
			)
		)
	)
	(footprint ""
		(layer "F.Cu")
		(at 50.050446 -414.175702 90)
		(property "Reference" "R249"
			(at 0 0 90)
			(layer "F.SilkS")
			(hide yes)
			(effects
				(font
					(size 1.27 1.27)
				)
			)
		)
		(property "Value" "200KR2F-L-GP"
			(at 0.064008 -3.993896 90)
			(unlocked yes)
			(layer "F.Fab")
			(hide yes)
			(effects
				(font
					(size 1.016 1.016)
					(thickness 0.1524)
				)
			)
		)
		(property "Device Type" "R402H16"
			(at 0.064008 -5.517896 90)
			(unlocked yes)
			(layer "F.Fab")
			(hide yes)
			(effects
				(font
					(size 1.016 1.016)
					(thickness 0.1524)
				)
			)
		)
		(duplicate_pad_numbers_are_jumpers no)
		(fp_line
			(start 0.508 -0.9398)
			(end -0.508 -0.9398)
			(stroke
				(width 0.1524)
				(type default)
			)
			(layer "F.SilkS")
		)
		(fp_line
			(start -0.508 -0.9398)
			(end -0.508 0.9398)
			(stroke
				(width 0.1524)
				(type default)
			)
			(layer "F.SilkS")
		)
		(fp_rect
			(start -0.508 0.9398)
			(end 0.508 -0.9398)
			(stroke
				(width 0)
				(type default)
			)
			(fill no)
			(layer "F.CrtYd")
		)
		(fp_rect
			(start -0.508 0.9398)
			(end 0.508 -0.9398)
			(stroke
				(width 0)
				(type default)
			)
			(fill no)
			(layer "F.Fab")
		)
		(pad "1" smd custom
			(at 0 -0.4445 90)
			(size 0.1397 0.1397)
			(layers "F.Cu" "F.Mask" "F.Paste")
			(net "P12V")
			(options
				(clearance outline)
				(anchor circle)
			)
			(primitives
				(gr_poly
					(pts
						(arc
							(start -0.1778 -0.2794)
							(mid -0.249642 -0.249642)
							(end -0.2794 -0.1778)
						)
						(arc
							(start -0.2794 0.1778)
							(mid -0.249642 0.249642)
							(end -0.1778 0.2794)
						)
						(arc
							(start 0.1778 0.2794)
							(mid 0.249642 0.249642)
							(end 0.2794 0.1778)
						)
						(arc
							(start 0.2794 -0.1778)
							(mid 0.249642 -0.249642)
							(end 0.1778 -0.2794)
						)
					)
					(width 0)
					(fill yes)
				)
			)
		)
		(pad "2" smd custom
			(at 0 0.4445 90)
			(size 0.1397 0.1397)
			(layers "F.Cu" "F.Mask" "F.Paste")
			(net "SW_HDD10_P")
			(options
				(clearance outline)
				(anchor circle)
			)
			(primitives
				(gr_poly
					(pts
						(arc
							(start -0.1778 -0.2794)
							(mid -0.249642 -0.249642)
							(end -0.2794 -0.1778)
						)
						(arc
							(start -0.2794 0.1778)
							(mid -0.249642 0.249642)
							(end -0.1778 0.2794)
						)
						(arc
							(start 0.1778 0.2794)
							(mid 0.249642 0.249642)
							(end 0.2794 0.1778)
						)
						(arc
							(start 0.2794 -0.1778)
							(mid 0.249642 -0.249642)
							(end 0.1778 -0.2794)
						)
					)
					(width 0)
					(fill yes)
				)
			)
		)
	)
	(footprint ""
		(layer "F.Cu")
		(at 205.951074 -178.905662 90)
		(property "Reference" "Q7"
			(at 0 0 90)
			(layer "F.SilkS")
			(hide yes)
			(effects
				(font
					(size 1.27 1.27)
				)
			)
		)
		(property "Value" "AO4406AL-GP"
			(at -3.707384 -1.5367 90)
			(unlocked yes)
			(layer "F.Fab")
			(hide yes)
			(effects
				(font
					(size 1.016 1.016)
					(thickness 0.1524)
				)
			)
		)
		(property "Device Type" "SOIC8H69"
			(at -3.707384 -3.0607 90)
			(unlocked yes)
			(layer "F.Fab")
			(hide yes)
			(effects
				(font
					(size 1.016 1.016)
					(thickness 0.1524)
				)
			)
		)
		(duplicate_pad_numbers_are_jumpers no)
		(fp_line
			(start 2.1336 -1.4224)
			(end -2.7432 -1.4224)
			(stroke
				(width 0.1524)
				(type default)
			)
			(layer "F.SilkS")
		)
		(fp_line
			(start -2.7432 -1.4224)
			(end -2.7432 1.4224)
			(stroke
				(width 0.1524)
				(type default)
			)
			(layer "F.SilkS")
		)
		(fp_line
			(start -2.7178 -0.508)
			(end -2.1844 -0.0508)
			(stroke
				(width 0.1524)
				(type default)
			)
			(layer "F.SilkS")
		)
		(fp_line
			(start -2.1844 -0.0508)
			(end -2.7178 0.508)
			(stroke
				(width 0.1524)
				(type default)
			)
			(layer "F.SilkS")
		)
		(fp_line
			(start 2.1336 1.4224)
			(end 2.1336 -1.4224)
			(stroke
				(width 0.1524)
				(type default)
			)
			(layer "F.SilkS")
		)
		(fp_line
			(start -2.7432 1.4224)
			(end 2.1336 1.4224)
			(stroke
				(width 0.1524)
				(type default)
			)
			(layer "F.SilkS")
		)
		(fp_line
			(start -2.7432 1.4224)
			(end -2.6416 1.4224)
			(stroke
				(width 0.1524)
				(type default)
			)
			(layer "F.SilkS")
		)
		(fp_line
			(start -2.6289 3.4417)
			(end -2.6289 1.4732)
			(stroke
				(width 0.381)
				(type default)
			)
			(layer "F.SilkS")
		)
		(fp_poly
			(pts
				(xy -2.2098 -1.4224) (xy -2.2098 1.4224) (xy 2.2098 1.4224) (xy 2.2098 -1.4224)
			)
			(stroke
				(width 0)
				(type default)
			)
			(fill yes)
			(layer "F.SilkS")
		)
		(fp_rect
			(start -2.450084 2.999994)
			(end 2.450084 -2.999994)
			(stroke
				(width 0)
				(type default)
			)
			(fill no)
			(layer "F.CrtYd")
		)
		(fp_poly
			(pts
				(xy -2.8194 3.6322) (xy -2.8194 -3.6322) (xy 2.8194 -3.6322) (xy 2.8194 1.18364) (xy 2.450084 1.18364)
				(xy 2.450084 -2.999994) (xy -2.450084 -2.999994) (xy -2.450084 2.999994) (xy 2.450084 2.999994)
				(xy 2.450084 1.18618) (xy 2.8194 1.18618) (xy 2.8194 3.6322)
			)
			(stroke
				(width 0)
				(type default)
			)
			(fill no)
			(layer "F.CrtYd")
		)
		(fp_rect
			(start -2.8194 3.6322)
			(end 2.8194 -3.6322)
			(stroke
				(width 0)
				(type default)
			)
			(fill no)
			(layer "F.Fab")
		)
		(pad "1" smd rect
			(at -1.905 2.54 90)
			(size 0.635 1.651)
			(layers "F.Cu" "F.Mask" "F.Paste")
			(net "P5V_HDD3")
		)
		(pad "2" smd rect
			(at -0.635 2.54 90)
			(size 0.635 1.651)
			(layers "F.Cu" "F.Mask" "F.Paste")
			(net "P5V_HDD3")
		)
		(pad "3" smd rect
			(at 0.635 2.54 90)
			(size 0.635 1.651)
			(layers "F.Cu" "F.Mask" "F.Paste")
			(net "P5V_HDD3")
		)
		(pad "4" smd rect
			(at 1.905 2.54 90)
			(size 0.635 1.651)
			(layers "F.Cu" "F.Mask" "F.Paste")
			(net "SW_HDD3_P")
		)
		(pad "5" smd rect
			(at 1.905 -2.54 90)
			(size 0.635 1.651)
			(layers "F.Cu" "F.Mask" "F.Paste")
			(net "P5VA")
		)
		(pad "6" smd rect
			(at 0.635 -2.54 90)
			(size 0.635 1.651)
			(layers "F.Cu" "F.Mask" "F.Paste")
			(net "P5VA")
		)
		(pad "7" smd rect
			(at -0.635 -2.54 90)
			(size 0.635 1.651)
			(layers "F.Cu" "F.Mask" "F.Paste")
			(net "P5VA")
		)
		(pad "8" smd rect
			(at -1.905 -2.54 90)
			(size 0.635 1.651)
			(layers "F.Cu" "F.Mask" "F.Paste")
			(net "P5VA")
		)
	)
	(footprint ""
		(layer "F.Cu")
		(at 25.971246 -374.9167 -90)
		(property "Reference" "R320"
			(at 0 0 270)
			(layer "F.SilkS")
			(hide yes)
			(effects
				(font
					(size 1.27 1.27)
				)
			)
		)
		(property "Value" "4K7R2J-2-GP"
			(at 0.064008 -3.993896 270)
			(unlocked yes)
			(layer "F.Fab")
			(hide yes)
			(effects
				(font
					(size 1.016 1.016)
					(thickness 0.1524)
				)
			)
		)
		(property "Device Type" "R402H16"
			(at 0.064008 -5.517896 270)
			(unlocked yes)
			(layer "F.Fab")
			(hide yes)
			(effects
				(font
					(size 1.016 1.016)
					(thickness 0.1524)
				)
			)
		)
		(duplicate_pad_numbers_are_jumpers no)
		(fp_line
			(start -0.508 -0.9398)
			(end -0.508 0.9398)
			(stroke
				(width 0.1524)
				(type default)
			)
			(layer "F.SilkS")
		)
		(fp_line
			(start 0.508 -0.9398)
			(end -0.508 -0.9398)
			(stroke
				(width 0.1524)
				(type default)
			)
			(layer "F.SilkS")
		)
		(fp_rect
			(start -0.508 0.9398)
			(end 0.508 -0.9398)
			(stroke
				(width 0)
				(type default)
			)
			(fill no)
			(layer "F.CrtYd")
		)
		(fp_rect
			(start -0.508 0.9398)
			(end 0.508 -0.9398)
			(stroke
				(width 0)
				(type default)
			)
			(fill no)
			(layer "F.Fab")
		)
		(pad "1" smd custom
			(at 0 -0.4445 270)
			(size 0.1397 0.1397)
			(layers "F.Cu" "F.Mask" "F.Paste")
			(net "I2C_B_TMP1_A2")
			(options
				(clearance outline)
				(anchor circle)
			)
			(primitives
				(gr_poly
					(pts
						(arc
							(start -0.1778 -0.2794)
							(mid -0.249642 -0.249642)
							(end -0.2794 -0.1778)
						)
						(arc
							(start -0.2794 0.1778)
							(mid -0.249642 0.249642)
							(end -0.1778 0.2794)
						)
						(arc
							(start 0.1778 0.2794)
							(mid 0.249642 0.249642)
							(end 0.2794 0.1778)
						)
						(arc
							(start 0.2794 -0.1778)
							(mid 0.249642 -0.249642)
							(end 0.1778 -0.2794)
						)
					)
					(width 0)
					(fill yes)
				)
			)
		)
		(pad "2" smd custom
			(at 0 0.4445 270)
			(size 0.1397 0.1397)
			(layers "F.Cu" "F.Mask" "F.Paste")
			(net "GND")
			(options
				(clearance outline)
				(anchor circle)
			)
			(primitives
				(gr_poly
					(pts
						(arc
							(start -0.1778 -0.2794)
							(mid -0.249642 -0.249642)
							(end -0.2794 -0.1778)
						)
						(arc
							(start -0.2794 0.1778)
							(mid -0.249642 0.249642)
							(end -0.1778 0.2794)
						)
						(arc
							(start 0.1778 0.2794)
							(mid 0.249642 0.249642)
							(end 0.2794 0.1778)
						)
						(arc
							(start 0.2794 -0.1778)
							(mid 0.249642 -0.249642)
							(end 0.1778 -0.2794)
						)
					)
					(width 0)
					(fill yes)
				)
			)
		)
	)
	(footprint ""
		(layer "F.Cu")
		(at 55.117492 -72.545956)
		(property "Reference" "C254"
			(at 0 0 0)
			(layer "F.SilkS")
			(hide yes)
			(effects
				(font
					(size 1.27 1.27)
				)
			)
		)
		(property "Value" "SCD01U50V2KX-1GP"
			(at 1.1811 -2.7051 0)
			(unlocked yes)
			(layer "F.Fab")
			(hide yes)
			(effects
				(font
					(size 1.016 1.016)
					(thickness 0.1524)
				)
			)
		)
		(property "Device Type" "C402H22"
			(at 1.1811 -4.2291 0)
			(unlocked yes)
			(layer "F.Fab")
			(hide yes)
			(effects
				(font
					(size 1.016 1.016)
					(thickness 0.1524)
				)
			)
		)
		(duplicate_pad_numbers_are_jumpers no)
		(fp_rect
			(start -0.4318 0.9525)
			(end 0.4318 -0.9525)
			(stroke
				(width 0)
				(type default)
			)
			(fill no)
			(layer "F.CrtYd")
		)
		(fp_rect
			(start -0.4318 0.9525)
			(end 0.4318 -0.9525)
			(stroke
				(width 0)
				(type default)
			)
			(fill no)
			(layer "F.Fab")
		)
		(pad "1" smd custom
			(at 0 -0.4445)
			(size 0.1524 0.1524)
			(layers "F.Cu" "F.Mask" "F.Paste")
			(net "HDD_PRSNT_NET9")
			(options
				(clearance outline)
				(anchor circle)
			)
			(primitives
				(gr_poly
					(pts
						(arc
							(start 0.3048 -0.2032)
							(mid 0.275042 -0.275042)
							(end 0.2032 -0.3048)
						)
						(arc
							(start -0.2032 -0.3048)
							(mid -0.275042 -0.275042)
							(end -0.3048 -0.2032)
						)
						(arc
							(start -0.3048 0.2032)
							(mid -0.275042 0.275042)
							(end -0.2032 0.3048)
						)
						(arc
							(start 0.2032 0.3048)
							(mid 0.275042 0.275042)
							(end 0.3048 0.2032)
						)
					)
					(width 0)
					(fill yes)
				)
			)
		)
		(pad "2" smd custom
			(at 0 0.4445)
			(size 0.1524 0.1524)
			(layers "F.Cu" "F.Mask" "F.Paste")
			(net "GND")
			(options
				(clearance outline)
				(anchor circle)
			)
			(primitives
				(gr_poly
					(pts
						(arc
							(start 0.3048 -0.2032)
							(mid 0.275042 -0.275042)
							(end 0.2032 -0.3048)
						)
						(arc
							(start -0.2032 -0.3048)
							(mid -0.275042 -0.275042)
							(end -0.3048 -0.2032)
						)
						(arc
							(start -0.3048 0.2032)
							(mid -0.275042 0.275042)
							(end -0.2032 0.3048)
						)
						(arc
							(start 0.2032 0.3048)
							(mid 0.275042 0.275042)
							(end 0.3048 0.2032)
						)
					)
					(width 0)
					(fill yes)
				)
			)
		)
	)
	(footprint ""
		(layer "F.Cu")
		(at 193.216784 -187.930028 -90)
		(property "Reference" "Q8"
			(at 0 0 270)
			(layer "F.SilkS")
			(hide yes)
			(effects
				(font
					(size 1.27 1.27)
				)
			)
		)
		(property "Value" "2N7002DW-7F-GP"
			(at -2.3622 -8.2042 270)
			(unlocked yes)
			(layer "F.Fab")
			(hide yes)
			(effects
				(font
					(size 1.016 1.016)
					(thickness 0.1524)
				)
			)
		)
		(property "Device Type" "SOT-363H44"
			(at -2.3622 -10.1092 270)
			(unlocked yes)
			(layer "F.Fab")
			(hide yes)
			(effects
				(font
					(size 1.016 1.016)
					(thickness 0.1524)
				)
			)
		)
		(duplicate_pad_numbers_are_jumpers no)
		(fp_line
			(start -1.4478 1.7018)
			(end 1.4478 1.7018)
			(stroke
				(width 0.1524)
				(type default)
			)
			(layer "F.SilkS")
		)
		(fp_line
			(start 1.4478 1.7018)
			(end 1.4478 -1.7018)
			(stroke
				(width 0.1524)
				(type default)
			)
			(layer "F.SilkS")
		)
		(fp_line
			(start -1.27 1.524)
			(end -1.27 0.6604)
			(stroke
				(width 0.4826)
				(type default)
			)
			(layer "F.SilkS")
		)
		(fp_line
			(start -1.4478 -1.7018)
			(end -1.4478 1.7018)
			(stroke
				(width 0.1524)
				(type default)
			)
			(layer "F.SilkS")
		)
		(fp_line
			(start 1.4478 -1.7018)
			(end -1.4478 -1.7018)
			(stroke
				(width 0.1524)
				(type default)
			)
			(layer "F.SilkS")
		)
		(fp_poly
			(pts
				(xy -1.524 -1.778) (xy 1.524 -1.778) (xy 1.524 1.778) (xy -1.524 1.778)
			)
			(stroke
				(width 0)
				(type default)
			)
			(fill no)
			(layer "F.CrtYd")
		)
		(fp_poly
			(pts
				(xy -1.524 -1.778) (xy 1.524 -1.778) (xy 1.524 1.778) (xy -1.524 1.778)
			)
			(stroke
				(width 0)
				(type default)
			)
			(fill no)
			(layer "F.Fab")
		)
		(pad "1" smd rect
			(at -0.65024 0.9398 270)
			(size 0.4064 1.016)
			(layers "F.Cu" "F.Mask" "F.Paste")
			(net "GND")
		)
		(pad "2" smd rect
			(at 0 0.9398 270)
			(size 0.4064 1.016)
			(layers "F.Cu" "F.Mask" "F.Paste")
			(net "SW_PWR_R_HDD3")
		)
		(pad "3" smd rect
			(at 0.65024 0.9398 270)
			(size 0.4064 1.016)
			(layers "F.Cu" "F.Mask" "F.Paste")
			(net "SW_HDD3_P")
		)
		(pad "4" smd rect
			(at 0.65024 -0.9398 270)
			(size 0.4064 1.016)
			(layers "F.Cu" "F.Mask" "F.Paste")
			(net "GND")
		)
		(pad "5" smd rect
			(at 0 -0.9398 270)
			(size 0.4064 1.016)
			(layers "F.Cu" "F.Mask" "F.Paste")
			(net "SW_HDD3_G")
		)
		(pad "6" smd rect
			(at -0.65024 -0.9398 270)
			(size 0.4064 1.016)
			(layers "F.Cu" "F.Mask" "F.Paste")
			(net "SW_HDD3_R")
		)
	)
	(footprint ""
		(layer "F.Cu")
		(at 227.499926 -350.160082 180)
		(property "Reference" "LED2"
			(at 0 0 180)
			(layer "F.SilkS")
			(hide yes)
			(effects
				(font
					(size 1.27 1.27)
				)
			)
		)
		(property "Value" "LED-RB-4-GP"
			(at 5.88899 1.80848 180)
			(unlocked yes)
			(layer "F.Fab")
			(hide yes)
			(effects
				(font
					(size 1.016 1.016)
					(thickness 0.1524)
				)
			)
		)
		(property "Device Type" "LED1613-4PH20"
			(at 5.88899 0.28448 180)
			(unlocked yes)
			(layer "F.Fab")
			(hide yes)
			(effects
				(font
					(size 1.016 1.016)
					(thickness 0.1524)
				)
			)
		)
		(duplicate_pad_numbers_are_jumpers no)
		(fp_line
			(start 1.4478 0.9652)
			(end -1.4478 0.9652)
			(stroke
				(width 0.1524)
				(type default)
			)
			(layer "F.SilkS")
		)
		(fp_line
			(start 1.4478 -0.9652)
			(end 1.4478 0.9652)
			(stroke
				(width 0.1524)
				(type default)
			)
			(layer "F.SilkS")
		)
		(fp_line
			(start -1.4478 0.9652)
			(end -1.4478 -0.9652)
			(stroke
				(width 0.1524)
				(type default)
			)
			(layer "F.SilkS")
		)
		(fp_line
			(start -1.4478 0.9652)
			(end -1.4478 -0.9652)
			(stroke
				(width 0.508)
				(type default)
			)
			(layer "F.SilkS")
		)
		(fp_line
			(start -1.4478 -0.9652)
			(end 1.4478 -0.9652)
			(stroke
				(width 0.1524)
				(type default)
			)
			(layer "F.SilkS")
		)
		(fp_rect
			(start -0.8001 0.6477)
			(end 0.8001 -0.6477)
			(stroke
				(width 0)
				(type default)
			)
			(fill no)
			(layer "F.CrtYd")
		)
		(fp_poly
			(pts
				(xy -1.7018 1.2192) (xy -1.7018 -0.06223) (xy -0.8001 -0.06223) (xy -0.8001 0.6477) (xy 0.8001 0.6477)
				(xy 0.8001 -0.6477) (xy -0.8001 -0.6477) (xy -0.8001 -0.0635) (xy -1.7018 -0.0635) (xy -1.7018 -1.2192)
				(xy 1.7018 -1.2192) (xy 1.7018 1.2192)
			)
			(stroke
				(width 0)
				(type default)
			)
			(fill no)
			(layer "F.CrtYd")
		)
		(fp_rect
			(start -1.7018 1.2192)
			(end 1.7018 -1.2192)
			(stroke
				(width 0)
				(type default)
			)
			(fill no)
			(layer "F.Fab")
		)
		(pad "1" smd rect
			(at -0.73025 0.4064 180)
			(size 0.9144 0.6096)
			(layers "F.Cu" "F.Mask" "F.Paste")
			(net "DRV_ACT_NET1")
		)
		(pad "2" smd rect
			(at -0.73025 -0.4064 180)
			(size 0.9144 0.6096)
			(layers "F.Cu" "F.Mask" "F.Paste")
			(net "FLT_NET_HDD1")
		)
		(pad "3" smd rect
			(at 0.73025 -0.4064 180)
			(size 0.9144 0.6096)
			(layers "F.Cu" "F.Mask" "F.Paste")
			(net "FLT_HDD1")
		)
		(pad "4" smd rect
			(at 0.73025 0.4064 180)
			(size 0.9144 0.6096)
			(layers "F.Cu" "F.Mask" "F.Paste")
			(net "DRV_ACT_1")
		)
	)
	(footprint ""
		(layer "F.Cu")
		(at 41.275 -141.605 -90)
		(property "Reference" "TP2"
			(at 0 0 270)
			(layer "F.SilkS")
			(hide yes)
			(effects
				(font
					(size 1.27 1.27)
				)
			)
		)
		(property "Value" "TPAD32-GP"
			(at 0 -3.166364 270)
			(unlocked yes)
			(layer "F.Fab")
			(hide yes)
			(effects
				(font
					(size 1.016 1.016)
					(thickness 0.1524)
				)
			)
		)
		(property "Device Type" "TPAD32"
			(at 0 -4.690618 270)
			(unlocked yes)
			(layer "F.Fab")
			(hide yes)
			(effects
				(font
					(size 1.016 1.016)
					(thickness 0.1524)
				)
			)
		)
		(duplicate_pad_numbers_are_jumpers no)
		(fp_poly
			(pts
				(arc
					(start 0 -0.4064)
					(mid 0 0.4064)
					(end 0 -0.4064)
				)
			)
			(stroke
				(width 0)
				(type default)
			)
			(fill no)
			(layer "F.CrtYd")
		)
		(fp_poly
			(pts
				(arc
					(start 0 -0.7112)
					(mid 0 0.7112)
					(end 0 -0.7112)
				)
			)
			(stroke
				(width 0)
				(type default)
			)
			(fill no)
			(layer "F.Fab")
		)
		(pad "1" smd circle
			(at 0 0 270)
			(size 0.8128 0.8128)
			(layers "F.Cu" "F.Mask" "F.Paste")
			(net "I2C_B_TMP2_ALERT")
		)
	)
	(footprint ""
		(layer "F.Cu")
		(at 209.422746 -52.0827 -90)
		(property "Reference" "TP4"
			(at 0 0 270)
			(layer "F.SilkS")
			(hide yes)
			(effects
				(font
					(size 1.27 1.27)
				)
			)
		)
		(property "Value" "TPAD32-GP"
			(at 0 -3.166364 270)
			(unlocked yes)
			(layer "F.Fab")
			(hide yes)
			(effects
				(font
					(size 1.016 1.016)
					(thickness 0.1524)
				)
			)
		)
		(property "Device Type" "TPAD32"
			(at 0 -4.690618 270)
			(unlocked yes)
			(layer "F.Fab")
			(hide yes)
			(effects
				(font
					(size 1.016 1.016)
					(thickness 0.1524)
				)
			)
		)
		(duplicate_pad_numbers_are_jumpers no)
		(fp_poly
			(pts
				(arc
					(start 0 -0.4064)
					(mid 0 0.4064)
					(end 0 -0.4064)
				)
			)
			(stroke
				(width 0)
				(type default)
			)
			(fill no)
			(layer "F.CrtYd")
		)
		(fp_poly
			(pts
				(arc
					(start 0 -0.7112)
					(mid 0 0.7112)
					(end 0 -0.7112)
				)
			)
			(stroke
				(width 0)
				(type default)
			)
			(fill no)
			(layer "F.Fab")
		)
		(pad "1" smd circle
			(at 0 0 270)
			(size 0.8128 0.8128)
			(layers "F.Cu" "F.Mask" "F.Paste")
			(net "I2C_B_TMP4_ALERT")
		)
	)
	(footprint ""
		(layer "F.Cu")
		(at 59.943746 -17.6657 90)
		(property "Reference" "PC16"
			(at 0 0 90)
			(layer "F.SilkS")
			(hide yes)
			(effects
				(font
					(size 1.27 1.27)
				)
			)
		)
		(property "Value" "SC22U25V5MX-GP"
			(at -0.0762 -6.1214 90)
			(unlocked yes)
			(layer "F.Fab")
			(hide yes)
			(effects
				(font
					(size 1.016 1.016)
					(thickness 0.1524)
				)
			)
		)
		(property "Device Type" "C805H58"
			(at -0.0762 -8.1534 90)
			(unlocked yes)
			(layer "F.Fab")
			(hide yes)
			(effects
				(font
					(size 1.016 1.016)
					(thickness 0.1524)
				)
			)
		)
		(duplicate_pad_numbers_are_jumpers no)
		(fp_line
			(start 0.635 0)
			(end -0.635 0)
			(stroke
				(width 0.508)
				(type default)
			)
			(layer "F.SilkS")
		)
		(fp_rect
			(start -0.9652 1.778)
			(end 0.9652 -1.778)
			(stroke
				(width 0)
				(type default)
			)
			(fill no)
			(layer "F.CrtYd")
		)
		(fp_poly
			(pts
				(xy -0.9652 -1.778) (xy 0.9652 -1.778) (xy 0.9652 1.778) (xy -0.9652 1.778)
			)
			(stroke
				(width 0)
				(type default)
			)
			(fill no)
			(layer "F.Fab")
		)
		(pad "1" smd rect
			(at 0 -0.9652 90)
			(size 1.397 1.143)
			(layers "F.Cu" "F.Mask" "F.Paste")
			(net "P5VB_12VIN")
		)
		(pad "2" smd rect
			(at 0 0.9652 90)
			(size 1.397 1.143)
			(layers "F.Cu" "F.Mask" "F.Paste")
			(net "GND")
		)
	)
	(footprint ""
		(layer "F.Cu")
		(at 39.623746 -144.7927 90)
		(property "Reference" "R213"
			(at 0 0 90)
			(layer "F.SilkS")
			(hide yes)
			(effects
				(font
					(size 1.27 1.27)
				)
			)
		)
		(property "Value" "402R2F-GP"
			(at 0.064008 -3.993896 90)
			(unlocked yes)
			(layer "F.Fab")
			(hide yes)
			(effects
				(font
					(size 1.016 1.016)
					(thickness 0.1524)
				)
			)
		)
		(property "Device Type" "R402H16"
			(at 0.064008 -5.517896 90)
			(unlocked yes)
			(layer "F.Fab")
			(hide yes)
			(effects
				(font
					(size 1.016 1.016)
					(thickness 0.1524)
				)
			)
		)
		(duplicate_pad_numbers_are_jumpers no)
		(fp_line
			(start 0.508 -0.9398)
			(end -0.508 -0.9398)
			(stroke
				(width 0.1524)
				(type default)
			)
			(layer "F.SilkS")
		)
		(fp_line
			(start -0.508 -0.9398)
			(end -0.508 0.9398)
			(stroke
				(width 0.1524)
				(type default)
			)
			(layer "F.SilkS")
		)
		(fp_rect
			(start -0.508 0.9398)
			(end 0.508 -0.9398)
			(stroke
				(width 0)
				(type default)
			)
			(fill no)
			(layer "F.CrtYd")
		)
		(fp_rect
			(start -0.508 0.9398)
			(end 0.508 -0.9398)
			(stroke
				(width 0)
				(type default)
			)
			(fill no)
			(layer "F.Fab")
		)
		(pad "1" smd custom
			(at 0 -0.4445 90)
			(size 0.1397 0.1397)
			(layers "F.Cu" "F.Mask" "F.Paste")
			(net "P5VB_HDD8_LED")
			(options
				(clearance outline)
				(anchor circle)
			)
			(primitives
				(gr_poly
					(pts
						(arc
							(start -0.1778 -0.2794)
							(mid -0.249642 -0.249642)
							(end -0.2794 -0.1778)
						)
						(arc
							(start -0.2794 0.1778)
							(mid -0.249642 0.249642)
							(end -0.1778 0.2794)
						)
						(arc
							(start 0.1778 0.2794)
							(mid 0.249642 0.249642)
							(end 0.2794 0.1778)
						)
						(arc
							(start 0.2794 -0.1778)
							(mid 0.249642 -0.249642)
							(end 0.1778 -0.2794)
						)
					)
					(width 0)
					(fill yes)
				)
			)
		)
		(pad "2" smd custom
			(at 0 0.4445 90)
			(size 0.1397 0.1397)
			(layers "F.Cu" "F.Mask" "F.Paste")
			(net "DRV_ACT_8")
			(options
				(clearance outline)
				(anchor circle)
			)
			(primitives
				(gr_poly
					(pts
						(arc
							(start -0.1778 -0.2794)
							(mid -0.249642 -0.249642)
							(end -0.2794 -0.1778)
						)
						(arc
							(start -0.2794 0.1778)
							(mid -0.249642 0.249642)
							(end -0.1778 0.2794)
						)
						(arc
							(start 0.1778 0.2794)
							(mid 0.249642 0.249642)
							(end 0.2794 0.1778)
						)
						(arc
							(start 0.2794 -0.1778)
							(mid 0.249642 -0.249642)
							(end 0.1778 -0.2794)
						)
					)
					(width 0)
					(fill yes)
				)
			)
		)
	)
	(footprint ""
		(layer "F.Cu")
		(at 33.273746 -263.0297 -90)
		(property "Reference" "C214"
			(at 0 0 270)
			(layer "F.SilkS")
			(hide yes)
			(effects
				(font
					(size 1.27 1.27)
				)
			)
		)
		(property "Value" "SCD01U50V2KX-1GP"
			(at 1.1811 -2.7051 270)
			(unlocked yes)
			(layer "F.Fab")
			(hide yes)
			(effects
				(font
					(size 1.016 1.016)
					(thickness 0.1524)
				)
			)
		)
		(property "Device Type" "C402H22"
			(at 1.1811 -4.2291 270)
			(unlocked yes)
			(layer "F.Fab")
			(hide yes)
			(effects
				(font
					(size 1.016 1.016)
					(thickness 0.1524)
				)
			)
		)
		(duplicate_pad_numbers_are_jumpers no)
		(fp_rect
			(start -0.4318 0.9525)
			(end 0.4318 -0.9525)
			(stroke
				(width 0)
				(type default)
			)
			(fill no)
			(layer "F.CrtYd")
		)
		(fp_rect
			(start -0.4318 0.9525)
			(end 0.4318 -0.9525)
			(stroke
				(width 0)
				(type default)
			)
			(fill no)
			(layer "F.Fab")
		)
		(pad "1" smd custom
			(at 0 -0.4445 270)
			(size 0.1524 0.1524)
			(layers "F.Cu" "F.Mask" "F.Paste")
			(net "SAS2X28_DRIVE_RX_N_A7")
			(options
				(clearance outline)
				(anchor circle)
			)
			(primitives
				(gr_poly
					(pts
						(arc
							(start 0.3048 -0.2032)
							(mid 0.275042 -0.275042)
							(end 0.2032 -0.3048)
						)
						(arc
							(start -0.2032 -0.3048)
							(mid -0.275042 -0.275042)
							(end -0.3048 -0.2032)
						)
						(arc
							(start -0.3048 0.2032)
							(mid -0.275042 0.275042)
							(end -0.2032 0.3048)
						)
						(arc
							(start 0.2032 0.3048)
							(mid 0.275042 0.275042)
							(end 0.3048 0.2032)
						)
					)
					(width 0)
					(fill yes)
				)
			)
		)
		(pad "2" smd custom
			(at 0 0.4445 270)
			(size 0.1524 0.1524)
			(layers "F.Cu" "F.Mask" "F.Paste")
			(net "SAS2X28_A_HDD7_RX_-")
			(options
				(clearance outline)
				(anchor circle)
			)
			(primitives
				(gr_poly
					(pts
						(arc
							(start 0.3048 -0.2032)
							(mid 0.275042 -0.275042)
							(end 0.2032 -0.3048)
						)
						(arc
							(start -0.2032 -0.3048)
							(mid -0.275042 -0.275042)
							(end -0.3048 -0.2032)
						)
						(arc
							(start -0.3048 0.2032)
							(mid -0.275042 0.275042)
							(end -0.2032 0.3048)
						)
						(arc
							(start 0.2032 0.3048)
							(mid 0.275042 0.275042)
							(end 0.3048 0.2032)
						)
					)
					(width 0)
					(fill yes)
				)
			)
		)
	)
	(footprint ""
		(layer "F.Cu")
		(at 49.021746 -348.7547 90)
		(property "Reference" "R188"
			(at 0 0 90)
			(layer "F.SilkS")
			(hide yes)
			(effects
				(font
					(size 1.27 1.27)
				)
			)
		)
		(property "Value" "0R2J-2-GP"
			(at 0.064008 -3.993896 90)
			(unlocked yes)
			(layer "F.Fab")
			(hide yes)
			(effects
				(font
					(size 1.016 1.016)
					(thickness 0.1524)
				)
			)
		)
		(property "Device Type" "R402H16"
			(at 0.064008 -5.517896 90)
			(unlocked yes)
			(layer "F.Fab")
			(hide yes)
			(effects
				(font
					(size 1.016 1.016)
					(thickness 0.1524)
				)
			)
		)
		(duplicate_pad_numbers_are_jumpers no)
		(fp_line
			(start 0.508 -0.9398)
			(end -0.508 -0.9398)
			(stroke
				(width 0.1524)
				(type default)
			)
			(layer "F.SilkS")
		)
		(fp_line
			(start -0.508 -0.9398)
			(end -0.508 0.9398)
			(stroke
				(width 0.1524)
				(type default)
			)
			(layer "F.SilkS")
		)
		(fp_rect
			(start -0.508 0.9398)
			(end 0.508 -0.9398)
			(stroke
				(width 0)
				(type default)
			)
			(fill no)
			(layer "F.CrtYd")
		)
		(fp_rect
			(start -0.508 0.9398)
			(end 0.508 -0.9398)
			(stroke
				(width 0)
				(type default)
			)
			(fill no)
			(layer "F.Fab")
		)
		(pad "1" smd custom
			(at 0 -0.4445 90)
			(size 0.1397 0.1397)
			(layers "F.Cu" "F.Mask" "F.Paste")
			(net "FLT_NET_HDD6")
			(options
				(clearance outline)
				(anchor circle)
			)
			(primitives
				(gr_poly
					(pts
						(arc
							(start -0.1778 -0.2794)
							(mid -0.249642 -0.249642)
							(end -0.2794 -0.1778)
						)
						(arc
							(start -0.2794 0.1778)
							(mid -0.249642 0.249642)
							(end -0.1778 0.2794)
						)
						(arc
							(start 0.1778 0.2794)
							(mid 0.249642 0.249642)
							(end 0.2794 0.1778)
						)
						(arc
							(start 0.2794 -0.1778)
							(mid 0.249642 -0.249642)
							(end 0.1778 -0.2794)
						)
					)
					(width 0)
					(fill yes)
				)
			)
		)
		(pad "2" smd custom
			(at 0 0.4445 90)
			(size 0.1397 0.1397)
			(layers "F.Cu" "F.Mask" "F.Paste")
			(net "FLT_HDD6_DRIVE")
			(options
				(clearance outline)
				(anchor circle)
			)
			(primitives
				(gr_poly
					(pts
						(arc
							(start -0.1778 -0.2794)
							(mid -0.249642 -0.249642)
							(end -0.2794 -0.1778)
						)
						(arc
							(start -0.2794 0.1778)
							(mid -0.249642 0.249642)
							(end -0.1778 0.2794)
						)
						(arc
							(start 0.1778 0.2794)
							(mid 0.249642 0.249642)
							(end 0.2794 0.1778)
						)
						(arc
							(start 0.2794 -0.1778)
							(mid 0.249642 -0.249642)
							(end 0.1778 -0.2794)
						)
					)
					(width 0)
					(fill yes)
				)
			)
		)
	)
	(footprint ""
		(layer "F.Cu")
		(at 197.357746 -286.3977 -90)
		(property "Reference" "R432"
			(at 0 0 270)
			(layer "F.SilkS")
			(hide yes)
			(effects
				(font
					(size 1.27 1.27)
				)
			)
		)
		(property "Value" "4K7R2J-2-GP"
			(at 0.064008 -3.993896 270)
			(unlocked yes)
			(layer "F.Fab")
			(hide yes)
			(effects
				(font
					(size 1.016 1.016)
					(thickness 0.1524)
				)
			)
		)
		(property "Device Type" "R402H16"
			(at 0.064008 -5.517896 270)
			(unlocked yes)
			(layer "F.Fab")
			(hide yes)
			(effects
				(font
					(size 1.016 1.016)
					(thickness 0.1524)
				)
			)
		)
		(duplicate_pad_numbers_are_jumpers no)
		(fp_line
			(start -0.508 -0.9398)
			(end -0.508 0.9398)
			(stroke
				(width 0.1524)
				(type default)
			)
			(layer "F.SilkS")
		)
		(fp_line
			(start 0.508 -0.9398)
			(end -0.508 -0.9398)
			(stroke
				(width 0.1524)
				(type default)
			)
			(layer "F.SilkS")
		)
		(fp_rect
			(start -0.508 0.9398)
			(end 0.508 -0.9398)
			(stroke
				(width 0)
				(type default)
			)
			(fill no)
			(layer "F.CrtYd")
		)
		(fp_rect
			(start -0.508 0.9398)
			(end 0.508 -0.9398)
			(stroke
				(width 0)
				(type default)
			)
			(fill no)
			(layer "F.Fab")
		)
		(pad "1" smd custom
			(at 0 -0.4445 270)
			(size 0.1397 0.1397)
			(layers "F.Cu" "F.Mask" "F.Paste")
			(net "P3V3")
			(options
				(clearance outline)
				(anchor circle)
			)
			(primitives
				(gr_poly
					(pts
						(arc
							(start -0.1778 -0.2794)
							(mid -0.249642 -0.249642)
							(end -0.2794 -0.1778)
						)
						(arc
							(start -0.2794 0.1778)
							(mid -0.249642 0.249642)
							(end -0.1778 0.2794)
						)
						(arc
							(start 0.1778 0.2794)
							(mid 0.249642 0.249642)
							(end 0.2794 0.1778)
						)
						(arc
							(start 0.2794 -0.1778)
							(mid 0.249642 -0.249642)
							(end 0.1778 -0.2794)
						)
					)
					(width 0)
					(fill yes)
				)
			)
		)
		(pad "2" smd custom
			(at 0 0.4445 270)
			(size 0.1397 0.1397)
			(layers "F.Cu" "F.Mask" "F.Paste")
			(net "SAS_EXP_A_PWR2")
			(options
				(clearance outline)
				(anchor circle)
			)
			(primitives
				(gr_poly
					(pts
						(arc
							(start -0.1778 -0.2794)
							(mid -0.249642 -0.249642)
							(end -0.2794 -0.1778)
						)
						(arc
							(start -0.2794 0.1778)
							(mid -0.249642 0.249642)
							(end -0.1778 0.2794)
						)
						(arc
							(start 0.1778 0.2794)
							(mid 0.249642 0.249642)
							(end 0.2794 0.1778)
						)
						(arc
							(start 0.2794 -0.1778)
							(mid 0.249642 -0.249642)
							(end 0.1778 -0.2794)
						)
					)
					(width 0)
					(fill yes)
				)
			)
		)
	)
	(footprint ""
		(layer "F.Cu")
		(at 71.500746 -190.5127)
		(property "Reference" "R452"
			(at 0 0 0)
			(layer "F.SilkS")
			(hide yes)
			(effects
				(font
					(size 1.27 1.27)
				)
			)
		)
		(property "Value" "4K7R2J-2-GP"
			(at 0.064008 -3.993896 0)
			(unlocked yes)
			(layer "F.Fab")
			(hide yes)
			(effects
				(font
					(size 1.016 1.016)
					(thickness 0.1524)
				)
			)
		)
		(property "Device Type" "R402H16"
			(at 0.064008 -5.517896 0)
			(unlocked yes)
			(layer "F.Fab")
			(hide yes)
			(effects
				(font
					(size 1.016 1.016)
					(thickness 0.1524)
				)
			)
		)
		(duplicate_pad_numbers_are_jumpers no)
		(fp_line
			(start -0.508 -0.9398)
			(end -0.508 0.9398)
			(stroke
				(width 0.1524)
				(type default)
			)
			(layer "F.SilkS")
		)
		(fp_line
			(start 0.508 -0.9398)
			(end -0.508 -0.9398)
			(stroke
				(width 0.1524)
				(type default)
			)
			(layer "F.SilkS")
		)
		(fp_rect
			(start -0.508 0.9398)
			(end 0.508 -0.9398)
			(stroke
				(width 0)
				(type default)
			)
			(fill no)
			(layer "F.CrtYd")
		)
		(fp_rect
			(start -0.508 0.9398)
			(end 0.508 -0.9398)
			(stroke
				(width 0)
				(type default)
			)
			(fill no)
			(layer "F.Fab")
		)
		(pad "1" smd custom
			(at 0 -0.4445)
			(size 0.1397 0.1397)
			(layers "F.Cu" "F.Mask" "F.Paste")
			(net "P3V3")
			(options
				(clearance outline)
				(anchor circle)
			)
			(primitives
				(gr_poly
					(pts
						(arc
							(start -0.1778 -0.2794)
							(mid -0.249642 -0.249642)
							(end -0.2794 -0.1778)
						)
						(arc
							(start -0.2794 0.1778)
							(mid -0.249642 0.249642)
							(end -0.1778 0.2794)
						)
						(arc
							(start 0.1778 0.2794)
							(mid 0.249642 0.249642)
							(end 0.2794 0.1778)
						)
						(arc
							(start 0.2794 -0.1778)
							(mid 0.249642 -0.249642)
							(end 0.1778 -0.2794)
						)
					)
					(width 0)
					(fill yes)
				)
			)
		)
		(pad "2" smd custom
			(at 0 0.4445)
			(size 0.1397 0.1397)
			(layers "F.Cu" "F.Mask" "F.Paste")
			(net "SAS2X28_A_HDD8_FLT")
			(options
				(clearance outline)
				(anchor circle)
			)
			(primitives
				(gr_poly
					(pts
						(arc
							(start -0.1778 -0.2794)
							(mid -0.249642 -0.249642)
							(end -0.2794 -0.1778)
						)
						(arc
							(start -0.2794 0.1778)
							(mid -0.249642 0.249642)
							(end -0.1778 0.2794)
						)
						(arc
							(start 0.1778 0.2794)
							(mid 0.249642 0.249642)
							(end 0.2794 0.1778)
						)
						(arc
							(start 0.2794 -0.1778)
							(mid 0.249642 -0.249642)
							(end 0.1778 -0.2794)
						)
					)
					(width 0)
					(fill yes)
				)
			)
		)
	)
	(footprint ""
		(layer "F.Cu")
		(at 207.009746 -42.4307 -90)
		(property "Reference" "R339"
			(at 0 0 270)
			(layer "F.SilkS")
			(hide yes)
			(effects
				(font
					(size 1.27 1.27)
				)
			)
		)
		(property "Value" "4K7R2J-2-GP"
			(at 0.064008 -3.993896 270)
			(unlocked yes)
			(layer "F.Fab")
			(hide yes)
			(effects
				(font
					(size 1.016 1.016)
					(thickness 0.1524)
				)
			)
		)
		(property "Device Type" "R402H16"
			(at 0.064008 -5.517896 270)
			(unlocked yes)
			(layer "F.Fab")
			(hide yes)
			(effects
				(font
					(size 1.016 1.016)
					(thickness 0.1524)
				)
			)
		)
		(duplicate_pad_numbers_are_jumpers no)
		(fp_line
			(start -0.508 -0.9398)
			(end -0.508 0.9398)
			(stroke
				(width 0.1524)
				(type default)
			)
			(layer "F.SilkS")
		)
		(fp_line
			(start 0.508 -0.9398)
			(end -0.508 -0.9398)
			(stroke
				(width 0.1524)
				(type default)
			)
			(layer "F.SilkS")
		)
		(fp_rect
			(start -0.508 0.9398)
			(end 0.508 -0.9398)
			(stroke
				(width 0)
				(type default)
			)
			(fill no)
			(layer "F.CrtYd")
		)
		(fp_rect
			(start -0.508 0.9398)
			(end 0.508 -0.9398)
			(stroke
				(width 0)
				(type default)
			)
			(fill no)
			(layer "F.Fab")
		)
		(pad "1" smd custom
			(at 0 -0.4445 270)
			(size 0.1397 0.1397)
			(layers "F.Cu" "F.Mask" "F.Paste")
			(net "I2C_B_TMP4_A2")
			(options
				(clearance outline)
				(anchor circle)
			)
			(primitives
				(gr_poly
					(pts
						(arc
							(start -0.1778 -0.2794)
							(mid -0.249642 -0.249642)
							(end -0.2794 -0.1778)
						)
						(arc
							(start -0.2794 0.1778)
							(mid -0.249642 0.249642)
							(end -0.1778 0.2794)
						)
						(arc
							(start 0.1778 0.2794)
							(mid 0.249642 0.249642)
							(end 0.2794 0.1778)
						)
						(arc
							(start 0.2794 -0.1778)
							(mid 0.249642 -0.249642)
							(end 0.1778 -0.2794)
						)
					)
					(width 0)
					(fill yes)
				)
			)
		)
		(pad "2" smd custom
			(at 0 0.4445 270)
			(size 0.1397 0.1397)
			(layers "F.Cu" "F.Mask" "F.Paste")
			(net "GND")
			(options
				(clearance outline)
				(anchor circle)
			)
			(primitives
				(gr_poly
					(pts
						(arc
							(start -0.1778 -0.2794)
							(mid -0.249642 -0.249642)
							(end -0.2794 -0.1778)
						)
						(arc
							(start -0.2794 0.1778)
							(mid -0.249642 0.249642)
							(end -0.1778 0.2794)
						)
						(arc
							(start 0.1778 0.2794)
							(mid 0.249642 0.249642)
							(end 0.2794 0.1778)
						)
						(arc
							(start 0.2794 -0.1778)
							(mid 0.249642 -0.249642)
							(end 0.1778 -0.2794)
						)
					)
					(width 0)
					(fill yes)
				)
			)
		)
	)
	(footprint ""
		(layer "F.Cu")
		(at 197.611746 -82.9437 -90)
		(property "Reference" "R440"
			(at 0 0 270)
			(layer "F.SilkS")
			(hide yes)
			(effects
				(font
					(size 1.27 1.27)
				)
			)
		)
		(property "Value" "4K7R2J-2-GP"
			(at 0.064008 -3.993896 270)
			(unlocked yes)
			(layer "F.Fab")
			(hide yes)
			(effects
				(font
					(size 1.016 1.016)
					(thickness 0.1524)
				)
			)
		)
		(property "Device Type" "R402H16"
			(at 0.064008 -5.517896 270)
			(unlocked yes)
			(layer "F.Fab")
			(hide yes)
			(effects
				(font
					(size 1.016 1.016)
					(thickness 0.1524)
				)
			)
		)
		(duplicate_pad_numbers_are_jumpers no)
		(fp_line
			(start -0.508 -0.9398)
			(end -0.508 0.9398)
			(stroke
				(width 0.1524)
				(type default)
			)
			(layer "F.SilkS")
		)
		(fp_line
			(start 0.508 -0.9398)
			(end -0.508 -0.9398)
			(stroke
				(width 0.1524)
				(type default)
			)
			(layer "F.SilkS")
		)
		(fp_rect
			(start -0.508 0.9398)
			(end 0.508 -0.9398)
			(stroke
				(width 0)
				(type default)
			)
			(fill no)
			(layer "F.CrtYd")
		)
		(fp_rect
			(start -0.508 0.9398)
			(end 0.508 -0.9398)
			(stroke
				(width 0)
				(type default)
			)
			(fill no)
			(layer "F.Fab")
		)
		(pad "1" smd custom
			(at 0 -0.4445 270)
			(size 0.1397 0.1397)
			(layers "F.Cu" "F.Mask" "F.Paste")
			(net "P3V3")
			(options
				(clearance outline)
				(anchor circle)
			)
			(primitives
				(gr_poly
					(pts
						(arc
							(start -0.1778 -0.2794)
							(mid -0.249642 -0.249642)
							(end -0.2794 -0.1778)
						)
						(arc
							(start -0.2794 0.1778)
							(mid -0.249642 0.249642)
							(end -0.1778 0.2794)
						)
						(arc
							(start 0.1778 0.2794)
							(mid 0.249642 0.249642)
							(end 0.2794 0.1778)
						)
						(arc
							(start 0.2794 -0.1778)
							(mid 0.249642 -0.249642)
							(end 0.1778 -0.2794)
						)
					)
					(width 0)
					(fill yes)
				)
			)
		)
		(pad "2" smd custom
			(at 0 0.4445 270)
			(size 0.1397 0.1397)
			(layers "F.Cu" "F.Mask" "F.Paste")
			(net "SAS_EXP_A_PWR4")
			(options
				(clearance outline)
				(anchor circle)
			)
			(primitives
				(gr_poly
					(pts
						(arc
							(start -0.1778 -0.2794)
							(mid -0.249642 -0.249642)
							(end -0.2794 -0.1778)
						)
						(arc
							(start -0.2794 0.1778)
							(mid -0.249642 0.249642)
							(end -0.1778 0.2794)
						)
						(arc
							(start 0.1778 0.2794)
							(mid 0.249642 0.249642)
							(end 0.2794 0.1778)
						)
						(arc
							(start 0.2794 -0.1778)
							(mid 0.249642 -0.249642)
							(end 0.1778 -0.2794)
						)
					)
					(width 0)
					(fill yes)
				)
			)
		)
	)
	(footprint ""
		(layer "F.Cu")
		(at 215.568784 -179.929028 180)
		(property "Reference" "C155"
			(at 0 0 180)
			(layer "F.SilkS")
			(hide yes)
			(effects
				(font
					(size 1.27 1.27)
				)
			)
		)
		(property "Value" "SC10U16V6KX-2GP"
			(at -0.0762 -5.1308 180)
			(unlocked yes)
			(layer "F.Fab")
			(hide yes)
			(effects
				(font
					(size 1.016 1.016)
					(thickness 0.1524)
				)
			)
		)
		(property "Device Type" "C1206H71"
			(at -0.127 -6.6548 180)
			(unlocked yes)
			(layer "F.Fab")
			(hide yes)
			(effects
				(font
					(size 1.016 1.016)
					(thickness 0.1524)
				)
			)
		)
		(duplicate_pad_numbers_are_jumpers no)
		(fp_line
			(start 1.016 2.2352)
			(end -1.016 2.2352)
			(stroke
				(width 0.1524)
				(type default)
			)
			(layer "F.SilkS")
		)
		(fp_line
			(start 1.016 0.8382)
			(end 1.016 2.2352)
			(stroke
				(width 0.1524)
				(type default)
			)
			(layer "F.SilkS")
		)
		(fp_line
			(start 1.016 -2.2352)
			(end 1.016 -0.8382)
			(stroke
				(width 0.1524)
				(type default)
			)
			(layer "F.SilkS")
		)
		(fp_line
			(start -1.016 2.2352)
			(end -1.016 0.8382)
			(stroke
				(width 0.1524)
				(type default)
			)
			(layer "F.SilkS")
		)
		(fp_line
			(start -1.016 -0.8382)
			(end -1.016 -2.2352)
			(stroke
				(width 0.1524)
				(type default)
			)
			(layer "F.SilkS")
		)
		(fp_line
			(start -1.016 -2.2352)
			(end 1.016 -2.2352)
			(stroke
				(width 0.1524)
				(type default)
			)
			(layer "F.SilkS")
		)
		(fp_rect
			(start -1.0922 2.3114)
			(end 1.0922 -2.3114)
			(stroke
				(width 0)
				(type default)
			)
			(fill no)
			(layer "F.CrtYd")
		)
		(fp_poly
			(pts
				(xy 1.0922 -2.3114) (xy 1.0922 2.3114) (xy -1.0922 2.3114) (xy -1.0922 -2.3114)
			)
			(stroke
				(width 0)
				(type default)
			)
			(fill no)
			(layer "F.Fab")
		)
		(pad "1" smd rect
			(at 0 -1.397 180)
			(size 1.651 1.27)
			(layers "F.Cu" "F.Mask" "F.Paste")
			(net "P5V_HDD3")
		)
		(pad "2" smd rect
			(at 0 1.397 180)
			(size 1.651 1.27)
			(layers "F.Cu" "F.Mask" "F.Paste")
			(net "GND")
		)
	)
	(footprint ""
		(layer "F.Cu")
		(at 42.500042 -479.67011 90)
		(property "Reference" "SKT6"
			(at 0 0 90)
			(layer "F.SilkS")
			(hide yes)
			(effects
				(font
					(size 1.27 1.27)
				)
			)
		)
		(property "Value" "SKT-SATA14P-15P-12-GP"
			(at -22.6187 8.1788 90)
			(unlocked yes)
			(layer "F.Fab")
			(hide yes)
			(effects
				(font
					(size 1.016 1.016)
					(thickness 0.1524)
				)
			)
		)
		(property "Device Type" "87945-1001"
			(at -22.6187 6.6548 90)
			(unlocked yes)
			(layer "F.Fab")
			(hide yes)
			(effects
				(font
					(size 1.016 1.016)
					(thickness 0.1524)
				)
			)
		)
		(duplicate_pad_numbers_are_jumpers no)
		(fp_line
			(start -15.3924 -5.8547)
			(end -16.3576 -5.8547)
			(stroke
				(width 0.3302)
				(type default)
			)
			(layer "F.SilkS")
		)
		(fp_line
			(start 20.4724 -5.7658)
			(end 20.4724 -2.3114)
			(stroke
				(width 0.1524)
				(type default)
			)
			(layer "F.SilkS")
		)
		(fp_line
			(start -20.4724 -5.7658)
			(end 20.4724 -5.7658)
			(stroke
				(width 0.1524)
				(type default)
			)
			(layer "F.SilkS")
		)
		(fp_line
			(start 23.7617 -2.3114)
			(end 23.7617 2.3114)
			(stroke
				(width 0.1524)
				(type default)
			)
			(layer "F.SilkS")
		)
		(fp_line
			(start 20.4724 -2.3114)
			(end 23.7617 -2.3114)
			(stroke
				(width 0.1524)
				(type default)
			)
			(layer "F.SilkS")
		)
		(fp_line
			(start -20.4724 -2.3114)
			(end -20.4724 -5.7658)
			(stroke
				(width 0.1524)
				(type default)
			)
			(layer "F.SilkS")
		)
		(fp_line
			(start -23.7617 -2.3114)
			(end -20.4724 -2.3114)
			(stroke
				(width 0.1524)
				(type default)
			)
			(layer "F.SilkS")
		)
		(fp_line
			(start 23.117556 -0.5461)
			(end 23.117556 0.5461)
			(stroke
				(width 0.3048)
				(type default)
			)
			(layer "F.SilkS")
		)
		(fp_line
			(start -20.882356 -0.5461)
			(end -20.882356 0.5461)
			(stroke
				(width 0.3048)
				(type default)
			)
			(layer "F.SilkS")
		)
		(fp_line
			(start 20.882356 0.5461)
			(end 20.882356 -0.5461)
			(stroke
				(width 0.3048)
				(type default)
			)
			(layer "F.SilkS")
		)
		(fp_line
			(start -23.117556 0.5461)
			(end -23.117556 -0.5461)
			(stroke
				(width 0.3048)
				(type default)
			)
			(layer "F.SilkS")
		)
		(fp_line
			(start 23.7617 2.3114)
			(end 20.4724 2.3114)
			(stroke
				(width 0.1524)
				(type default)
			)
			(layer "F.SilkS")
		)
		(fp_line
			(start 20.4724 2.3114)
			(end 20.4724 9.652)
			(stroke
				(width 0.1524)
				(type default)
			)
			(layer "F.SilkS")
		)
		(fp_line
			(start -20.4724 2.3114)
			(end -23.7617 2.3114)
			(stroke
				(width 0.1524)
				(type default)
			)
			(layer "F.SilkS")
		)
		(fp_line
			(start -23.7617 2.3114)
			(end -23.7617 -2.3114)
			(stroke
				(width 0.1524)
				(type default)
			)
			(layer "F.SilkS")
		)
		(fp_line
			(start 17.8435 7.9502)
			(end -17.8435 7.9502)
			(stroke
				(width 0.1524)
				(type default)
			)
			(layer "F.SilkS")
		)
		(fp_line
			(start -17.8435 7.9502)
			(end -17.8435 9.652)
			(stroke
				(width 0.1524)
				(type default)
			)
			(layer "F.SilkS")
		)
		(fp_line
			(start 20.4724 9.652)
			(end 17.8435 9.652)
			(stroke
				(width 0.1524)
				(type default)
			)
			(layer "F.SilkS")
		)
		(fp_line
			(start 17.8435 9.652)
			(end 17.8435 7.9502)
			(stroke
				(width 0.1524)
				(type default)
			)
			(layer "F.SilkS")
		)
		(fp_line
			(start -17.8435 9.652)
			(end -20.4724 9.652)
			(stroke
				(width 0.1524)
				(type default)
			)
			(layer "F.SilkS")
		)
		(fp_line
			(start -20.4724 9.652)
			(end -20.4724 2.3114)
			(stroke
				(width 0.1524)
				(type default)
			)
			(layer "F.SilkS")
		)
		(fp_arc
			(start 20.882356 -0.5461)
			(mid 21.999956 -1.6637)
			(end 23.117556 -0.5461)
			(stroke
				(width 0.3048)
				(type default)
			)
			(layer "F.SilkS")
		)
		(fp_arc
			(start -23.117556 -0.5461)
			(mid -21.999956 -1.6637)
			(end -20.882356 -0.5461)
			(stroke
				(width 0.3048)
				(type default)
			)
			(layer "F.SilkS")
		)
		(fp_arc
			(start 23.117556 0.5461)
			(mid 21.999956 1.6637)
			(end 20.882356 0.5461)
			(stroke
				(width 0.3048)
				(type default)
			)
			(layer "F.SilkS")
		)
		(fp_arc
			(start -20.882356 0.5461)
			(mid -21.999956 1.6637)
			(end -23.117556 0.5461)
			(stroke
				(width 0.3048)
				(type default)
			)
			(layer "F.SilkS")
		)
		(fp_poly
			(pts
				(xy -15.87119 -5.838698) (xy -15.23619 -6.473698) (xy -16.50619 -6.473698)
			)
			(stroke
				(width 0)
				(type default)
			)
			(fill yes)
			(layer "F.SilkS")
		)
		(fp_poly
			(pts
				(xy -20.2184 -5.5118) (xy 20.2184 -5.5118) (xy 20.2184 -2.0574) (xy 23.5077 -2.0574) (xy 23.5077 2.0574)
				(xy 20.2184 2.0574) (xy 20.2184 9.398) (xy 18.0975 9.398) (xy 18.0975 7.6962) (xy -18.0975 7.6962)
				(xy -18.0975 9.398) (xy -20.2184 9.398) (xy -20.2184 2.0574) (xy -23.5077 2.0574) (xy -23.5077 -2.0574)
				(xy -20.2184 -2.0574)
			)
			(stroke
				(width 0)
				(type default)
			)
			(fill no)
			(layer "F.CrtYd")
		)
		(fp_poly
			(pts
				(xy -20.2184 -5.5118) (xy -20.2184 -6.0198) (xy -20.7264 -6.0198) (xy -20.7264 -2.5654) (xy -24.0157 -2.5654)
				(xy -24.0157 2.5654) (xy -20.7264 2.5654) (xy -20.7264 9.906) (xy -17.5895 9.906) (xy -17.5895 8.2042)
				(xy 17.5895 8.2042) (xy 17.5895 9.906) (xy 20.7264 9.906) (xy 20.7264 2.5654) (xy 24.0157 2.5654)
				(xy 24.0157 -2.5654) (xy 20.7264 -2.5654) (xy 20.7264 -6.0198) (xy -20.21586 -6.0198) (xy -20.21586 -5.5118)
				(xy 20.2184 -5.5118) (xy 20.2184 -2.0574) (xy 23.5077 -2.0574) (xy 23.5077 2.0574) (xy 20.2184 2.0574)
				(xy 20.2184 9.398) (xy 18.0975 9.398) (xy 18.0975 7.6962) (xy -18.0975 7.6962) (xy -18.0975 9.398)
				(xy -20.2184 9.398) (xy -20.2184 2.0574) (xy -23.5077 2.0574) (xy -23.5077 -2.0574) (xy -20.2184 -2.0574)
			)
			(stroke
				(width 0)
				(type default)
			)
			(fill no)
			(layer "F.CrtYd")
		)
		(fp_poly
			(pts
				(xy -20.7264 -6.0198) (xy -20.7264 -2.5654) (xy -24.0157 -2.5654) (xy -24.0157 2.5654) (xy -20.7264 2.5654)
				(xy -20.7264 9.906) (xy -17.5895 9.906) (xy -17.5895 8.2042) (xy 17.5895 8.2042) (xy 17.5895 9.906)
				(xy 20.7264 9.906) (xy 20.7264 2.5654) (xy 24.0157 2.5654) (xy 24.0157 -2.5654) (xy 20.7264 -2.5654)
				(xy 20.7264 -6.0198)
			)
			(stroke
				(width 0)
				(type default)
			)
			(fill no)
			(layer "F.Fab")
		)
		(pad "" np_thru_hole circle
			(at -18.999962 -2.350008 90)
			(size 0.254 0.254)
			(drill 1.8542)
			(layers "*.Cu" "*.Mask")
			(clearance 1.1557)
			(thermal_gap 1.1557)
		)
		(pad "" np_thru_hole circle
			(at 18.999962 -2.350008 90)
			(size 0.254 0.254)
			(drill 1.8542)
			(layers "*.Cu" "*.Mask")
			(clearance 1.1557)
			(thermal_gap 1.1557)
		)
		(pad "H1" thru_hole oval
			(at -21.999956 0 90)
			(size 1.524 2.6162)
			(drill oval 0.8128 1.905)
			(layers "*.Cu" "*.Mask")
			(remove_unused_layers no)
			(net "GND")
			(clearance 0.1524)
			(thermal_gap 0.1524)
		)
		(pad "H2" thru_hole oval
			(at 21.999956 0 90)
			(size 1.524 2.6162)
			(drill oval 0.8128 1.905)
			(layers "*.Cu" "*.Mask")
			(remove_unused_layers no)
			(net "GND")
			(clearance 0.1524)
			(thermal_gap 0.1524)
		)
		(pad "P1" smd rect
			(at -1.89992 -4.249928 90)
			(size 0.6604 2.3876)
			(layers "F.Cu" "F.Mask" "F.Paste")
			(net "Net_20")
		)
		(pad "P2" smd rect
			(at -0.62992 -4.249928 90)
			(size 0.6604 2.3876)
			(layers "F.Cu" "F.Mask" "F.Paste")
			(net "Net_19")
		)
		(pad "P3" smd rect
			(at 0.64008 -4.249928 90)
			(size 0.6604 2.3876)
			(layers "F.Cu" "F.Mask" "F.Paste")
			(net "Net_18")
		)
		(pad "P4" smd rect
			(at 1.91008 -4.249928 90)
			(size 0.6604 2.3876)
			(layers "F.Cu" "F.Mask" "F.Paste")
			(net "GND")
		)
		(pad "P5" smd rect
			(at 3.18008 -4.249928 90)
			(size 0.6604 2.3876)
			(layers "F.Cu" "F.Mask" "F.Paste")
			(net "HDD_PRSNT_NET5")
		)
		(pad "P6" smd rect
			(at 4.45008 -4.249928 90)
			(size 0.6604 2.3876)
			(layers "F.Cu" "F.Mask" "F.Paste")
			(net "GND")
		)
		(pad "P7" smd rect
			(at 5.72008 -4.249928 90)
			(size 0.6604 2.3876)
			(layers "F.Cu" "F.Mask" "F.Paste")
			(net "5V_PRE_5")
		)
		(pad "P8" smd rect
			(at 6.99008 -4.249928 90)
			(size 0.6604 2.3876)
			(layers "F.Cu" "F.Mask" "F.Paste")
			(net "P5V_HDD5")
		)
		(pad "P9" smd rect
			(at 8.26008 -4.249928 90)
			(size 0.6604 2.3876)
			(layers "F.Cu" "F.Mask" "F.Paste")
			(net "P5V_HDD5")
		)
		(pad "P10" smd rect
			(at 9.53008 -4.249928 90)
			(size 0.6604 2.3876)
			(layers "F.Cu" "F.Mask" "F.Paste")
			(net "GND")
		)
		(pad "P11" smd rect
			(at 10.80008 -4.249928 90)
			(size 0.6604 2.3876)
			(layers "F.Cu" "F.Mask" "F.Paste")
			(net "ACT_HDD5")
		)
		(pad "P12" smd rect
			(at 12.07008 -4.249928 90)
			(size 0.6604 2.3876)
			(layers "F.Cu" "F.Mask" "F.Paste")
			(net "GND")
		)
		(pad "P13" smd rect
			(at 13.34008 -4.249928 90)
			(size 0.6604 2.3876)
			(layers "F.Cu" "F.Mask" "F.Paste")
			(net "12V_PRE_5")
		)
		(pad "P14" smd rect
			(at 14.61008 -4.249928 90)
			(size 0.6604 2.3876)
			(layers "F.Cu" "F.Mask" "F.Paste")
			(net "P12V_HDD5")
		)
		(pad "P15" smd rect
			(at 15.88008 -4.249928 90)
			(size 0.6604 2.3876)
			(layers "F.Cu" "F.Mask" "F.Paste")
			(net "P12V_HDD5")
		)
		(pad "S1" smd rect
			(at -15.86992 -4.249928 90)
			(size 0.6604 2.3876)
			(layers "F.Cu" "F.Mask" "F.Paste")
			(net "GND")
		)
		(pad "S2" smd rect
			(at -14.59992 -4.249928 90)
			(size 0.6604 2.3876)
			(layers "F.Cu" "F.Mask" "F.Paste")
			(net "SAS2X28_A_HDD5_TX_+")
		)
		(pad "S3" smd rect
			(at -13.32992 -4.249928 90)
			(size 0.6604 2.3876)
			(layers "F.Cu" "F.Mask" "F.Paste")
			(net "SAS2X28_A_HDD5_TX_-")
		)
		(pad "S4" smd rect
			(at -12.05992 -4.249928 90)
			(size 0.6604 2.3876)
			(layers "F.Cu" "F.Mask" "F.Paste")
			(net "GND")
		)
		(pad "S5" smd rect
			(at -10.78992 -4.249928 90)
			(size 0.6604 2.3876)
			(layers "F.Cu" "F.Mask" "F.Paste")
			(net "SAS2X28_DRIVE_RX_N_A5")
		)
		(pad "S6" smd rect
			(at -9.51992 -4.249928 90)
			(size 0.6604 2.3876)
			(layers "F.Cu" "F.Mask" "F.Paste")
			(net "SAS2X28_DRIVE_RX_P_A5")
		)
		(pad "S7" smd rect
			(at -8.24992 -4.249928 90)
			(size 0.6604 2.3876)
			(layers "F.Cu" "F.Mask" "F.Paste")
			(net "GND")
		)
		(pad "S8" smd rect
			(at -7.480046 -2.100072 90)
			(size 0.508 1.905)
			(layers "F.Cu" "F.Mask" "F.Paste")
			(net "GND")
		)
		(pad "S9" smd rect
			(at -6.679946 -2.100072 90)
			(size 0.508 1.905)
			(layers "F.Cu" "F.Mask" "F.Paste")
			(net "SAS2X28_B_HDD5_TX_+")
		)
		(pad "S10" smd rect
			(at -5.8801 -2.100072 90)
			(size 0.508 1.905)
			(layers "F.Cu" "F.Mask" "F.Paste")
			(net "SAS2X28_B_HDD5_TX_-")
		)
		(pad "S11" smd rect
			(at -5.08 -2.100072 90)
			(size 0.508 1.905)
			(layers "F.Cu" "F.Mask" "F.Paste")
			(net "GND")
		)
		(pad "S12" smd rect
			(at -4.2799 -2.100072 90)
			(size 0.508 1.905)
			(layers "F.Cu" "F.Mask" "F.Paste")
			(net "SAS2X28_DRIVE_RX_N_B5")
		)
		(pad "S13" smd rect
			(at -3.480054 -2.100072 90)
			(size 0.508 1.905)
			(layers "F.Cu" "F.Mask" "F.Paste")
			(net "SAS2X28_DRIVE_RX_P_B5")
		)
		(pad "S14" smd rect
			(at -2.679954 -2.100072 90)
			(size 0.508 1.905)
			(layers "F.Cu" "F.Mask" "F.Paste")
			(net "GND")
		)
		(zone
			(layers "F.Cu" "B.Cu" "In1.Cu" "In2.Cu" "In3.Cu" "In4.Cu" "In5.Cu" "In6.Cu")
			(hatch none 0.5)
			(connect_pads
				(clearance 0)
			)
			(min_thickness 0.25)
			(keepout
				(tracks not_allowed)
				(vias allowed)
				(pads allowed)
				(copperpour not_allowed)
				(footprints allowed)
			)
			(placement
				(enabled no)
				(sheetname "")
			)
			(fill
				(thermal_gap 0.5)
				(thermal_bridge_width 0.5)
				(island_removal_mode 0)
			)
			(polygon
				(pts
					(arc
						(start 41.381934 -498.670072)
						(mid 38.918134 -498.670072)
						(end 41.381934 -498.670072)
					)
				)
			)
		)
		(zone
			(layers "F.Cu" "B.Cu" "In1.Cu" "In2.Cu" "In3.Cu" "In4.Cu" "In5.Cu" "In6.Cu")
			(hatch none 0.5)
			(connect_pads
				(clearance 0)
			)
			(min_thickness 0.25)
			(keepout
				(tracks not_allowed)
				(vias allowed)
				(pads allowed)
				(copperpour not_allowed)
				(footprints allowed)
			)
			(placement
				(enabled no)
				(sheetname "")
			)
			(fill
				(thermal_gap 0.5)
				(thermal_bridge_width 0.5)
				(island_removal_mode 0)
			)
			(polygon
				(pts
					(arc
						(start 41.381934 -460.670148)
						(mid 38.918134 -460.670148)
						(end 41.381934 -460.670148)
					)
				)
			)
		)
	)
	(footprint ""
		(layer "F.Cu")
		(at 242.569746 -16.2687 90)
		(property "Reference" "PC4"
			(at 0 0 90)
			(layer "F.SilkS")
			(hide yes)
			(effects
				(font
					(size 1.27 1.27)
				)
			)
		)
		(property "Value" "SC22U25V5MX-GP"
			(at -0.0762 -6.1214 90)
			(unlocked yes)
			(layer "F.Fab")
			(hide yes)
			(effects
				(font
					(size 1.016 1.016)
					(thickness 0.1524)
				)
			)
		)
		(property "Device Type" "C805H58"
			(at -0.0762 -8.1534 90)
			(unlocked yes)
			(layer "F.Fab")
			(hide yes)
			(effects
				(font
					(size 1.016 1.016)
					(thickness 0.1524)
				)
			)
		)
		(duplicate_pad_numbers_are_jumpers no)
		(fp_line
			(start 0.635 0)
			(end -0.635 0)
			(stroke
				(width 0.508)
				(type default)
			)
			(layer "F.SilkS")
		)
		(fp_rect
			(start -0.9652 1.778)
			(end 0.9652 -1.778)
			(stroke
				(width 0)
				(type default)
			)
			(fill no)
			(layer "F.CrtYd")
		)
		(fp_poly
			(pts
				(xy -0.9652 -1.778) (xy 0.9652 -1.778) (xy 0.9652 1.778) (xy -0.9652 1.778)
			)
			(stroke
				(width 0)
				(type default)
			)
			(fill no)
			(layer "F.Fab")
		)
		(pad "1" smd rect
			(at 0 -0.9652 90)
			(size 1.397 1.143)
			(layers "F.Cu" "F.Mask" "F.Paste")
			(net "P5VA_12VIN")
		)
		(pad "2" smd rect
			(at 0 0.9652 90)
			(size 1.397 1.143)
			(layers "F.Cu" "F.Mask" "F.Paste")
			(net "GND")
		)
	)
	(footprint ""
		(layer "F.Cu")
		(at 98.933 -18.796 180)
		(property "Reference" "C339"
			(at 0 0 180)
			(layer "F.SilkS")
			(hide yes)
			(effects
				(font
					(size 1.27 1.27)
				)
			)
		)
		(property "Value" "SCD1U10V2KX-5GP"
			(at 1.1811 -2.7051 180)
			(unlocked yes)
			(layer "F.Fab")
			(hide yes)
			(effects
				(font
					(size 1.016 1.016)
					(thickness 0.1524)
				)
			)
		)
		(property "Device Type" "C402H22"
			(at 1.1811 -4.2291 180)
			(unlocked yes)
			(layer "F.Fab")
			(hide yes)
			(effects
				(font
					(size 1.016 1.016)
					(thickness 0.1524)
				)
			)
		)
		(duplicate_pad_numbers_are_jumpers no)
		(fp_rect
			(start -0.4318 0.9525)
			(end 0.4318 -0.9525)
			(stroke
				(width 0)
				(type default)
			)
			(fill no)
			(layer "F.CrtYd")
		)
		(fp_rect
			(start -0.4318 0.9525)
			(end 0.4318 -0.9525)
			(stroke
				(width 0)
				(type default)
			)
			(fill no)
			(layer "F.Fab")
		)
		(pad "1" smd custom
			(at 0 -0.4445 180)
			(size 0.1524 0.1524)
			(layers "F.Cu" "F.Mask" "F.Paste")
			(net "P3V3")
			(options
				(clearance outline)
				(anchor circle)
			)
			(primitives
				(gr_poly
					(pts
						(arc
							(start 0.3048 -0.2032)
							(mid 0.275042 -0.275042)
							(end 0.2032 -0.3048)
						)
						(arc
							(start -0.2032 -0.3048)
							(mid -0.275042 -0.275042)
							(end -0.3048 -0.2032)
						)
						(arc
							(start -0.3048 0.2032)
							(mid -0.275042 0.275042)
							(end -0.2032 0.3048)
						)
						(arc
							(start 0.2032 0.3048)
							(mid 0.275042 0.275042)
							(end 0.3048 0.2032)
						)
					)
					(width 0)
					(fill yes)
				)
			)
		)
		(pad "2" smd custom
			(at 0 0.4445 180)
			(size 0.1524 0.1524)
			(layers "F.Cu" "F.Mask" "F.Paste")
			(net "GND")
			(options
				(clearance outline)
				(anchor circle)
			)
			(primitives
				(gr_poly
					(pts
						(arc
							(start 0.3048 -0.2032)
							(mid 0.275042 -0.275042)
							(end 0.2032 -0.3048)
						)
						(arc
							(start -0.2032 -0.3048)
							(mid -0.275042 -0.275042)
							(end -0.3048 -0.2032)
						)
						(arc
							(start -0.3048 0.2032)
							(mid -0.275042 0.275042)
							(end -0.2032 0.3048)
						)
						(arc
							(start 0.2032 0.3048)
							(mid 0.275042 0.275042)
							(end 0.3048 0.2032)
						)
					)
					(width 0)
					(fill yes)
				)
			)
		)
	)
	(footprint ""
		(layer "F.Cu")
		(at 163.588446 -458.631036 180)
		(property "Reference" "R390"
			(at 0 0 180)
			(layer "F.SilkS")
			(hide yes)
			(effects
				(font
					(size 1.27 1.27)
				)
			)
		)
		(property "Value" "10KR2F-2-GP"
			(at 0.064008 -3.993896 180)
			(unlocked yes)
			(layer "F.Fab")
			(hide yes)
			(effects
				(font
					(size 1.016 1.016)
					(thickness 0.1524)
				)
			)
		)
		(property "Device Type" "R402H16"
			(at 0.064008 -5.517896 180)
			(unlocked yes)
			(layer "F.Fab")
			(hide yes)
			(effects
				(font
					(size 1.016 1.016)
					(thickness 0.1524)
				)
			)
		)
		(duplicate_pad_numbers_are_jumpers no)
		(fp_line
			(start 0.508 -0.9398)
			(end -0.508 -0.9398)
			(stroke
				(width 0.1524)
				(type default)
			)
			(layer "F.SilkS")
		)
		(fp_line
			(start -0.508 -0.9398)
			(end -0.508 0.9398)
			(stroke
				(width 0.1524)
				(type default)
			)
			(layer "F.SilkS")
		)
		(fp_rect
			(start -0.508 0.9398)
			(end 0.508 -0.9398)
			(stroke
				(width 0)
				(type default)
			)
			(fill no)
			(layer "F.CrtYd")
		)
		(fp_rect
			(start -0.508 0.9398)
			(end 0.508 -0.9398)
			(stroke
				(width 0)
				(type default)
			)
			(fill no)
			(layer "F.Fab")
		)
		(pad "1" smd custom
			(at 0 -0.4445 180)
			(size 0.1397 0.1397)
			(layers "F.Cu" "F.Mask" "F.Paste")
			(net "P5VA_DIV")
			(options
				(clearance outline)
				(anchor circle)
			)
			(primitives
				(gr_poly
					(pts
						(arc
							(start -0.1778 -0.2794)
							(mid -0.249642 -0.249642)
							(end -0.2794 -0.1778)
						)
						(arc
							(start -0.2794 0.1778)
							(mid -0.249642 0.249642)
							(end -0.1778 0.2794)
						)
						(arc
							(start 0.1778 0.2794)
							(mid 0.249642 0.249642)
							(end 0.2794 0.1778)
						)
						(arc
							(start 0.2794 -0.1778)
							(mid 0.249642 -0.249642)
							(end 0.1778 -0.2794)
						)
					)
					(width 0)
					(fill yes)
				)
			)
		)
		(pad "2" smd custom
			(at 0 0.4445 180)
			(size 0.1397 0.1397)
			(layers "F.Cu" "F.Mask" "F.Paste")
			(net "GND")
			(options
				(clearance outline)
				(anchor circle)
			)
			(primitives
				(gr_poly
					(pts
						(arc
							(start -0.1778 -0.2794)
							(mid -0.249642 -0.249642)
							(end -0.2794 -0.1778)
						)
						(arc
							(start -0.2794 0.1778)
							(mid -0.249642 0.249642)
							(end -0.1778 0.2794)
						)
						(arc
							(start 0.1778 0.2794)
							(mid 0.249642 0.249642)
							(end 0.2794 0.1778)
						)
						(arc
							(start 0.2794 -0.1778)
							(mid 0.249642 -0.249642)
							(end 0.1778 -0.2794)
						)
					)
					(width 0)
					(fill yes)
				)
			)
		)
	)
	(footprint ""
		(layer "F.Cu")
		(at 10.8458 -104.2924)
		(property "Reference" "R407"
			(at 0 0 0)
			(layer "F.SilkS")
			(hide yes)
			(effects
				(font
					(size 1.27 1.27)
				)
			)
		)
		(property "Value" "100R2J-2-GP"
			(at 0.064008 -3.993896 0)
			(unlocked yes)
			(layer "F.Fab")
			(hide yes)
			(effects
				(font
					(size 1.016 1.016)
					(thickness 0.1524)
				)
			)
		)
		(property "Device Type" "R402H14"
			(at 0.064008 -5.517896 0)
			(unlocked yes)
			(layer "F.Fab")
			(hide yes)
			(effects
				(font
					(size 1.016 1.016)
					(thickness 0.1524)
				)
			)
		)
		(duplicate_pad_numbers_are_jumpers no)
		(fp_line
			(start -0.508 -0.9398)
			(end -0.508 0.9398)
			(stroke
				(width 0.1524)
				(type default)
			)
			(layer "F.SilkS")
		)
		(fp_line
			(start 0.508 -0.9398)
			(end -0.508 -0.9398)
			(stroke
				(width 0.1524)
				(type default)
			)
			(layer "F.SilkS")
		)
		(fp_rect
			(start -0.508 0.9398)
			(end 0.508 -0.9398)
			(stroke
				(width 0)
				(type default)
			)
			(fill no)
			(layer "F.CrtYd")
		)
		(fp_rect
			(start -0.508 0.9398)
			(end 0.508 -0.9398)
			(stroke
				(width 0)
				(type default)
			)
			(fill no)
			(layer "F.Fab")
		)
		(pad "1" smd custom
			(at 0 -0.4445)
			(size 0.1397 0.1397)
			(layers "F.Cu" "F.Mask" "F.Paste")
			(net "DPB_HW_REV")
			(options
				(clearance outline)
				(anchor circle)
			)
			(primitives
				(gr_poly
					(pts
						(arc
							(start -0.1778 -0.2794)
							(mid -0.249642 -0.249642)
							(end -0.2794 -0.1778)
						)
						(arc
							(start -0.2794 0.1778)
							(mid -0.249642 0.249642)
							(end -0.1778 0.2794)
						)
						(arc
							(start 0.1778 0.2794)
							(mid 0.249642 0.249642)
							(end 0.2794 0.1778)
						)
						(arc
							(start 0.2794 -0.1778)
							(mid 0.249642 -0.249642)
							(end 0.1778 -0.2794)
						)
					)
					(width 0)
					(fill yes)
				)
			)
		)
		(pad "2" smd custom
			(at 0 0.4445)
			(size 0.1397 0.1397)
			(layers "F.Cu" "F.Mask" "F.Paste")
			(net "GND")
			(options
				(clearance outline)
				(anchor circle)
			)
			(primitives
				(gr_poly
					(pts
						(arc
							(start -0.1778 -0.2794)
							(mid -0.249642 -0.249642)
							(end -0.2794 -0.1778)
						)
						(arc
							(start -0.2794 0.1778)
							(mid -0.249642 0.249642)
							(end -0.1778 0.2794)
						)
						(arc
							(start 0.1778 0.2794)
							(mid 0.249642 0.249642)
							(end 0.2794 0.1778)
						)
						(arc
							(start 0.2794 -0.1778)
							(mid 0.249642 -0.249642)
							(end 0.1778 -0.2794)
						)
					)
					(width 0)
					(fill yes)
				)
			)
		)
	)
	(footprint ""
		(layer "F.Cu")
		(at 46.659546 -419.208458 -90)
		(property "Reference" "Q22"
			(at 0 0 270)
			(layer "F.SilkS")
			(hide yes)
			(effects
				(font
					(size 1.27 1.27)
				)
			)
		)
		(property "Value" "2N7002DW-7F-GP"
			(at -2.3622 -8.2042 270)
			(unlocked yes)
			(layer "F.Fab")
			(hide yes)
			(effects
				(font
					(size 1.016 1.016)
					(thickness 0.1524)
				)
			)
		)
		(property "Device Type" "SOT-363H44"
			(at -2.3622 -10.1092 270)
			(unlocked yes)
			(layer "F.Fab")
			(hide yes)
			(effects
				(font
					(size 1.016 1.016)
					(thickness 0.1524)
				)
			)
		)
		(duplicate_pad_numbers_are_jumpers no)
		(fp_line
			(start -1.4478 1.7018)
			(end 1.4478 1.7018)
			(stroke
				(width 0.1524)
				(type default)
			)
			(layer "F.SilkS")
		)
		(fp_line
			(start 1.4478 1.7018)
			(end 1.4478 -1.7018)
			(stroke
				(width 0.1524)
				(type default)
			)
			(layer "F.SilkS")
		)
		(fp_line
			(start -1.27 1.524)
			(end -1.27 0.6604)
			(stroke
				(width 0.4826)
				(type default)
			)
			(layer "F.SilkS")
		)
		(fp_line
			(start -1.4478 -1.7018)
			(end -1.4478 1.7018)
			(stroke
				(width 0.1524)
				(type default)
			)
			(layer "F.SilkS")
		)
		(fp_line
			(start 1.4478 -1.7018)
			(end -1.4478 -1.7018)
			(stroke
				(width 0.1524)
				(type default)
			)
			(layer "F.SilkS")
		)
		(fp_poly
			(pts
				(xy -1.524 -1.778) (xy 1.524 -1.778) (xy 1.524 1.778) (xy -1.524 1.778)
			)
			(stroke
				(width 0)
				(type default)
			)
			(fill no)
			(layer "F.CrtYd")
		)
		(fp_poly
			(pts
				(xy -1.524 -1.778) (xy 1.524 -1.778) (xy 1.524 1.778) (xy -1.524 1.778)
			)
			(stroke
				(width 0)
				(type default)
			)
			(fill no)
			(layer "F.Fab")
		)
		(pad "1" smd rect
			(at -0.65024 0.9398 270)
			(size 0.4064 1.016)
			(layers "F.Cu" "F.Mask" "F.Paste")
			(net "GND")
		)
		(pad "2" smd rect
			(at 0 0.9398 270)
			(size 0.4064 1.016)
			(layers "F.Cu" "F.Mask" "F.Paste")
			(net "SW_PWR_R_HDD10")
		)
		(pad "3" smd rect
			(at 0.65024 0.9398 270)
			(size 0.4064 1.016)
			(layers "F.Cu" "F.Mask" "F.Paste")
			(net "SW_HDD10_P")
		)
		(pad "4" smd rect
			(at 0.65024 -0.9398 270)
			(size 0.4064 1.016)
			(layers "F.Cu" "F.Mask" "F.Paste")
			(net "GND")
		)
		(pad "5" smd rect
			(at 0 -0.9398 270)
			(size 0.4064 1.016)
			(layers "F.Cu" "F.Mask" "F.Paste")
			(net "SW_HDD10_G")
		)
		(pad "6" smd rect
			(at -0.65024 -0.9398 270)
			(size 0.4064 1.016)
			(layers "F.Cu" "F.Mask" "F.Paste")
			(net "SW_HDD10_R")
		)
	)
	(footprint ""
		(layer "F.Cu")
		(at 217.799412 -58.019696 -90)
		(property "Reference" "C167"
			(at 0 0 270)
			(layer "F.SilkS")
			(hide yes)
			(effects
				(font
					(size 1.27 1.27)
				)
			)
		)
		(property "Value" "SCD01U50V2KX-1GP"
			(at 1.1811 -2.7051 270)
			(unlocked yes)
			(layer "F.Fab")
			(hide yes)
			(effects
				(font
					(size 1.016 1.016)
					(thickness 0.1524)
				)
			)
		)
		(property "Device Type" "C402H22"
			(at 1.1811 -4.2291 270)
			(unlocked yes)
			(layer "F.Fab")
			(hide yes)
			(effects
				(font
					(size 1.016 1.016)
					(thickness 0.1524)
				)
			)
		)
		(duplicate_pad_numbers_are_jumpers no)
		(fp_rect
			(start -0.4318 0.9525)
			(end 0.4318 -0.9525)
			(stroke
				(width 0)
				(type default)
			)
			(fill no)
			(layer "F.CrtYd")
		)
		(fp_rect
			(start -0.4318 0.9525)
			(end 0.4318 -0.9525)
			(stroke
				(width 0)
				(type default)
			)
			(fill no)
			(layer "F.Fab")
		)
		(pad "1" smd custom
			(at 0 -0.4445 270)
			(size 0.1524 0.1524)
			(layers "F.Cu" "F.Mask" "F.Paste")
			(net "SAS2X28_DRIVE_RX_P_A4")
			(options
				(clearance outline)
				(anchor circle)
			)
			(primitives
				(gr_poly
					(pts
						(arc
							(start 0.3048 -0.2032)
							(mid 0.275042 -0.275042)
							(end 0.2032 -0.3048)
						)
						(arc
							(start -0.2032 -0.3048)
							(mid -0.275042 -0.275042)
							(end -0.3048 -0.2032)
						)
						(arc
							(start -0.3048 0.2032)
							(mid -0.275042 0.275042)
							(end -0.2032 0.3048)
						)
						(arc
							(start 0.2032 0.3048)
							(mid 0.275042 0.275042)
							(end 0.3048 0.2032)
						)
					)
					(width 0)
					(fill yes)
				)
			)
		)
		(pad "2" smd custom
			(at 0 0.4445 270)
			(size 0.1524 0.1524)
			(layers "F.Cu" "F.Mask" "F.Paste")
			(net "SAS2X28_A_HDD4_RX_+")
			(options
				(clearance outline)
				(anchor circle)
			)
			(primitives
				(gr_poly
					(pts
						(arc
							(start 0.3048 -0.2032)
							(mid 0.275042 -0.275042)
							(end 0.2032 -0.3048)
						)
						(arc
							(start -0.2032 -0.3048)
							(mid -0.275042 -0.275042)
							(end -0.3048 -0.2032)
						)
						(arc
							(start -0.3048 0.2032)
							(mid -0.275042 0.275042)
							(end -0.2032 0.3048)
						)
						(arc
							(start 0.2032 0.3048)
							(mid 0.275042 0.275042)
							(end 0.3048 0.2032)
						)
					)
					(width 0)
					(fill yes)
				)
			)
		)
	)
	(footprint ""
		(layer "F.Cu")
		(at 217.854784 -161.006028 -90)
		(property "Reference" "C151"
			(at 0 0 270)
			(layer "F.SilkS")
			(hide yes)
			(effects
				(font
					(size 1.27 1.27)
				)
			)
		)
		(property "Value" "SCD01U50V2KX-1GP"
			(at 1.1811 -2.7051 270)
			(unlocked yes)
			(layer "F.Fab")
			(hide yes)
			(effects
				(font
					(size 1.016 1.016)
					(thickness 0.1524)
				)
			)
		)
		(property "Device Type" "C402H22"
			(at 1.1811 -4.2291 270)
			(unlocked yes)
			(layer "F.Fab")
			(hide yes)
			(effects
				(font
					(size 1.016 1.016)
					(thickness 0.1524)
				)
			)
		)
		(duplicate_pad_numbers_are_jumpers no)
		(fp_rect
			(start -0.4318 0.9525)
			(end 0.4318 -0.9525)
			(stroke
				(width 0)
				(type default)
			)
			(fill no)
			(layer "F.CrtYd")
		)
		(fp_rect
			(start -0.4318 0.9525)
			(end 0.4318 -0.9525)
			(stroke
				(width 0)
				(type default)
			)
			(fill no)
			(layer "F.Fab")
		)
		(pad "1" smd custom
			(at 0 -0.4445 270)
			(size 0.1524 0.1524)
			(layers "F.Cu" "F.Mask" "F.Paste")
			(net "SAS2X28_DRIVE_RX_P_A3")
			(options
				(clearance outline)
				(anchor circle)
			)
			(primitives
				(gr_poly
					(pts
						(arc
							(start 0.3048 -0.2032)
							(mid 0.275042 -0.275042)
							(end 0.2032 -0.3048)
						)
						(arc
							(start -0.2032 -0.3048)
							(mid -0.275042 -0.275042)
							(end -0.3048 -0.2032)
						)
						(arc
							(start -0.3048 0.2032)
							(mid -0.275042 0.275042)
							(end -0.2032 0.3048)
						)
						(arc
							(start 0.2032 0.3048)
							(mid 0.275042 0.275042)
							(end 0.3048 0.2032)
						)
					)
					(width 0)
					(fill yes)
				)
			)
		)
		(pad "2" smd custom
			(at 0 0.4445 270)
			(size 0.1524 0.1524)
			(layers "F.Cu" "F.Mask" "F.Paste")
			(net "SAS2X28_A_HDD3_RX_+")
			(options
				(clearance outline)
				(anchor circle)
			)
			(primitives
				(gr_poly
					(pts
						(arc
							(start 0.3048 -0.2032)
							(mid 0.275042 -0.275042)
							(end 0.2032 -0.3048)
						)
						(arc
							(start -0.2032 -0.3048)
							(mid -0.275042 -0.275042)
							(end -0.3048 -0.2032)
						)
						(arc
							(start -0.3048 0.2032)
							(mid -0.275042 0.275042)
							(end -0.2032 0.3048)
						)
						(arc
							(start 0.2032 0.3048)
							(mid 0.275042 0.275042)
							(end 0.3048 0.2032)
						)
					)
					(width 0)
					(fill yes)
				)
			)
		)
	)
	(footprint ""
		(layer "F.Cu")
		(at 78.612746 -194.8307 90)
		(property "Reference" "R221"
			(at 0 0 90)
			(layer "F.SilkS")
			(hide yes)
			(effects
				(font
					(size 1.27 1.27)
				)
			)
		)
		(property "Value" "4K7R2J-2-GP"
			(at 0.064008 -3.993896 90)
			(unlocked yes)
			(layer "F.Fab")
			(hide yes)
			(effects
				(font
					(size 1.016 1.016)
					(thickness 0.1524)
				)
			)
		)
		(property "Device Type" "R402H16"
			(at 0.064008 -5.517896 90)
			(unlocked yes)
			(layer "F.Fab")
			(hide yes)
			(effects
				(font
					(size 1.016 1.016)
					(thickness 0.1524)
				)
			)
		)
		(duplicate_pad_numbers_are_jumpers no)
		(fp_line
			(start 0.508 -0.9398)
			(end -0.508 -0.9398)
			(stroke
				(width 0.1524)
				(type default)
			)
			(layer "F.SilkS")
		)
		(fp_line
			(start -0.508 -0.9398)
			(end -0.508 0.9398)
			(stroke
				(width 0.1524)
				(type default)
			)
			(layer "F.SilkS")
		)
		(fp_rect
			(start -0.508 0.9398)
			(end 0.508 -0.9398)
			(stroke
				(width 0)
				(type default)
			)
			(fill no)
			(layer "F.CrtYd")
		)
		(fp_rect
			(start -0.508 0.9398)
			(end 0.508 -0.9398)
			(stroke
				(width 0)
				(type default)
			)
			(fill no)
			(layer "F.Fab")
		)
		(pad "1" smd custom
			(at 0 -0.4445 90)
			(size 0.1397 0.1397)
			(layers "F.Cu" "F.Mask" "F.Paste")
			(net "P12V")
			(options
				(clearance outline)
				(anchor circle)
			)
			(primitives
				(gr_poly
					(pts
						(arc
							(start -0.1778 -0.2794)
							(mid -0.249642 -0.249642)
							(end -0.2794 -0.1778)
						)
						(arc
							(start -0.2794 0.1778)
							(mid -0.249642 0.249642)
							(end -0.1778 0.2794)
						)
						(arc
							(start 0.1778 0.2794)
							(mid 0.249642 0.249642)
							(end 0.2794 0.1778)
						)
						(arc
							(start 0.2794 -0.1778)
							(mid 0.249642 -0.249642)
							(end 0.1778 -0.2794)
						)
					)
					(width 0)
					(fill yes)
				)
			)
		)
		(pad "2" smd custom
			(at 0 0.4445 90)
			(size 0.1397 0.1397)
			(layers "F.Cu" "F.Mask" "F.Paste")
			(net "SW_HDD8_R")
			(options
				(clearance outline)
				(anchor circle)
			)
			(primitives
				(gr_poly
					(pts
						(arc
							(start -0.1778 -0.2794)
							(mid -0.249642 -0.249642)
							(end -0.2794 -0.1778)
						)
						(arc
							(start -0.2794 0.1778)
							(mid -0.249642 0.249642)
							(end -0.1778 0.2794)
						)
						(arc
							(start 0.1778 0.2794)
							(mid 0.249642 0.249642)
							(end 0.2794 0.1778)
						)
						(arc
							(start 0.2794 -0.1778)
							(mid 0.249642 -0.249642)
							(end 0.1778 -0.2794)
						)
					)
					(width 0)
					(fill yes)
				)
			)
		)
	)
	(footprint ""
		(layer "F.Cu")
		(at 26.14803 -133.600952 90)
		(property "Reference" "C312"
			(at 0 0 90)
			(layer "F.SilkS")
			(hide yes)
			(effects
				(font
					(size 1.27 1.27)
				)
			)
		)
		(property "Value" "SCD01U50V2KX-1GP"
			(at 1.1811 -2.7051 90)
			(unlocked yes)
			(layer "F.Fab")
			(hide yes)
			(effects
				(font
					(size 1.016 1.016)
					(thickness 0.1524)
				)
			)
		)
		(property "Device Type" "C402H22"
			(at 1.1811 -4.2291 90)
			(unlocked yes)
			(layer "F.Fab")
			(hide yes)
			(effects
				(font
					(size 1.016 1.016)
					(thickness 0.1524)
				)
			)
		)
		(duplicate_pad_numbers_are_jumpers no)
		(fp_rect
			(start -0.4318 0.9525)
			(end 0.4318 -0.9525)
			(stroke
				(width 0)
				(type default)
			)
			(fill no)
			(layer "F.CrtYd")
		)
		(fp_rect
			(start -0.4318 0.9525)
			(end 0.4318 -0.9525)
			(stroke
				(width 0)
				(type default)
			)
			(fill no)
			(layer "F.Fab")
		)
		(pad "1" smd custom
			(at 0 -0.4445 90)
			(size 0.1524 0.1524)
			(layers "F.Cu" "F.Mask" "F.Paste")
			(net "SAS2X28_DRIVE_RX_N_B13")
			(options
				(clearance outline)
				(anchor circle)
			)
			(primitives
				(gr_poly
					(pts
						(arc
							(start 0.3048 -0.2032)
							(mid 0.275042 -0.275042)
							(end 0.2032 -0.3048)
						)
						(arc
							(start -0.2032 -0.3048)
							(mid -0.275042 -0.275042)
							(end -0.3048 -0.2032)
						)
						(arc
							(start -0.3048 0.2032)
							(mid -0.275042 0.275042)
							(end -0.2032 0.3048)
						)
						(arc
							(start 0.2032 0.3048)
							(mid 0.275042 0.275042)
							(end 0.3048 0.2032)
						)
					)
					(width 0)
					(fill yes)
				)
			)
		)
		(pad "2" smd custom
			(at 0 0.4445 90)
			(size 0.1524 0.1524)
			(layers "F.Cu" "F.Mask" "F.Paste")
			(net "SAS2X28_B_HDD13_RX_-")
			(options
				(clearance outline)
				(anchor circle)
			)
			(primitives
				(gr_poly
					(pts
						(arc
							(start 0.3048 -0.2032)
							(mid 0.275042 -0.275042)
							(end 0.2032 -0.3048)
						)
						(arc
							(start -0.2032 -0.3048)
							(mid -0.275042 -0.275042)
							(end -0.3048 -0.2032)
						)
						(arc
							(start -0.3048 0.2032)
							(mid -0.275042 0.275042)
							(end -0.2032 0.3048)
						)
						(arc
							(start 0.2032 0.3048)
							(mid 0.275042 0.275042)
							(end 0.3048 0.2032)
						)
					)
					(width 0)
					(fill yes)
				)
			)
		)
	)
	(footprint ""
		(layer "F.Cu")
		(at 190.803784 -187.168028 180)
		(property "Reference" "R153"
			(at 0 0 180)
			(layer "F.SilkS")
			(hide yes)
			(effects
				(font
					(size 1.27 1.27)
				)
			)
		)
		(property "Value" "0R2J-2-GP"
			(at 0.064008 -3.993896 180)
			(unlocked yes)
			(layer "F.Fab")
			(hide yes)
			(effects
				(font
					(size 1.016 1.016)
					(thickness 0.1524)
				)
			)
		)
		(property "Device Type" "R402H16"
			(at 0.064008 -5.517896 180)
			(unlocked yes)
			(layer "F.Fab")
			(hide yes)
			(effects
				(font
					(size 1.016 1.016)
					(thickness 0.1524)
				)
			)
		)
		(duplicate_pad_numbers_are_jumpers no)
		(fp_line
			(start 0.508 -0.9398)
			(end -0.508 -0.9398)
			(stroke
				(width 0.1524)
				(type default)
			)
			(layer "F.SilkS")
		)
		(fp_line
			(start -0.508 -0.9398)
			(end -0.508 0.9398)
			(stroke
				(width 0.1524)
				(type default)
			)
			(layer "F.SilkS")
		)
		(fp_rect
			(start -0.508 0.9398)
			(end 0.508 -0.9398)
			(stroke
				(width 0)
				(type default)
			)
			(fill no)
			(layer "F.CrtYd")
		)
		(fp_rect
			(start -0.508 0.9398)
			(end 0.508 -0.9398)
			(stroke
				(width 0)
				(type default)
			)
			(fill no)
			(layer "F.Fab")
		)
		(pad "1" smd custom
			(at 0 -0.4445 180)
			(size 0.1397 0.1397)
			(layers "F.Cu" "F.Mask" "F.Paste")
			(net "SW_PWR_HDD3")
			(options
				(clearance outline)
				(anchor circle)
			)
			(primitives
				(gr_poly
					(pts
						(arc
							(start -0.1778 -0.2794)
							(mid -0.249642 -0.249642)
							(end -0.2794 -0.1778)
						)
						(arc
							(start -0.2794 0.1778)
							(mid -0.249642 0.249642)
							(end -0.1778 0.2794)
						)
						(arc
							(start 0.1778 0.2794)
							(mid 0.249642 0.249642)
							(end 0.2794 0.1778)
						)
						(arc
							(start 0.2794 -0.1778)
							(mid 0.249642 -0.249642)
							(end 0.1778 -0.2794)
						)
					)
					(width 0)
					(fill yes)
				)
			)
		)
		(pad "2" smd custom
			(at 0 0.4445 180)
			(size 0.1397 0.1397)
			(layers "F.Cu" "F.Mask" "F.Paste")
			(net "SW_PWR_R_HDD3")
			(options
				(clearance outline)
				(anchor circle)
			)
			(primitives
				(gr_poly
					(pts
						(arc
							(start -0.1778 -0.2794)
							(mid -0.249642 -0.249642)
							(end -0.2794 -0.1778)
						)
						(arc
							(start -0.2794 0.1778)
							(mid -0.249642 0.249642)
							(end -0.1778 0.2794)
						)
						(arc
							(start 0.1778 0.2794)
							(mid 0.249642 0.249642)
							(end 0.2794 0.1778)
						)
						(arc
							(start 0.2794 -0.1778)
							(mid 0.249642 -0.249642)
							(end 0.1778 -0.2794)
						)
					)
					(width 0)
					(fill yes)
				)
			)
		)
	)
	(footprint ""
		(layer "F.Cu")
		(at 212.851746 -454.1647 90)
		(property "Reference" "C342"
			(at 0 0 90)
			(layer "F.SilkS")
			(hide yes)
			(effects
				(font
					(size 1.27 1.27)
				)
			)
		)
		(property "Value" "SCD1U10V2KX-5GP"
			(at 1.1811 -2.7051 90)
			(unlocked yes)
			(layer "F.Fab")
			(hide yes)
			(effects
				(font
					(size 1.016 1.016)
					(thickness 0.1524)
				)
			)
		)
		(property "Device Type" "C402H22"
			(at 1.1811 -4.2291 90)
			(unlocked yes)
			(layer "F.Fab")
			(hide yes)
			(effects
				(font
					(size 1.016 1.016)
					(thickness 0.1524)
				)
			)
		)
		(duplicate_pad_numbers_are_jumpers no)
		(fp_rect
			(start -0.4318 0.9525)
			(end 0.4318 -0.9525)
			(stroke
				(width 0)
				(type default)
			)
			(fill no)
			(layer "F.CrtYd")
		)
		(fp_rect
			(start -0.4318 0.9525)
			(end 0.4318 -0.9525)
			(stroke
				(width 0)
				(type default)
			)
			(fill no)
			(layer "F.Fab")
		)
		(pad "1" smd custom
			(at 0 -0.4445 90)
			(size 0.1524 0.1524)
			(layers "F.Cu" "F.Mask" "F.Paste")
			(net "P3V3")
			(options
				(clearance outline)
				(anchor circle)
			)
			(primitives
				(gr_poly
					(pts
						(arc
							(start 0.3048 -0.2032)
							(mid 0.275042 -0.275042)
							(end 0.2032 -0.3048)
						)
						(arc
							(start -0.2032 -0.3048)
							(mid -0.275042 -0.275042)
							(end -0.3048 -0.2032)
						)
						(arc
							(start -0.3048 0.2032)
							(mid -0.275042 0.275042)
							(end -0.2032 0.3048)
						)
						(arc
							(start 0.2032 0.3048)
							(mid 0.275042 0.275042)
							(end 0.3048 0.2032)
						)
					)
					(width 0)
					(fill yes)
				)
			)
		)
		(pad "2" smd custom
			(at 0 0.4445 90)
			(size 0.1524 0.1524)
			(layers "F.Cu" "F.Mask" "F.Paste")
			(net "GND")
			(options
				(clearance outline)
				(anchor circle)
			)
			(primitives
				(gr_poly
					(pts
						(arc
							(start 0.3048 -0.2032)
							(mid 0.275042 -0.275042)
							(end 0.2032 -0.3048)
						)
						(arc
							(start -0.2032 -0.3048)
							(mid -0.275042 -0.275042)
							(end -0.3048 -0.2032)
						)
						(arc
							(start -0.3048 0.2032)
							(mid -0.275042 0.275042)
							(end -0.2032 0.3048)
						)
						(arc
							(start 0.2032 0.3048)
							(mid 0.275042 0.275042)
							(end 0.3048 0.2032)
						)
					)
					(width 0)
					(fill yes)
				)
			)
		)
	)
	(footprint ""
		(layer "F.Cu")
		(at 192.3796 -295.8592 90)
		(property "Reference" "D17"
			(at 0 0 90)
			(layer "F.SilkS")
			(hide yes)
			(effects
				(font
					(size 1.27 1.27)
				)
			)
		)
		(property "Value" "RB551V30-1-GP"
			(at 0 -6.7818 90)
			(unlocked yes)
			(layer "F.Fab")
			(hide yes)
			(effects
				(font
					(size 1.016 1.016)
					(thickness 0.1524)
				)
			)
		)
		(property "Device Type" "SOD323AKH44"
			(at 0 -8.6868 90)
			(unlocked yes)
			(layer "F.Fab")
			(hide yes)
			(effects
				(font
					(size 1.016 1.016)
					(thickness 0.1524)
				)
			)
		)
		(duplicate_pad_numbers_are_jumpers no)
		(fp_line
			(start 0.889 -1.9304)
			(end 0.889 2.159)
			(stroke
				(width 0.1524)
				(type default)
			)
			(layer "F.SilkS")
		)
		(fp_line
			(start -0.889 -1.9304)
			(end 0.889 -1.9304)
			(stroke
				(width 0.1524)
				(type default)
			)
			(layer "F.SilkS")
		)
		(fp_line
			(start 0.762 2.0574)
			(end -0.762 2.0574)
			(stroke
				(width 0.508)
				(type default)
			)
			(layer "F.SilkS")
		)
		(fp_line
			(start 0.889 2.159)
			(end -0.889 2.159)
			(stroke
				(width 0.1524)
				(type default)
			)
			(layer "F.SilkS")
		)
		(fp_line
			(start -0.889 2.159)
			(end -0.889 -1.9304)
			(stroke
				(width 0.1524)
				(type default)
			)
			(layer "F.SilkS")
		)
		(fp_rect
			(start -1.016 2.3114)
			(end 1.016 -2.0066)
			(stroke
				(width 0)
				(type default)
			)
			(fill no)
			(layer "F.CrtYd")
		)
		(fp_poly
			(pts
				(xy -1.016 -2.0066) (xy 1.016 -2.0066) (xy 1.016 2.3114) (xy -1.016 2.3114)
			)
			(stroke
				(width 0)
				(type default)
			)
			(fill no)
			(layer "F.Fab")
		)
		(pad "A" smd rect
			(at 0 -1.143 90)
			(size 0.5588 1.016)
			(layers "F.Cu" "F.Mask" "F.Paste")
			(net "SW_HDD2_R")
		)
		(pad "K" smd rect
			(at 0 1.143 90)
			(size 0.5588 1.016)
			(layers "F.Cu" "F.Mask" "F.Paste")
			(net "SW_HDD2_N")
		)
	)
	(footprint ""
		(layer "F.Cu")
		(at 36.957 -138.43 -90)
		(property "Reference" "R403"
			(at 0 0 270)
			(layer "F.SilkS")
			(hide yes)
			(effects
				(font
					(size 1.27 1.27)
				)
			)
		)
		(property "Value" "10KR2F-2-GP"
			(at 0.064008 -3.993896 270)
			(unlocked yes)
			(layer "F.Fab")
			(hide yes)
			(effects
				(font
					(size 1.016 1.016)
					(thickness 0.1524)
				)
			)
		)
		(property "Device Type" "R402H16"
			(at 0.064008 -5.517896 270)
			(unlocked yes)
			(layer "F.Fab")
			(hide yes)
			(effects
				(font
					(size 1.016 1.016)
					(thickness 0.1524)
				)
			)
		)
		(duplicate_pad_numbers_are_jumpers no)
		(fp_line
			(start -0.508 -0.9398)
			(end -0.508 0.9398)
			(stroke
				(width 0.1524)
				(type default)
			)
			(layer "F.SilkS")
		)
		(fp_line
			(start 0.508 -0.9398)
			(end -0.508 -0.9398)
			(stroke
				(width 0.1524)
				(type default)
			)
			(layer "F.SilkS")
		)
		(fp_rect
			(start -0.508 0.9398)
			(end 0.508 -0.9398)
			(stroke
				(width 0)
				(type default)
			)
			(fill no)
			(layer "F.CrtYd")
		)
		(fp_rect
			(start -0.508 0.9398)
			(end 0.508 -0.9398)
			(stroke
				(width 0)
				(type default)
			)
			(fill no)
			(layer "F.Fab")
		)
		(pad "1" smd custom
			(at 0 -0.4445 270)
			(size 0.1397 0.1397)
			(layers "F.Cu" "F.Mask" "F.Paste")
			(net "P12V")
			(options
				(clearance outline)
				(anchor circle)
			)
			(primitives
				(gr_poly
					(pts
						(arc
							(start -0.1778 -0.2794)
							(mid -0.249642 -0.249642)
							(end -0.2794 -0.1778)
						)
						(arc
							(start -0.2794 0.1778)
							(mid -0.249642 0.249642)
							(end -0.1778 0.2794)
						)
						(arc
							(start 0.1778 0.2794)
							(mid 0.249642 0.249642)
							(end 0.2794 0.1778)
						)
						(arc
							(start 0.2794 -0.1778)
							(mid 0.249642 -0.249642)
							(end 0.1778 -0.2794)
						)
					)
					(width 0)
					(fill yes)
				)
			)
		)
		(pad "2" smd custom
			(at 0 0.4445 270)
			(size 0.1397 0.1397)
			(layers "F.Cu" "F.Mask" "F.Paste")
			(net "HDD13_LED_G")
			(options
				(clearance outline)
				(anchor circle)
			)
			(primitives
				(gr_poly
					(pts
						(arc
							(start -0.1778 -0.2794)
							(mid -0.249642 -0.249642)
							(end -0.2794 -0.1778)
						)
						(arc
							(start -0.2794 0.1778)
							(mid -0.249642 0.249642)
							(end -0.1778 0.2794)
						)
						(arc
							(start 0.1778 0.2794)
							(mid 0.249642 0.249642)
							(end 0.2794 0.1778)
						)
						(arc
							(start 0.2794 -0.1778)
							(mid 0.249642 -0.249642)
							(end 0.1778 -0.2794)
						)
					)
					(width 0)
					(fill yes)
				)
			)
		)
	)
	(footprint ""
		(layer "F.Cu")
		(at 32.054546 -417.452302)
		(property "Reference" "C273"
			(at 0 0 0)
			(layer "F.SilkS")
			(hide yes)
			(effects
				(font
					(size 1.27 1.27)
				)
			)
		)
		(property "Value" "SC10U25V6KX-1GP"
			(at -0.0762 -5.1308 0)
			(unlocked yes)
			(layer "F.Fab")
			(hide yes)
			(effects
				(font
					(size 1.016 1.016)
					(thickness 0.1524)
				)
			)
		)
		(property "Device Type" "C1206H71"
			(at -0.127 -6.6548 0)
			(unlocked yes)
			(layer "F.Fab")
			(hide yes)
			(effects
				(font
					(size 1.016 1.016)
					(thickness 0.1524)
				)
			)
		)
		(duplicate_pad_numbers_are_jumpers no)
		(fp_line
			(start -1.016 -2.2352)
			(end 1.016 -2.2352)
			(stroke
				(width 0.1524)
				(type default)
			)
			(layer "F.SilkS")
		)
		(fp_line
			(start -1.016 -0.8382)
			(end -1.016 -2.2352)
			(stroke
				(width 0.1524)
				(type default)
			)
			(layer "F.SilkS")
		)
		(fp_line
			(start -1.016 2.2352)
			(end -1.016 0.8382)
			(stroke
				(width 0.1524)
				(type default)
			)
			(layer "F.SilkS")
		)
		(fp_line
			(start 1.016 -2.2352)
			(end 1.016 -0.8382)
			(stroke
				(width 0.1524)
				(type default)
			)
			(layer "F.SilkS")
		)
		(fp_line
			(start 1.016 0.8382)
			(end 1.016 2.2352)
			(stroke
				(width 0.1524)
				(type default)
			)
			(layer "F.SilkS")
		)
		(fp_line
			(start 1.016 2.2352)
			(end -1.016 2.2352)
			(stroke
				(width 0.1524)
				(type default)
			)
			(layer "F.SilkS")
		)
		(fp_rect
			(start -1.0922 2.3114)
			(end 1.0922 -2.3114)
			(stroke
				(width 0)
				(type default)
			)
			(fill no)
			(layer "F.CrtYd")
		)
		(fp_poly
			(pts
				(xy 1.0922 -2.3114) (xy 1.0922 2.3114) (xy -1.0922 2.3114) (xy -1.0922 -2.3114)
			)
			(stroke
				(width 0)
				(type default)
			)
			(fill no)
			(layer "F.Fab")
		)
		(pad "1" smd rect
			(at 0 -1.397)
			(size 1.651 1.27)
			(layers "F.Cu" "F.Mask" "F.Paste")
			(net "P12V_HDD10")
		)
		(pad "2" smd rect
			(at 0 1.397)
			(size 1.651 1.27)
			(layers "F.Cu" "F.Mask" "F.Paste")
			(net "GND")
		)
	)
	(footprint ""
		(layer "F.Cu")
		(at 20.066 -393.7)
		(property "Reference" "R508"
			(at 0 0 0)
			(layer "F.SilkS")
			(hide yes)
			(effects
				(font
					(size 1.27 1.27)
				)
			)
		)
		(property "Value" "0R2J-2-GP"
			(at 0.064008 -3.993896 0)
			(unlocked yes)
			(layer "F.Fab")
			(hide yes)
			(effects
				(font
					(size 1.016 1.016)
					(thickness 0.1524)
				)
			)
		)
		(property "Device Type" "R402H16"
			(at 0.064008 -5.517896 0)
			(unlocked yes)
			(layer "F.Fab")
			(hide yes)
			(effects
				(font
					(size 1.016 1.016)
					(thickness 0.1524)
				)
			)
		)
		(duplicate_pad_numbers_are_jumpers no)
		(fp_line
			(start -0.508 -0.9398)
			(end -0.508 0.9398)
			(stroke
				(width 0.1524)
				(type default)
			)
			(layer "F.SilkS")
		)
		(fp_line
			(start 0.508 -0.9398)
			(end -0.508 -0.9398)
			(stroke
				(width 0.1524)
				(type default)
			)
			(layer "F.SilkS")
		)
		(fp_rect
			(start -0.508 0.9398)
			(end 0.508 -0.9398)
			(stroke
				(width 0)
				(type default)
			)
			(fill no)
			(layer "F.CrtYd")
		)
		(fp_rect
			(start -0.508 0.9398)
			(end 0.508 -0.9398)
			(stroke
				(width 0)
				(type default)
			)
			(fill no)
			(layer "F.Fab")
		)
		(pad "1" smd custom
			(at 0 -0.4445)
			(size 0.1397 0.1397)
			(layers "F.Cu" "F.Mask" "F.Paste")
			(net "I2C_D_SCL_DAMP_A")
			(options
				(clearance outline)
				(anchor circle)
			)
			(primitives
				(gr_poly
					(pts
						(arc
							(start -0.1778 -0.2794)
							(mid -0.249642 -0.249642)
							(end -0.2794 -0.1778)
						)
						(arc
							(start -0.2794 0.1778)
							(mid -0.249642 0.249642)
							(end -0.1778 0.2794)
						)
						(arc
							(start 0.1778 0.2794)
							(mid 0.249642 0.249642)
							(end 0.2794 0.1778)
						)
						(arc
							(start 0.2794 -0.1778)
							(mid 0.249642 -0.249642)
							(end 0.1778 -0.2794)
						)
					)
					(width 0)
					(fill yes)
				)
			)
		)
		(pad "2" smd custom
			(at 0 0.4445)
			(size 0.1397 0.1397)
			(layers "F.Cu" "F.Mask" "F.Paste")
			(net "I2C_D_SCL")
			(options
				(clearance outline)
				(anchor circle)
			)
			(primitives
				(gr_poly
					(pts
						(arc
							(start -0.1778 -0.2794)
							(mid -0.249642 -0.249642)
							(end -0.2794 -0.1778)
						)
						(arc
							(start -0.2794 0.1778)
							(mid -0.249642 0.249642)
							(end -0.1778 0.2794)
						)
						(arc
							(start 0.1778 0.2794)
							(mid 0.249642 0.249642)
							(end 0.2794 0.1778)
						)
						(arc
							(start 0.2794 -0.1778)
							(mid 0.249642 -0.249642)
							(end 0.1778 -0.2794)
						)
					)
					(width 0)
					(fill yes)
				)
			)
		)
	)
	(footprint ""
		(layer "F.Cu")
		(at 193.167 -500.888 90)
		(property "Reference" "D15"
			(at 0 0 90)
			(layer "F.SilkS")
			(hide yes)
			(effects
				(font
					(size 1.27 1.27)
				)
			)
		)
		(property "Value" "RB551V30-1-GP"
			(at 0 -6.7818 90)
			(unlocked yes)
			(layer "F.Fab")
			(hide yes)
			(effects
				(font
					(size 1.016 1.016)
					(thickness 0.1524)
				)
			)
		)
		(property "Device Type" "SOD323AKH44"
			(at 0 -8.6868 90)
			(unlocked yes)
			(layer "F.Fab")
			(hide yes)
			(effects
				(font
					(size 1.016 1.016)
					(thickness 0.1524)
				)
			)
		)
		(duplicate_pad_numbers_are_jumpers no)
		(fp_line
			(start 0.889 -1.9304)
			(end 0.889 2.159)
			(stroke
				(width 0.1524)
				(type default)
			)
			(layer "F.SilkS")
		)
		(fp_line
			(start -0.889 -1.9304)
			(end 0.889 -1.9304)
			(stroke
				(width 0.1524)
				(type default)
			)
			(layer "F.SilkS")
		)
		(fp_line
			(start 0.762 2.0574)
			(end -0.762 2.0574)
			(stroke
				(width 0.508)
				(type default)
			)
			(layer "F.SilkS")
		)
		(fp_line
			(start 0.889 2.159)
			(end -0.889 2.159)
			(stroke
				(width 0.1524)
				(type default)
			)
			(layer "F.SilkS")
		)
		(fp_line
			(start -0.889 2.159)
			(end -0.889 -1.9304)
			(stroke
				(width 0.1524)
				(type default)
			)
			(layer "F.SilkS")
		)
		(fp_rect
			(start -1.016 2.3114)
			(end 1.016 -2.0066)
			(stroke
				(width 0)
				(type default)
			)
			(fill no)
			(layer "F.CrtYd")
		)
		(fp_poly
			(pts
				(xy -1.016 -2.0066) (xy 1.016 -2.0066) (xy 1.016 2.3114) (xy -1.016 2.3114)
			)
			(stroke
				(width 0)
				(type default)
			)
			(fill no)
			(layer "F.Fab")
		)
		(pad "A" smd rect
			(at 0 -1.143 90)
			(size 0.5588 1.016)
			(layers "F.Cu" "F.Mask" "F.Paste")
			(net "SW_HDD0_R")
		)
		(pad "K" smd rect
			(at 0 1.143 90)
			(size 0.5588 1.016)
			(layers "F.Cu" "F.Mask" "F.Paste")
			(net "SW_HDD0_N")
		)
	)
	(footprint ""
		(layer "F.Cu")
		(at 78.561946 -389.8773)
		(property "Reference" "C197"
			(at 0 0 0)
			(layer "F.SilkS")
			(hide yes)
			(effects
				(font
					(size 1.27 1.27)
				)
			)
		)
		(property "Value" "SCD1U10V2KX-5GP"
			(at 1.1811 -2.7051 0)
			(unlocked yes)
			(layer "F.Fab")
			(hide yes)
			(effects
				(font
					(size 1.016 1.016)
					(thickness 0.1524)
				)
			)
		)
		(property "Device Type" "C402H22"
			(at 1.1811 -4.2291 0)
			(unlocked yes)
			(layer "F.Fab")
			(hide yes)
			(effects
				(font
					(size 1.016 1.016)
					(thickness 0.1524)
				)
			)
		)
		(duplicate_pad_numbers_are_jumpers no)
		(fp_rect
			(start -0.4318 0.9525)
			(end 0.4318 -0.9525)
			(stroke
				(width 0)
				(type default)
			)
			(fill no)
			(layer "F.CrtYd")
		)
		(fp_rect
			(start -0.4318 0.9525)
			(end 0.4318 -0.9525)
			(stroke
				(width 0)
				(type default)
			)
			(fill no)
			(layer "F.Fab")
		)
		(pad "1" smd custom
			(at 0 -0.4445)
			(size 0.1524 0.1524)
			(layers "F.Cu" "F.Mask" "F.Paste")
			(net "P3V3")
			(options
				(clearance outline)
				(anchor circle)
			)
			(primitives
				(gr_poly
					(pts
						(arc
							(start 0.3048 -0.2032)
							(mid 0.275042 -0.275042)
							(end 0.2032 -0.3048)
						)
						(arc
							(start -0.2032 -0.3048)
							(mid -0.275042 -0.275042)
							(end -0.3048 -0.2032)
						)
						(arc
							(start -0.3048 0.2032)
							(mid -0.275042 0.275042)
							(end -0.2032 0.3048)
						)
						(arc
							(start 0.2032 0.3048)
							(mid 0.275042 0.275042)
							(end 0.3048 0.2032)
						)
					)
					(width 0)
					(fill yes)
				)
			)
		)
		(pad "2" smd custom
			(at 0 0.4445)
			(size 0.1524 0.1524)
			(layers "F.Cu" "F.Mask" "F.Paste")
			(net "GND")
			(options
				(clearance outline)
				(anchor circle)
			)
			(primitives
				(gr_poly
					(pts
						(arc
							(start 0.3048 -0.2032)
							(mid 0.275042 -0.275042)
							(end 0.2032 -0.3048)
						)
						(arc
							(start -0.2032 -0.3048)
							(mid -0.275042 -0.275042)
							(end -0.3048 -0.2032)
						)
						(arc
							(start -0.3048 0.2032)
							(mid -0.275042 0.275042)
							(end -0.2032 0.3048)
						)
						(arc
							(start 0.2032 0.3048)
							(mid 0.275042 0.275042)
							(end 0.3048 0.2032)
						)
					)
					(width 0)
					(fill yes)
				)
			)
		)
	)
	(footprint ""
		(layer "F.Cu")
		(at 78.485746 -184.5437)
		(property "Reference" "C235"
			(at 0 0 0)
			(layer "F.SilkS")
			(hide yes)
			(effects
				(font
					(size 1.27 1.27)
				)
			)
		)
		(property "Value" "SCD1U10V2KX-5GP"
			(at 1.1811 -2.7051 0)
			(unlocked yes)
			(layer "F.Fab")
			(hide yes)
			(effects
				(font
					(size 1.016 1.016)
					(thickness 0.1524)
				)
			)
		)
		(property "Device Type" "C402H22"
			(at 1.1811 -4.2291 0)
			(unlocked yes)
			(layer "F.Fab")
			(hide yes)
			(effects
				(font
					(size 1.016 1.016)
					(thickness 0.1524)
				)
			)
		)
		(duplicate_pad_numbers_are_jumpers no)
		(fp_rect
			(start -0.4318 0.9525)
			(end 0.4318 -0.9525)
			(stroke
				(width 0)
				(type default)
			)
			(fill no)
			(layer "F.CrtYd")
		)
		(fp_rect
			(start -0.4318 0.9525)
			(end 0.4318 -0.9525)
			(stroke
				(width 0)
				(type default)
			)
			(fill no)
			(layer "F.Fab")
		)
		(pad "1" smd custom
			(at 0 -0.4445)
			(size 0.1524 0.1524)
			(layers "F.Cu" "F.Mask" "F.Paste")
			(net "P3V3")
			(options
				(clearance outline)
				(anchor circle)
			)
			(primitives
				(gr_poly
					(pts
						(arc
							(start 0.3048 -0.2032)
							(mid 0.275042 -0.275042)
							(end 0.2032 -0.3048)
						)
						(arc
							(start -0.2032 -0.3048)
							(mid -0.275042 -0.275042)
							(end -0.3048 -0.2032)
						)
						(arc
							(start -0.3048 0.2032)
							(mid -0.275042 0.275042)
							(end -0.2032 0.3048)
						)
						(arc
							(start 0.2032 0.3048)
							(mid 0.275042 0.275042)
							(end 0.3048 0.2032)
						)
					)
					(width 0)
					(fill yes)
				)
			)
		)
		(pad "2" smd custom
			(at 0 0.4445)
			(size 0.1524 0.1524)
			(layers "F.Cu" "F.Mask" "F.Paste")
			(net "GND")
			(options
				(clearance outline)
				(anchor circle)
			)
			(primitives
				(gr_poly
					(pts
						(arc
							(start 0.3048 -0.2032)
							(mid 0.275042 -0.275042)
							(end 0.2032 -0.3048)
						)
						(arc
							(start -0.2032 -0.3048)
							(mid -0.275042 -0.275042)
							(end -0.3048 -0.2032)
						)
						(arc
							(start -0.3048 0.2032)
							(mid -0.275042 0.275042)
							(end -0.2032 0.3048)
						)
						(arc
							(start 0.2032 0.3048)
							(mid 0.275042 0.275042)
							(end 0.3048 0.2032)
						)
					)
					(width 0)
					(fill yes)
				)
			)
		)
	)
	(footprint ""
		(layer "F.Cu")
		(at 77.978 -25.7556)
		(property "Reference" "Q75"
			(at 0 0 0)
			(layer "F.SilkS")
			(hide yes)
			(effects
				(font
					(size 1.27 1.27)
				)
			)
		)
		(property "Value" "2N7002-11-GP"
			(at 0.127 -8.9662 0)
			(unlocked yes)
			(layer "F.Fab")
			(hide yes)
			(effects
				(font
					(size 1.016 1.016)
					(thickness 0.1524)
				)
			)
		)
		(property "Device Type" "SOT23DGS2D4H44"
			(at 0.127 -10.4902 0)
			(unlocked yes)
			(layer "F.Fab")
			(hide yes)
			(effects
				(font
					(size 1.016 1.016)
					(thickness 0.1524)
				)
			)
		)
		(duplicate_pad_numbers_are_jumpers no)
		(fp_line
			(start -1.651 -1.778)
			(end -1.651 1.778)
			(stroke
				(width 0.1524)
				(type default)
			)
			(layer "F.SilkS")
		)
		(fp_line
			(start -1.651 1.778)
			(end 1.651 1.778)
			(stroke
				(width 0.1524)
				(type default)
			)
			(layer "F.SilkS")
		)
		(fp_line
			(start 1.651 -1.778)
			(end -1.651 -1.778)
			(stroke
				(width 0.1524)
				(type default)
			)
			(layer "F.SilkS")
		)
		(fp_line
			(start 1.651 1.778)
			(end 1.651 -1.778)
			(stroke
				(width 0.1524)
				(type default)
			)
			(layer "F.SilkS")
		)
		(fp_poly
			(pts
				(xy -1.778 1.8796) (xy -1.778 -1.8796) (xy 1.778 -1.8796) (xy 1.778 1.8796)
			)
			(stroke
				(width 0)
				(type default)
			)
			(fill no)
			(layer "F.CrtYd")
		)
		(fp_poly
			(pts
				(xy -1.778 1.8796) (xy -1.778 -1.8796) (xy 1.778 -1.8796) (xy 1.778 1.8796)
			)
			(stroke
				(width 0)
				(type default)
			)
			(fill no)
			(layer "F.Fab")
		)
		(pad "D" smd custom
			(at 0 -0.9525)
			(size 0.1905 0.1905)
			(layers "F.Cu" "F.Mask" "F.Paste")
			(net "HDD14_LED_G")
			(options
				(clearance outline)
				(anchor circle)
			)
			(primitives
				(gr_poly
					(pts
						(arc
							(start -0.1778 0.5715)
							(mid -0.321484 0.511984)
							(end -0.381 0.3683)
						)
						(arc
							(start -0.381 -0.3683)
							(mid -0.321484 -0.511984)
							(end -0.1778 -0.5715)
						)
						(arc
							(start 0.1778 -0.5715)
							(mid 0.321484 -0.511984)
							(end 0.381 -0.3683)
						)
						(arc
							(start 0.381 0.3683)
							(mid 0.321484 0.511984)
							(end 0.1778 0.5715)
						)
					)
					(width 0)
					(fill yes)
				)
			)
		)
		(pad "G" smd custom
			(at -0.98425 0.9525)
			(size 0.1905 0.1905)
			(layers "F.Cu" "F.Mask" "F.Paste")
			(net "HDD14_LED_B")
			(options
				(clearance outline)
				(anchor circle)
			)
			(primitives
				(gr_poly
					(pts
						(arc
							(start -0.1778 0.5715)
							(mid -0.321484 0.511984)
							(end -0.381 0.3683)
						)
						(arc
							(start -0.381 -0.3683)
							(mid -0.321484 -0.511984)
							(end -0.1778 -0.5715)
						)
						(arc
							(start 0.1778 -0.5715)
							(mid 0.321484 -0.511984)
							(end 0.381 -0.3683)
						)
						(arc
							(start 0.381 0.3683)
							(mid 0.321484 0.511984)
							(end 0.1778 0.5715)
						)
					)
					(width 0)
					(fill yes)
				)
			)
		)
		(pad "S" smd custom
			(at 0.98425 0.9525)
			(size 0.1905 0.1905)
			(layers "F.Cu" "F.Mask" "F.Paste")
			(net "GND")
			(options
				(clearance outline)
				(anchor circle)
			)
			(primitives
				(gr_poly
					(pts
						(arc
							(start -0.1778 0.5715)
							(mid -0.321484 0.511984)
							(end -0.381 0.3683)
						)
						(arc
							(start -0.381 -0.3683)
							(mid -0.321484 -0.511984)
							(end -0.1778 -0.5715)
						)
						(arc
							(start 0.1778 -0.5715)
							(mid 0.321484 -0.511984)
							(end 0.381 -0.3683)
						)
						(arc
							(start 0.381 0.3683)
							(mid 0.321484 0.511984)
							(end 0.1778 0.5715)
						)
					)
					(width 0)
					(fill yes)
				)
			)
		)
	)
	(footprint ""
		(layer "F.Cu")
		(at 242.569746 -20.8407 90)
		(property "Reference" "PC2"
			(at 0 0 90)
			(layer "F.SilkS")
			(hide yes)
			(effects
				(font
					(size 1.27 1.27)
				)
			)
		)
		(property "Value" "SC22U25V5MX-GP"
			(at -0.0762 -6.1214 90)
			(unlocked yes)
			(layer "F.Fab")
			(hide yes)
			(effects
				(font
					(size 1.016 1.016)
					(thickness 0.1524)
				)
			)
		)
		(property "Device Type" "C805H58"
			(at -0.0762 -8.1534 90)
			(unlocked yes)
			(layer "F.Fab")
			(hide yes)
			(effects
				(font
					(size 1.016 1.016)
					(thickness 0.1524)
				)
			)
		)
		(duplicate_pad_numbers_are_jumpers no)
		(fp_line
			(start 0.635 0)
			(end -0.635 0)
			(stroke
				(width 0.508)
				(type default)
			)
			(layer "F.SilkS")
		)
		(fp_rect
			(start -0.9652 1.778)
			(end 0.9652 -1.778)
			(stroke
				(width 0)
				(type default)
			)
			(fill no)
			(layer "F.CrtYd")
		)
		(fp_poly
			(pts
				(xy -0.9652 -1.778) (xy 0.9652 -1.778) (xy 0.9652 1.778) (xy -0.9652 1.778)
			)
			(stroke
				(width 0)
				(type default)
			)
			(fill no)
			(layer "F.Fab")
		)
		(pad "1" smd rect
			(at 0 -0.9652 90)
			(size 1.397 1.143)
			(layers "F.Cu" "F.Mask" "F.Paste")
			(net "P5VA_12VIN")
		)
		(pad "2" smd rect
			(at 0 0.9652 90)
			(size 1.397 1.143)
			(layers "F.Cu" "F.Mask" "F.Paste")
			(net "GND")
		)
	)
	(footprint ""
		(layer "F.Cu")
		(at 46.837346 -450.3928 -90)
		(property "Reference" "R493"
			(at 0 0 270)
			(layer "F.SilkS")
			(hide yes)
			(effects
				(font
					(size 1.27 1.27)
				)
			)
		)
		(property "Value" "1KR2F-3-GP"
			(at 0.064008 -3.993896 270)
			(unlocked yes)
			(layer "F.Fab")
			(hide yes)
			(effects
				(font
					(size 1.016 1.016)
					(thickness 0.1524)
				)
			)
		)
		(property "Device Type" "R402H16"
			(at 0.064008 -5.517896 270)
			(unlocked yes)
			(layer "F.Fab")
			(hide yes)
			(effects
				(font
					(size 1.016 1.016)
					(thickness 0.1524)
				)
			)
		)
		(duplicate_pad_numbers_are_jumpers no)
		(fp_line
			(start -0.508 -0.9398)
			(end -0.508 0.9398)
			(stroke
				(width 0.1524)
				(type default)
			)
			(layer "F.SilkS")
		)
		(fp_line
			(start 0.508 -0.9398)
			(end -0.508 -0.9398)
			(stroke
				(width 0.1524)
				(type default)
			)
			(layer "F.SilkS")
		)
		(fp_rect
			(start -0.508 0.9398)
			(end 0.508 -0.9398)
			(stroke
				(width 0)
				(type default)
			)
			(fill no)
			(layer "F.CrtYd")
		)
		(fp_rect
			(start -0.508 0.9398)
			(end 0.508 -0.9398)
			(stroke
				(width 0)
				(type default)
			)
			(fill no)
			(layer "F.Fab")
		)
		(pad "1" smd custom
			(at 0 -0.4445 270)
			(size 0.1397 0.1397)
			(layers "F.Cu" "F.Mask" "F.Paste")
			(net "FLT_HDD5_B")
			(options
				(clearance outline)
				(anchor circle)
			)
			(primitives
				(gr_poly
					(pts
						(arc
							(start -0.1778 -0.2794)
							(mid -0.249642 -0.249642)
							(end -0.2794 -0.1778)
						)
						(arc
							(start -0.2794 0.1778)
							(mid -0.249642 0.249642)
							(end -0.1778 0.2794)
						)
						(arc
							(start 0.1778 0.2794)
							(mid 0.249642 0.249642)
							(end 0.2794 0.1778)
						)
						(arc
							(start 0.2794 -0.1778)
							(mid 0.249642 -0.249642)
							(end 0.1778 -0.2794)
						)
					)
					(width 0)
					(fill yes)
				)
			)
		)
		(pad "2" smd custom
			(at 0 0.4445 270)
			(size 0.1397 0.1397)
			(layers "F.Cu" "F.Mask" "F.Paste")
			(net "FLT_HDD5_DRIVE")
			(options
				(clearance outline)
				(anchor circle)
			)
			(primitives
				(gr_poly
					(pts
						(arc
							(start -0.1778 -0.2794)
							(mid -0.249642 -0.249642)
							(end -0.2794 -0.1778)
						)
						(arc
							(start -0.2794 0.1778)
							(mid -0.249642 0.249642)
							(end -0.1778 0.2794)
						)
						(arc
							(start 0.1778 0.2794)
							(mid 0.249642 0.249642)
							(end 0.2794 0.1778)
						)
						(arc
							(start 0.2794 -0.1778)
							(mid 0.249642 -0.249642)
							(end 0.1778 -0.2794)
						)
					)
					(width 0)
					(fill yes)
				)
			)
		)
	)
	(footprint ""
		(layer "F.Cu")
		(at 57.6072 -276.4282)
		(property "Reference" "R203"
			(at 0 0 0)
			(layer "F.SilkS")
			(hide yes)
			(effects
				(font
					(size 1.27 1.27)
				)
			)
		)
		(property "Value" "4K7R2J-2-GP"
			(at 0.064008 -3.993896 0)
			(unlocked yes)
			(layer "F.Fab")
			(hide yes)
			(effects
				(font
					(size 1.016 1.016)
					(thickness 0.1524)
				)
			)
		)
		(property "Device Type" "R402H16"
			(at 0.064008 -5.517896 0)
			(unlocked yes)
			(layer "F.Fab")
			(hide yes)
			(effects
				(font
					(size 1.016 1.016)
					(thickness 0.1524)
				)
			)
		)
		(duplicate_pad_numbers_are_jumpers no)
		(fp_line
			(start -0.508 -0.9398)
			(end -0.508 0.9398)
			(stroke
				(width 0.1524)
				(type default)
			)
			(layer "F.SilkS")
		)
		(fp_line
			(start 0.508 -0.9398)
			(end -0.508 -0.9398)
			(stroke
				(width 0.1524)
				(type default)
			)
			(layer "F.SilkS")
		)
		(fp_rect
			(start -0.508 0.9398)
			(end 0.508 -0.9398)
			(stroke
				(width 0)
				(type default)
			)
			(fill no)
			(layer "F.CrtYd")
		)
		(fp_rect
			(start -0.508 0.9398)
			(end 0.508 -0.9398)
			(stroke
				(width 0)
				(type default)
			)
			(fill no)
			(layer "F.Fab")
		)
		(pad "1" smd custom
			(at 0 -0.4445)
			(size 0.1397 0.1397)
			(layers "F.Cu" "F.Mask" "F.Paste")
			(net "P3V3")
			(options
				(clearance outline)
				(anchor circle)
			)
			(primitives
				(gr_poly
					(pts
						(arc
							(start -0.1778 -0.2794)
							(mid -0.249642 -0.249642)
							(end -0.2794 -0.1778)
						)
						(arc
							(start -0.2794 0.1778)
							(mid -0.249642 0.249642)
							(end -0.1778 0.2794)
						)
						(arc
							(start 0.1778 0.2794)
							(mid 0.249642 0.249642)
							(end 0.2794 0.1778)
						)
						(arc
							(start 0.2794 -0.1778)
							(mid 0.249642 -0.249642)
							(end 0.1778 -0.2794)
						)
					)
					(width 0)
					(fill yes)
				)
			)
		)
		(pad "2" smd custom
			(at 0 0.4445)
			(size 0.1397 0.1397)
			(layers "F.Cu" "F.Mask" "F.Paste")
			(net "HDD_PRSNT_NET7")
			(options
				(clearance outline)
				(anchor circle)
			)
			(primitives
				(gr_poly
					(pts
						(arc
							(start -0.1778 -0.2794)
							(mid -0.249642 -0.249642)
							(end -0.2794 -0.1778)
						)
						(arc
							(start -0.2794 0.1778)
							(mid -0.249642 0.249642)
							(end -0.1778 0.2794)
						)
						(arc
							(start 0.1778 0.2794)
							(mid 0.249642 0.249642)
							(end 0.2794 0.1778)
						)
						(arc
							(start 0.2794 -0.1778)
							(mid 0.249642 -0.249642)
							(end 0.1778 -0.2794)
						)
					)
					(width 0)
					(fill yes)
				)
			)
		)
	)
	(footprint ""
		(layer "F.Cu")
		(at 25.653746 -119.0117)
		(property "Reference" "TP38"
			(at 0 0 0)
			(layer "F.SilkS")
			(hide yes)
			(effects
				(font
					(size 1.27 1.27)
				)
			)
		)
		(property "Value" "TPAD32-GP"
			(at 0 -3.166364 0)
			(unlocked yes)
			(layer "F.Fab")
			(hide yes)
			(effects
				(font
					(size 1.016 1.016)
					(thickness 0.1524)
				)
			)
		)
		(property "Device Type" "TPAD32"
			(at 0 -4.690618 0)
			(unlocked yes)
			(layer "F.Fab")
			(hide yes)
			(effects
				(font
					(size 1.016 1.016)
					(thickness 0.1524)
				)
			)
		)
		(duplicate_pad_numbers_are_jumpers no)
		(fp_poly
			(pts
				(arc
					(start 0.4064 0)
					(mid -0.4064 0)
					(end 0.4064 0)
				)
			)
			(stroke
				(width 0)
				(type default)
			)
			(fill no)
			(layer "F.CrtYd")
		)
		(fp_poly
			(pts
				(arc
					(start 0.7112 0)
					(mid -0.7112 0)
					(end 0.7112 0)
				)
			)
			(stroke
				(width 0)
				(type default)
			)
			(fill no)
			(layer "F.Fab")
		)
		(pad "1" smd circle
			(at 0 0)
			(size 0.8128 0.8128)
			(layers "F.Cu" "F.Mask" "F.Paste")
			(net "ACT_HDD13")
		)
	)
	(footprint ""
		(layer "F.Cu")
		(at 215.6714 -497.713 180)
		(property "Reference" "C113"
			(at 0 0 180)
			(layer "F.SilkS")
			(hide yes)
			(effects
				(font
					(size 1.27 1.27)
				)
			)
		)
		(property "Value" "SC10U25V6KX-1GP"
			(at -0.0762 -5.1308 180)
			(unlocked yes)
			(layer "F.Fab")
			(hide yes)
			(effects
				(font
					(size 1.016 1.016)
					(thickness 0.1524)
				)
			)
		)
		(property "Device Type" "C1206H71"
			(at -0.127 -6.6548 180)
			(unlocked yes)
			(layer "F.Fab")
			(hide yes)
			(effects
				(font
					(size 1.016 1.016)
					(thickness 0.1524)
				)
			)
		)
		(duplicate_pad_numbers_are_jumpers no)
		(fp_line
			(start 1.016 2.2352)
			(end -1.016 2.2352)
			(stroke
				(width 0.1524)
				(type default)
			)
			(layer "F.SilkS")
		)
		(fp_line
			(start 1.016 0.8382)
			(end 1.016 2.2352)
			(stroke
				(width 0.1524)
				(type default)
			)
			(layer "F.SilkS")
		)
		(fp_line
			(start 1.016 -2.2352)
			(end 1.016 -0.8382)
			(stroke
				(width 0.1524)
				(type default)
			)
			(layer "F.SilkS")
		)
		(fp_line
			(start -1.016 2.2352)
			(end -1.016 0.8382)
			(stroke
				(width 0.1524)
				(type default)
			)
			(layer "F.SilkS")
		)
		(fp_line
			(start -1.016 -0.8382)
			(end -1.016 -2.2352)
			(stroke
				(width 0.1524)
				(type default)
			)
			(layer "F.SilkS")
		)
		(fp_line
			(start -1.016 -2.2352)
			(end 1.016 -2.2352)
			(stroke
				(width 0.1524)
				(type default)
			)
			(layer "F.SilkS")
		)
		(fp_rect
			(start -1.0922 2.3114)
			(end 1.0922 -2.3114)
			(stroke
				(width 0)
				(type default)
			)
			(fill no)
			(layer "F.CrtYd")
		)
		(fp_poly
			(pts
				(xy 1.0922 -2.3114) (xy 1.0922 2.3114) (xy -1.0922 2.3114) (xy -1.0922 -2.3114)
			)
			(stroke
				(width 0)
				(type default)
			)
			(fill no)
			(layer "F.Fab")
		)
		(pad "1" smd rect
			(at 0 -1.397 180)
			(size 1.651 1.27)
			(layers "F.Cu" "F.Mask" "F.Paste")
			(net "P12V_HDD0")
		)
		(pad "2" smd rect
			(at 0 1.397 180)
			(size 1.651 1.27)
			(layers "F.Cu" "F.Mask" "F.Paste")
			(net "GND")
		)
	)
	(footprint ""
		(layer "F.Cu")
		(at 219.583 -497.6876 180)
		(property "Reference" "C115"
			(at 0 0 180)
			(layer "F.SilkS")
			(hide yes)
			(effects
				(font
					(size 1.27 1.27)
				)
			)
		)
		(property "Value" "SC1U25V3KX-1-GP"
			(at 0 -2.8194 180)
			(unlocked yes)
			(layer "F.Fab")
			(hide yes)
			(effects
				(font
					(size 1.016 1.016)
					(thickness 0.1524)
				)
			)
		)
		(property "Device Type" "C603H36"
			(at 0 -4.3434 180)
			(unlocked yes)
			(layer "F.Fab")
			(hide yes)
			(effects
				(font
					(size 1.016 1.016)
					(thickness 0.1524)
				)
			)
		)
		(duplicate_pad_numbers_are_jumpers no)
		(fp_line
			(start 0.508 0)
			(end -0.508 0)
			(stroke
				(width 0.2032)
				(type default)
			)
			(layer "F.SilkS")
		)
		(fp_rect
			(start -0.5842 1.3335)
			(end 0.5842 -1.3335)
			(stroke
				(width 0)
				(type default)
			)
			(fill no)
			(layer "F.CrtYd")
		)
		(fp_rect
			(start -0.5842 1.3335)
			(end 0.5842 -1.3335)
			(stroke
				(width 0)
				(type default)
			)
			(fill no)
			(layer "F.Fab")
		)
		(pad "1" smd custom
			(at 0 -0.762 180)
			(size 0.2159 0.2159)
			(layers "F.Cu" "F.Mask" "F.Paste")
			(net "P12V_HDD0")
			(options
				(clearance outline)
				(anchor circle)
			)
			(primitives
				(gr_poly
					(pts
						(arc
							(start -0.3302 -0.4318)
							(mid -0.402042 -0.402042)
							(end -0.4318 -0.3302)
						)
						(arc
							(start -0.4318 0.3302)
							(mid -0.402042 0.402042)
							(end -0.3302 0.4318)
						)
						(arc
							(start 0.3302 0.4318)
							(mid 0.402042 0.402042)
							(end 0.4318 0.3302)
						)
						(arc
							(start 0.4318 -0.3302)
							(mid 0.402042 -0.402042)
							(end 0.3302 -0.4318)
						)
					)
					(width 0)
					(fill yes)
				)
			)
		)
		(pad "2" smd custom
			(at 0 0.762 180)
			(size 0.2159 0.2159)
			(layers "F.Cu" "F.Mask" "F.Paste")
			(net "GND")
			(options
				(clearance outline)
				(anchor circle)
			)
			(primitives
				(gr_poly
					(pts
						(arc
							(start -0.3302 -0.4318)
							(mid -0.402042 -0.402042)
							(end -0.4318 -0.3302)
						)
						(arc
							(start -0.4318 0.3302)
							(mid -0.402042 0.402042)
							(end -0.3302 0.4318)
						)
						(arc
							(start 0.3302 0.4318)
							(mid 0.402042 0.402042)
							(end 0.4318 0.3302)
						)
						(arc
							(start 0.4318 -0.3302)
							(mid 0.402042 -0.402042)
							(end 0.3302 -0.4318)
						)
					)
					(width 0)
					(fill yes)
				)
			)
		)
	)
	(footprint ""
		(layer "F.Cu")
		(at 46.354746 -18.5547 180)
		(property "Reference" "PC20"
			(at 0 0 180)
			(layer "F.SilkS")
			(hide yes)
			(effects
				(font
					(size 1.27 1.27)
				)
			)
		)
		(property "Value" "SC2200P50V2KX-2GP"
			(at 1.1811 -2.7051 180)
			(unlocked yes)
			(layer "F.Fab")
			(hide yes)
			(effects
				(font
					(size 1.016 1.016)
					(thickness 0.1524)
				)
			)
		)
		(property "Device Type" "C402H22"
			(at 1.1811 -4.2291 180)
			(unlocked yes)
			(layer "F.Fab")
			(hide yes)
			(effects
				(font
					(size 1.016 1.016)
					(thickness 0.1524)
				)
			)
		)
		(duplicate_pad_numbers_are_jumpers no)
		(fp_rect
			(start -0.4318 0.9525)
			(end 0.4318 -0.9525)
			(stroke
				(width 0)
				(type default)
			)
			(fill no)
			(layer "F.CrtYd")
		)
		(fp_rect
			(start -0.4318 0.9525)
			(end 0.4318 -0.9525)
			(stroke
				(width 0)
				(type default)
			)
			(fill no)
			(layer "F.Fab")
		)
		(pad "1" smd custom
			(at 0 -0.4445 180)
			(size 0.1524 0.1524)
			(layers "F.Cu" "F.Mask" "F.Paste")
			(net "P5VB_LL")
			(options
				(clearance outline)
				(anchor circle)
			)
			(primitives
				(gr_poly
					(pts
						(arc
							(start 0.3048 -0.2032)
							(mid 0.275042 -0.275042)
							(end 0.2032 -0.3048)
						)
						(arc
							(start -0.2032 -0.3048)
							(mid -0.275042 -0.275042)
							(end -0.3048 -0.2032)
						)
						(arc
							(start -0.3048 0.2032)
							(mid -0.275042 0.275042)
							(end -0.2032 0.3048)
						)
						(arc
							(start 0.2032 0.3048)
							(mid 0.275042 0.275042)
							(end 0.3048 0.2032)
						)
					)
					(width 0)
					(fill yes)
				)
			)
		)
		(pad "2" smd custom
			(at 0 0.4445 180)
			(size 0.1524 0.1524)
			(layers "F.Cu" "F.Mask" "F.Paste")
			(net "P5VB_SNB")
			(options
				(clearance outline)
				(anchor circle)
			)
			(primitives
				(gr_poly
					(pts
						(arc
							(start 0.3048 -0.2032)
							(mid 0.275042 -0.275042)
							(end 0.2032 -0.3048)
						)
						(arc
							(start -0.2032 -0.3048)
							(mid -0.275042 -0.275042)
							(end -0.3048 -0.2032)
						)
						(arc
							(start -0.3048 0.2032)
							(mid -0.275042 0.275042)
							(end -0.2032 0.3048)
						)
						(arc
							(start 0.2032 0.3048)
							(mid 0.275042 0.275042)
							(end 0.3048 0.2032)
						)
					)
					(width 0)
					(fill yes)
				)
			)
		)
	)
	(footprint ""
		(layer "F.Cu")
		(at 197.911974 -388.084822 -90)
		(property "Reference" "R428"
			(at 0 0 270)
			(layer "F.SilkS")
			(hide yes)
			(effects
				(font
					(size 1.27 1.27)
				)
			)
		)
		(property "Value" "4K7R2J-2-GP"
			(at 0.064008 -3.993896 270)
			(unlocked yes)
			(layer "F.Fab")
			(hide yes)
			(effects
				(font
					(size 1.016 1.016)
					(thickness 0.1524)
				)
			)
		)
		(property "Device Type" "R402H16"
			(at 0.064008 -5.517896 270)
			(unlocked yes)
			(layer "F.Fab")
			(hide yes)
			(effects
				(font
					(size 1.016 1.016)
					(thickness 0.1524)
				)
			)
		)
		(duplicate_pad_numbers_are_jumpers no)
		(fp_line
			(start -0.508 -0.9398)
			(end -0.508 0.9398)
			(stroke
				(width 0.1524)
				(type default)
			)
			(layer "F.SilkS")
		)
		(fp_line
			(start 0.508 -0.9398)
			(end -0.508 -0.9398)
			(stroke
				(width 0.1524)
				(type default)
			)
			(layer "F.SilkS")
		)
		(fp_rect
			(start -0.508 0.9398)
			(end 0.508 -0.9398)
			(stroke
				(width 0)
				(type default)
			)
			(fill no)
			(layer "F.CrtYd")
		)
		(fp_rect
			(start -0.508 0.9398)
			(end 0.508 -0.9398)
			(stroke
				(width 0)
				(type default)
			)
			(fill no)
			(layer "F.Fab")
		)
		(pad "1" smd custom
			(at 0 -0.4445 270)
			(size 0.1397 0.1397)
			(layers "F.Cu" "F.Mask" "F.Paste")
			(net "P3V3")
			(options
				(clearance outline)
				(anchor circle)
			)
			(primitives
				(gr_poly
					(pts
						(arc
							(start -0.1778 -0.2794)
							(mid -0.249642 -0.249642)
							(end -0.2794 -0.1778)
						)
						(arc
							(start -0.2794 0.1778)
							(mid -0.249642 0.249642)
							(end -0.1778 0.2794)
						)
						(arc
							(start 0.1778 0.2794)
							(mid 0.249642 0.249642)
							(end 0.2794 0.1778)
						)
						(arc
							(start 0.2794 -0.1778)
							(mid 0.249642 -0.249642)
							(end 0.1778 -0.2794)
						)
					)
					(width 0)
					(fill yes)
				)
			)
		)
		(pad "2" smd custom
			(at 0 0.4445 270)
			(size 0.1397 0.1397)
			(layers "F.Cu" "F.Mask" "F.Paste")
			(net "SAS_EXP_B_PWR1")
			(options
				(clearance outline)
				(anchor circle)
			)
			(primitives
				(gr_poly
					(pts
						(arc
							(start -0.1778 -0.2794)
							(mid -0.249642 -0.249642)
							(end -0.2794 -0.1778)
						)
						(arc
							(start -0.2794 0.1778)
							(mid -0.249642 0.249642)
							(end -0.1778 0.2794)
						)
						(arc
							(start 0.1778 0.2794)
							(mid 0.249642 0.249642)
							(end 0.2794 0.1778)
						)
						(arc
							(start 0.2794 -0.1778)
							(mid 0.249642 -0.249642)
							(end 0.1778 -0.2794)
						)
					)
					(width 0)
					(fill yes)
				)
			)
		)
	)
	(footprint ""
		(layer "F.Cu")
		(at 21.971 -280.543 -90)
		(property "Reference" "C213"
			(at 0 0 270)
			(layer "F.SilkS")
			(hide yes)
			(effects
				(font
					(size 1.27 1.27)
				)
			)
		)
		(property "Value" "SCD1U10V2KX-5GP"
			(at 1.1811 -2.7051 270)
			(unlocked yes)
			(layer "F.Fab")
			(hide yes)
			(effects
				(font
					(size 1.016 1.016)
					(thickness 0.1524)
				)
			)
		)
		(property "Device Type" "C402H22"
			(at 1.1811 -4.2291 270)
			(unlocked yes)
			(layer "F.Fab")
			(hide yes)
			(effects
				(font
					(size 1.016 1.016)
					(thickness 0.1524)
				)
			)
		)
		(duplicate_pad_numbers_are_jumpers no)
		(fp_rect
			(start -0.4318 0.9525)
			(end 0.4318 -0.9525)
			(stroke
				(width 0)
				(type default)
			)
			(fill no)
			(layer "F.CrtYd")
		)
		(fp_rect
			(start -0.4318 0.9525)
			(end 0.4318 -0.9525)
			(stroke
				(width 0)
				(type default)
			)
			(fill no)
			(layer "F.Fab")
		)
		(pad "1" smd custom
			(at 0 -0.4445 270)
			(size 0.1524 0.1524)
			(layers "F.Cu" "F.Mask" "F.Paste")
			(net "P3V3")
			(options
				(clearance outline)
				(anchor circle)
			)
			(primitives
				(gr_poly
					(pts
						(arc
							(start 0.3048 -0.2032)
							(mid 0.275042 -0.275042)
							(end 0.2032 -0.3048)
						)
						(arc
							(start -0.2032 -0.3048)
							(mid -0.275042 -0.275042)
							(end -0.3048 -0.2032)
						)
						(arc
							(start -0.3048 0.2032)
							(mid -0.275042 0.275042)
							(end -0.2032 0.3048)
						)
						(arc
							(start 0.2032 0.3048)
							(mid 0.275042 0.275042)
							(end 0.3048 0.2032)
						)
					)
					(width 0)
					(fill yes)
				)
			)
		)
		(pad "2" smd custom
			(at 0 0.4445 270)
			(size 0.1524 0.1524)
			(layers "F.Cu" "F.Mask" "F.Paste")
			(net "GND")
			(options
				(clearance outline)
				(anchor circle)
			)
			(primitives
				(gr_poly
					(pts
						(arc
							(start 0.3048 -0.2032)
							(mid 0.275042 -0.275042)
							(end 0.2032 -0.3048)
						)
						(arc
							(start -0.2032 -0.3048)
							(mid -0.275042 -0.275042)
							(end -0.3048 -0.2032)
						)
						(arc
							(start -0.3048 0.2032)
							(mid -0.275042 0.275042)
							(end -0.2032 0.3048)
						)
						(arc
							(start 0.2032 0.3048)
							(mid 0.275042 0.275042)
							(end 0.3048 0.2032)
						)
					)
					(width 0)
					(fill yes)
				)
			)
		)
	)
	(footprint ""
		(layer "F.Cu")
		(at 5.079746 -495.8207 -90)
		(property "Reference" "PR45"
			(at 0 0 270)
			(layer "F.SilkS")
			(hide yes)
			(effects
				(font
					(size 1.27 1.27)
				)
			)
		)
		(property "Value" "73K2R2F-GP"
			(at 0.064008 -3.993896 270)
			(unlocked yes)
			(layer "F.Fab")
			(hide yes)
			(effects
				(font
					(size 1.016 1.016)
					(thickness 0.1524)
				)
			)
		)
		(property "Device Type" "R402H16"
			(at 0.064008 -5.517896 270)
			(unlocked yes)
			(layer "F.Fab")
			(hide yes)
			(effects
				(font
					(size 1.016 1.016)
					(thickness 0.1524)
				)
			)
		)
		(duplicate_pad_numbers_are_jumpers no)
		(fp_line
			(start -0.508 -0.9398)
			(end -0.508 0.9398)
			(stroke
				(width 0.1524)
				(type default)
			)
			(layer "F.SilkS")
		)
		(fp_line
			(start 0.508 -0.9398)
			(end -0.508 -0.9398)
			(stroke
				(width 0.1524)
				(type default)
			)
			(layer "F.SilkS")
		)
		(fp_rect
			(start -0.508 0.9398)
			(end 0.508 -0.9398)
			(stroke
				(width 0)
				(type default)
			)
			(fill no)
			(layer "F.CrtYd")
		)
		(fp_rect
			(start -0.508 0.9398)
			(end 0.508 -0.9398)
			(stroke
				(width 0)
				(type default)
			)
			(fill no)
			(layer "F.Fab")
		)
		(pad "1" smd custom
			(at 0 -0.4445 270)
			(size 0.1397 0.1397)
			(layers "F.Cu" "F.Mask" "F.Paste")
			(net "P5VC_VFB")
			(options
				(clearance outline)
				(anchor circle)
			)
			(primitives
				(gr_poly
					(pts
						(arc
							(start -0.1778 -0.2794)
							(mid -0.249642 -0.249642)
							(end -0.2794 -0.1778)
						)
						(arc
							(start -0.2794 0.1778)
							(mid -0.249642 0.249642)
							(end -0.1778 0.2794)
						)
						(arc
							(start 0.1778 0.2794)
							(mid 0.249642 0.249642)
							(end 0.2794 0.1778)
						)
						(arc
							(start 0.2794 -0.1778)
							(mid 0.249642 -0.249642)
							(end 0.1778 -0.2794)
						)
					)
					(width 0)
					(fill yes)
				)
			)
		)
		(pad "2" smd custom
			(at 0 0.4445 270)
			(size 0.1397 0.1397)
			(layers "F.Cu" "F.Mask" "F.Paste")
			(net "P5VC_VFB_NET")
			(options
				(clearance outline)
				(anchor circle)
			)
			(primitives
				(gr_poly
					(pts
						(arc
							(start -0.1778 -0.2794)
							(mid -0.249642 -0.249642)
							(end -0.2794 -0.1778)
						)
						(arc
							(start -0.2794 0.1778)
							(mid -0.249642 0.249642)
							(end -0.1778 0.2794)
						)
						(arc
							(start 0.1778 0.2794)
							(mid 0.249642 0.249642)
							(end 0.2794 0.1778)
						)
						(arc
							(start 0.2794 -0.1778)
							(mid 0.249642 -0.249642)
							(end 0.1778 -0.2794)
						)
					)
					(width 0)
					(fill yes)
				)
			)
		)
	)
	(footprint ""
		(layer "F.Cu")
		(at 17.500092 -335.330038 -90)
		(property "Reference" "SKT12"
			(at 0 0 270)
			(layer "F.SilkS")
			(hide yes)
			(effects
				(font
					(size 1.27 1.27)
				)
			)
		)
		(property "Value" "SKT-SATA14P-15P-12-GP"
			(at -22.6187 8.1788 270)
			(unlocked yes)
			(layer "F.Fab")
			(hide yes)
			(effects
				(font
					(size 1.016 1.016)
					(thickness 0.1524)
				)
			)
		)
		(property "Device Type" "87945-1001"
			(at -22.6187 6.6548 270)
			(unlocked yes)
			(layer "F.Fab")
			(hide yes)
			(effects
				(font
					(size 1.016 1.016)
					(thickness 0.1524)
				)
			)
		)
		(duplicate_pad_numbers_are_jumpers no)
		(fp_line
			(start -20.4724 9.652)
			(end -20.4724 2.3114)
			(stroke
				(width 0.1524)
				(type default)
			)
			(layer "F.SilkS")
		)
		(fp_line
			(start -17.8435 9.652)
			(end -20.4724 9.652)
			(stroke
				(width 0.1524)
				(type default)
			)
			(layer "F.SilkS")
		)
		(fp_line
			(start 17.8435 9.652)
			(end 17.8435 7.9502)
			(stroke
				(width 0.1524)
				(type default)
			)
			(layer "F.SilkS")
		)
		(fp_line
			(start 20.4724 9.652)
			(end 17.8435 9.652)
			(stroke
				(width 0.1524)
				(type default)
			)
			(layer "F.SilkS")
		)
		(fp_line
			(start -17.8435 7.9502)
			(end -17.8435 9.652)
			(stroke
				(width 0.1524)
				(type default)
			)
			(layer "F.SilkS")
		)
		(fp_line
			(start 17.8435 7.9502)
			(end -17.8435 7.9502)
			(stroke
				(width 0.1524)
				(type default)
			)
			(layer "F.SilkS")
		)
		(fp_line
			(start -23.7617 2.3114)
			(end -23.7617 -2.3114)
			(stroke
				(width 0.1524)
				(type default)
			)
			(layer "F.SilkS")
		)
		(fp_line
			(start -20.4724 2.3114)
			(end -23.7617 2.3114)
			(stroke
				(width 0.1524)
				(type default)
			)
			(layer "F.SilkS")
		)
		(fp_line
			(start 20.4724 2.3114)
			(end 20.4724 9.652)
			(stroke
				(width 0.1524)
				(type default)
			)
			(layer "F.SilkS")
		)
		(fp_line
			(start 23.7617 2.3114)
			(end 20.4724 2.3114)
			(stroke
				(width 0.1524)
				(type default)
			)
			(layer "F.SilkS")
		)
		(fp_line
			(start -23.117556 0.5461)
			(end -23.117556 -0.5461)
			(stroke
				(width 0.3048)
				(type default)
			)
			(layer "F.SilkS")
		)
		(fp_line
			(start 20.882356 0.5461)
			(end 20.882356 -0.5461)
			(stroke
				(width 0.3048)
				(type default)
			)
			(layer "F.SilkS")
		)
		(fp_line
			(start -20.882356 -0.5461)
			(end -20.882356 0.5461)
			(stroke
				(width 0.3048)
				(type default)
			)
			(layer "F.SilkS")
		)
		(fp_line
			(start 23.117556 -0.5461)
			(end 23.117556 0.5461)
			(stroke
				(width 0.3048)
				(type default)
			)
			(layer "F.SilkS")
		)
		(fp_line
			(start -23.7617 -2.3114)
			(end -20.4724 -2.3114)
			(stroke
				(width 0.1524)
				(type default)
			)
			(layer "F.SilkS")
		)
		(fp_line
			(start -20.4724 -2.3114)
			(end -20.4724 -5.7658)
			(stroke
				(width 0.1524)
				(type default)
			)
			(layer "F.SilkS")
		)
		(fp_line
			(start 20.4724 -2.3114)
			(end 23.7617 -2.3114)
			(stroke
				(width 0.1524)
				(type default)
			)
			(layer "F.SilkS")
		)
		(fp_line
			(start 23.7617 -2.3114)
			(end 23.7617 2.3114)
			(stroke
				(width 0.1524)
				(type default)
			)
			(layer "F.SilkS")
		)
		(fp_line
			(start -20.4724 -5.7658)
			(end 20.4724 -5.7658)
			(stroke
				(width 0.1524)
				(type default)
			)
			(layer "F.SilkS")
		)
		(fp_line
			(start 20.4724 -5.7658)
			(end 20.4724 -2.3114)
			(stroke
				(width 0.1524)
				(type default)
			)
			(layer "F.SilkS")
		)
		(fp_line
			(start -15.3924 -5.8547)
			(end -16.3576 -5.8547)
			(stroke
				(width 0.3302)
				(type default)
			)
			(layer "F.SilkS")
		)
		(fp_arc
			(start -20.882356 0.5461)
			(mid -21.999956 1.6637)
			(end -23.117556 0.5461)
			(stroke
				(width 0.3048)
				(type default)
			)
			(layer "F.SilkS")
		)
		(fp_arc
			(start 23.117556 0.5461)
			(mid 21.999956 1.6637)
			(end 20.882356 0.5461)
			(stroke
				(width 0.3048)
				(type default)
			)
			(layer "F.SilkS")
		)
		(fp_arc
			(start -23.117556 -0.5461)
			(mid -21.999956 -1.6637)
			(end -20.882356 -0.5461)
			(stroke
				(width 0.3048)
				(type default)
			)
			(layer "F.SilkS")
		)
		(fp_arc
			(start 20.882356 -0.5461)
			(mid 21.999956 -1.6637)
			(end 23.117556 -0.5461)
			(stroke
				(width 0.3048)
				(type default)
			)
			(layer "F.SilkS")
		)
		(fp_poly
			(pts
				(xy -15.87119 -5.838698) (xy -15.23619 -6.473698) (xy -16.50619 -6.473698)
			)
			(stroke
				(width 0)
				(type default)
			)
			(fill yes)
			(layer "F.SilkS")
		)
		(fp_poly
			(pts
				(xy -20.2184 -5.5118) (xy 20.2184 -5.5118) (xy 20.2184 -2.0574) (xy 23.5077 -2.0574) (xy 23.5077 2.0574)
				(xy 20.2184 2.0574) (xy 20.2184 9.398) (xy 18.0975 9.398) (xy 18.0975 7.6962) (xy -18.0975 7.6962)
				(xy -18.0975 9.398) (xy -20.2184 9.398) (xy -20.2184 2.0574) (xy -23.5077 2.0574) (xy -23.5077 -2.0574)
				(xy -20.2184 -2.0574)
			)
			(stroke
				(width 0)
				(type default)
			)
			(fill no)
			(layer "F.CrtYd")
		)
		(fp_poly
			(pts
				(xy -20.2184 -5.5118) (xy -20.2184 -6.0198) (xy -20.7264 -6.0198) (xy -20.7264 -2.5654) (xy -24.0157 -2.5654)
				(xy -24.0157 2.5654) (xy -20.7264 2.5654) (xy -20.7264 9.906) (xy -17.5895 9.906) (xy -17.5895 8.2042)
				(xy 17.5895 8.2042) (xy 17.5895 9.906) (xy 20.7264 9.906) (xy 20.7264 2.5654) (xy 24.0157 2.5654)
				(xy 24.0157 -2.5654) (xy 20.7264 -2.5654) (xy 20.7264 -6.0198) (xy -20.21586 -6.0198) (xy -20.21586 -5.5118)
				(xy 20.2184 -5.5118) (xy 20.2184 -2.0574) (xy 23.5077 -2.0574) (xy 23.5077 2.0574) (xy 20.2184 2.0574)
				(xy 20.2184 9.398) (xy 18.0975 9.398) (xy 18.0975 7.6962) (xy -18.0975 7.6962) (xy -18.0975 9.398)
				(xy -20.2184 9.398) (xy -20.2184 2.0574) (xy -23.5077 2.0574) (xy -23.5077 -2.0574) (xy -20.2184 -2.0574)
			)
			(stroke
				(width 0)
				(type default)
			)
			(fill no)
			(layer "F.CrtYd")
		)
		(fp_poly
			(pts
				(xy -20.7264 -6.0198) (xy -20.7264 -2.5654) (xy -24.0157 -2.5654) (xy -24.0157 2.5654) (xy -20.7264 2.5654)
				(xy -20.7264 9.906) (xy -17.5895 9.906) (xy -17.5895 8.2042) (xy 17.5895 8.2042) (xy 17.5895 9.906)
				(xy 20.7264 9.906) (xy 20.7264 2.5654) (xy 24.0157 2.5654) (xy 24.0157 -2.5654) (xy 20.7264 -2.5654)
				(xy 20.7264 -6.0198)
			)
			(stroke
				(width 0)
				(type default)
			)
			(fill no)
			(layer "F.Fab")
		)
		(pad "" np_thru_hole circle
			(at -18.999962 -2.350008 270)
			(size 0.254 0.254)
			(drill 1.8542)
			(layers "*.Cu" "*.Mask")
			(clearance 1.1557)
			(thermal_gap 1.1557)
		)
		(pad "" np_thru_hole circle
			(at 18.999962 -2.350008 270)
			(size 0.254 0.254)
			(drill 1.8542)
			(layers "*.Cu" "*.Mask")
			(clearance 1.1557)
			(thermal_gap 1.1557)
		)
		(pad "H1" thru_hole oval
			(at -21.999956 0 270)
			(size 1.524 2.6162)
			(drill oval 0.8128 1.905)
			(layers "*.Cu" "*.Mask")
			(remove_unused_layers no)
			(net "GND")
			(clearance 0.1524)
			(thermal_gap 0.1524)
		)
		(pad "H2" thru_hole oval
			(at 21.999956 0 270)
			(size 1.524 2.6162)
			(drill oval 0.8128 1.905)
			(layers "*.Cu" "*.Mask")
			(remove_unused_layers no)
			(net "GND")
			(clearance 0.1524)
			(thermal_gap 0.1524)
		)
		(pad "P1" smd rect
			(at -1.89992 -4.249928 270)
			(size 0.6604 2.3876)
			(layers "F.Cu" "F.Mask" "F.Paste")
			(net "Net_60")
		)
		(pad "P2" smd rect
			(at -0.62992 -4.249928 270)
			(size 0.6604 2.3876)
			(layers "F.Cu" "F.Mask" "F.Paste")
			(net "Net_59")
		)
		(pad "P3" smd rect
			(at 0.64008 -4.249928 270)
			(size 0.6604 2.3876)
			(layers "F.Cu" "F.Mask" "F.Paste")
			(net "Net_58")
		)
		(pad "P4" smd rect
			(at 1.91008 -4.249928 270)
			(size 0.6604 2.3876)
			(layers "F.Cu" "F.Mask" "F.Paste")
			(net "GND")
		)
		(pad "P5" smd rect
			(at 3.18008 -4.249928 270)
			(size 0.6604 2.3876)
			(layers "F.Cu" "F.Mask" "F.Paste")
			(net "HDD_PRSNT_NET11")
		)
		(pad "P6" smd rect
			(at 4.45008 -4.249928 270)
			(size 0.6604 2.3876)
			(layers "F.Cu" "F.Mask" "F.Paste")
			(net "GND")
		)
		(pad "P7" smd rect
			(at 5.72008 -4.249928 270)
			(size 0.6604 2.3876)
			(layers "F.Cu" "F.Mask" "F.Paste")
			(net "5V_PRE_11")
		)
		(pad "P8" smd rect
			(at 6.99008 -4.249928 270)
			(size 0.6604 2.3876)
			(layers "F.Cu" "F.Mask" "F.Paste")
			(net "P5V_HDD11")
		)
		(pad "P9" smd rect
			(at 8.26008 -4.249928 270)
			(size 0.6604 2.3876)
			(layers "F.Cu" "F.Mask" "F.Paste")
			(net "P5V_HDD11")
		)
		(pad "P10" smd rect
			(at 9.53008 -4.249928 270)
			(size 0.6604 2.3876)
			(layers "F.Cu" "F.Mask" "F.Paste")
			(net "GND")
		)
		(pad "P11" smd rect
			(at 10.80008 -4.249928 270)
			(size 0.6604 2.3876)
			(layers "F.Cu" "F.Mask" "F.Paste")
			(net "ACT_HDD11")
		)
		(pad "P12" smd rect
			(at 12.07008 -4.249928 270)
			(size 0.6604 2.3876)
			(layers "F.Cu" "F.Mask" "F.Paste")
			(net "GND")
		)
		(pad "P13" smd rect
			(at 13.34008 -4.249928 270)
			(size 0.6604 2.3876)
			(layers "F.Cu" "F.Mask" "F.Paste")
			(net "12V_PRE_11")
		)
		(pad "P14" smd rect
			(at 14.61008 -4.249928 270)
			(size 0.6604 2.3876)
			(layers "F.Cu" "F.Mask" "F.Paste")
			(net "P12V_HDD11")
		)
		(pad "P15" smd rect
			(at 15.88008 -4.249928 270)
			(size 0.6604 2.3876)
			(layers "F.Cu" "F.Mask" "F.Paste")
			(net "P12V_HDD11")
		)
		(pad "S1" smd rect
			(at -15.86992 -4.249928 270)
			(size 0.6604 2.3876)
			(layers "F.Cu" "F.Mask" "F.Paste")
			(net "GND")
		)
		(pad "S2" smd rect
			(at -14.59992 -4.249928 270)
			(size 0.6604 2.3876)
			(layers "F.Cu" "F.Mask" "F.Paste")
			(net "SAS2X28_A_HDD11_TX_+")
		)
		(pad "S3" smd rect
			(at -13.32992 -4.249928 270)
			(size 0.6604 2.3876)
			(layers "F.Cu" "F.Mask" "F.Paste")
			(net "SAS2X28_A_HDD11_TX_-")
		)
		(pad "S4" smd rect
			(at -12.05992 -4.249928 270)
			(size 0.6604 2.3876)
			(layers "F.Cu" "F.Mask" "F.Paste")
			(net "GND")
		)
		(pad "S5" smd rect
			(at -10.78992 -4.249928 270)
			(size 0.6604 2.3876)
			(layers "F.Cu" "F.Mask" "F.Paste")
			(net "SAS2X28_DRIVE_RX_N_A11")
		)
		(pad "S6" smd rect
			(at -9.51992 -4.249928 270)
			(size 0.6604 2.3876)
			(layers "F.Cu" "F.Mask" "F.Paste")
			(net "SAS2X28_DRIVE_RX_P_A11")
		)
		(pad "S7" smd rect
			(at -8.24992 -4.249928 270)
			(size 0.6604 2.3876)
			(layers "F.Cu" "F.Mask" "F.Paste")
			(net "GND")
		)
		(pad "S8" smd rect
			(at -7.480046 -2.100072 270)
			(size 0.508 1.905)
			(layers "F.Cu" "F.Mask" "F.Paste")
			(net "GND")
		)
		(pad "S9" smd rect
			(at -6.679946 -2.100072 270)
			(size 0.508 1.905)
			(layers "F.Cu" "F.Mask" "F.Paste")
			(net "SAS2X28_B_HDD11_TX_+")
		)
		(pad "S10" smd rect
			(at -5.8801 -2.100072 270)
			(size 0.508 1.905)
			(layers "F.Cu" "F.Mask" "F.Paste")
			(net "SAS2X28_B_HDD11_TX_-")
		)
		(pad "S11" smd rect
			(at -5.08 -2.100072 270)
			(size 0.508 1.905)
			(layers "F.Cu" "F.Mask" "F.Paste")
			(net "GND")
		)
		(pad "S12" smd rect
			(at -4.2799 -2.100072 270)
			(size 0.508 1.905)
			(layers "F.Cu" "F.Mask" "F.Paste")
			(net "SAS2X28_DRIVE_RX_N_B11")
		)
		(pad "S13" smd rect
			(at -3.480054 -2.100072 270)
			(size 0.508 1.905)
			(layers "F.Cu" "F.Mask" "F.Paste")
			(net "SAS2X28_DRIVE_RX_P_B11")
		)
		(pad "S14" smd rect
			(at -2.679954 -2.100072 270)
			(size 0.508 1.905)
			(layers "F.Cu" "F.Mask" "F.Paste")
			(net "GND")
		)
		(zone
			(layers "F.Cu" "B.Cu" "In1.Cu" "In2.Cu" "In3.Cu" "In4.Cu" "In5.Cu" "In6.Cu")
			(hatch none 0.5)
			(connect_pads
				(clearance 0)
			)
			(min_thickness 0.25)
			(keepout
				(tracks not_allowed)
				(vias allowed)
				(pads allowed)
				(copperpour not_allowed)
				(footprints allowed)
			)
			(placement
				(enabled no)
				(sheetname "")
			)
			(fill
				(thermal_gap 0.5)
				(thermal_bridge_width 0.5)
				(island_removal_mode 0)
			)
			(polygon
				(pts
					(arc
						(start 21.082 -354.33)
						(mid 18.6182 -354.33)
						(end 21.082 -354.33)
					)
				)
			)
		)
		(zone
			(layers "F.Cu" "B.Cu" "In1.Cu" "In2.Cu" "In3.Cu" "In4.Cu" "In5.Cu" "In6.Cu")
			(hatch none 0.5)
			(connect_pads
				(clearance 0)
			)
			(min_thickness 0.25)
			(keepout
				(tracks not_allowed)
				(vias allowed)
				(pads allowed)
				(copperpour not_allowed)
				(footprints allowed)
			)
			(placement
				(enabled no)
				(sheetname "")
			)
			(fill
				(thermal_gap 0.5)
				(thermal_bridge_width 0.5)
				(island_removal_mode 0)
			)
			(polygon
				(pts
					(arc
						(start 21.082 -316.330076)
						(mid 18.6182 -316.330076)
						(end 21.082 -316.330076)
					)
				)
			)
		)
	)
	(footprint ""
		(layer "F.Cu")
		(at 205.953614 -281.613864 90)
		(property "Reference" "Q5"
			(at 0 0 90)
			(layer "F.SilkS")
			(hide yes)
			(effects
				(font
					(size 1.27 1.27)
				)
			)
		)
		(property "Value" "AO4406AL-GP"
			(at -3.707384 -1.5367 90)
			(unlocked yes)
			(layer "F.Fab")
			(hide yes)
			(effects
				(font
					(size 1.016 1.016)
					(thickness 0.1524)
				)
			)
		)
		(property "Device Type" "SOIC8H69"
			(at -3.707384 -3.0607 90)
			(unlocked yes)
			(layer "F.Fab")
			(hide yes)
			(effects
				(font
					(size 1.016 1.016)
					(thickness 0.1524)
				)
			)
		)
		(duplicate_pad_numbers_are_jumpers no)
		(fp_line
			(start 2.1336 -1.4224)
			(end -2.7432 -1.4224)
			(stroke
				(width 0.1524)
				(type default)
			)
			(layer "F.SilkS")
		)
		(fp_line
			(start -2.7432 -1.4224)
			(end -2.7432 1.4224)
			(stroke
				(width 0.1524)
				(type default)
			)
			(layer "F.SilkS")
		)
		(fp_line
			(start -2.7178 -0.508)
			(end -2.1844 -0.0508)
			(stroke
				(width 0.1524)
				(type default)
			)
			(layer "F.SilkS")
		)
		(fp_line
			(start -2.1844 -0.0508)
			(end -2.7178 0.508)
			(stroke
				(width 0.1524)
				(type default)
			)
			(layer "F.SilkS")
		)
		(fp_line
			(start 2.1336 1.4224)
			(end 2.1336 -1.4224)
			(stroke
				(width 0.1524)
				(type default)
			)
			(layer "F.SilkS")
		)
		(fp_line
			(start -2.7432 1.4224)
			(end 2.1336 1.4224)
			(stroke
				(width 0.1524)
				(type default)
			)
			(layer "F.SilkS")
		)
		(fp_line
			(start -2.7432 1.4224)
			(end -2.6416 1.4224)
			(stroke
				(width 0.1524)
				(type default)
			)
			(layer "F.SilkS")
		)
		(fp_line
			(start -2.6289 3.4417)
			(end -2.6289 1.4732)
			(stroke
				(width 0.381)
				(type default)
			)
			(layer "F.SilkS")
		)
		(fp_poly
			(pts
				(xy -2.2098 -1.4224) (xy -2.2098 1.4224) (xy 2.2098 1.4224) (xy 2.2098 -1.4224)
			)
			(stroke
				(width 0)
				(type default)
			)
			(fill yes)
			(layer "F.SilkS")
		)
		(fp_rect
			(start -2.450084 2.999994)
			(end 2.450084 -2.999994)
			(stroke
				(width 0)
				(type default)
			)
			(fill no)
			(layer "F.CrtYd")
		)
		(fp_poly
			(pts
				(xy -2.8194 3.6322) (xy -2.8194 -3.6322) (xy 2.8194 -3.6322) (xy 2.8194 1.18364) (xy 2.450084 1.18364)
				(xy 2.450084 -2.999994) (xy -2.450084 -2.999994) (xy -2.450084 2.999994) (xy 2.450084 2.999994)
				(xy 2.450084 1.18618) (xy 2.8194 1.18618) (xy 2.8194 3.6322)
			)
			(stroke
				(width 0)
				(type default)
			)
			(fill no)
			(layer "F.CrtYd")
		)
		(fp_rect
			(start -2.8194 3.6322)
			(end 2.8194 -3.6322)
			(stroke
				(width 0)
				(type default)
			)
			(fill no)
			(layer "F.Fab")
		)
		(pad "1" smd rect
			(at -1.905 2.54 90)
			(size 0.635 1.651)
			(layers "F.Cu" "F.Mask" "F.Paste")
			(net "P5V_HDD2")
		)
		(pad "2" smd rect
			(at -0.635 2.54 90)
			(size 0.635 1.651)
			(layers "F.Cu" "F.Mask" "F.Paste")
			(net "P5V_HDD2")
		)
		(pad "3" smd rect
			(at 0.635 2.54 90)
			(size 0.635 1.651)
			(layers "F.Cu" "F.Mask" "F.Paste")
			(net "P5V_HDD2")
		)
		(pad "4" smd rect
			(at 1.905 2.54 90)
			(size 0.635 1.651)
			(layers "F.Cu" "F.Mask" "F.Paste")
			(net "SW_HDD2_P")
		)
		(pad "5" smd rect
			(at 1.905 -2.54 90)
			(size 0.635 1.651)
			(layers "F.Cu" "F.Mask" "F.Paste")
			(net "P5VA")
		)
		(pad "6" smd rect
			(at 0.635 -2.54 90)
			(size 0.635 1.651)
			(layers "F.Cu" "F.Mask" "F.Paste")
			(net "P5VA")
		)
		(pad "7" smd rect
			(at -0.635 -2.54 90)
			(size 0.635 1.651)
			(layers "F.Cu" "F.Mask" "F.Paste")
			(net "P5VA")
		)
		(pad "8" smd rect
			(at -1.905 -2.54 90)
			(size 0.635 1.651)
			(layers "F.Cu" "F.Mask" "F.Paste")
			(net "P5VA")
		)
	)
	(footprint ""
		(layer "F.Cu")
		(at 209.041746 -454.1647 -90)
		(property "Reference" "R337"
			(at 0 0 270)
			(layer "F.SilkS")
			(hide yes)
			(effects
				(font
					(size 1.27 1.27)
				)
			)
		)
		(property "Value" "4K7R2J-2-GP"
			(at 0.064008 -3.993896 270)
			(unlocked yes)
			(layer "F.Fab")
			(hide yes)
			(effects
				(font
					(size 1.016 1.016)
					(thickness 0.1524)
				)
			)
		)
		(property "Device Type" "R402H16"
			(at 0.064008 -5.517896 270)
			(unlocked yes)
			(layer "F.Fab")
			(hide yes)
			(effects
				(font
					(size 1.016 1.016)
					(thickness 0.1524)
				)
			)
		)
		(duplicate_pad_numbers_are_jumpers no)
		(fp_line
			(start -0.508 -0.9398)
			(end -0.508 0.9398)
			(stroke
				(width 0.1524)
				(type default)
			)
			(layer "F.SilkS")
		)
		(fp_line
			(start 0.508 -0.9398)
			(end -0.508 -0.9398)
			(stroke
				(width 0.1524)
				(type default)
			)
			(layer "F.SilkS")
		)
		(fp_rect
			(start -0.508 0.9398)
			(end 0.508 -0.9398)
			(stroke
				(width 0)
				(type default)
			)
			(fill no)
			(layer "F.CrtYd")
		)
		(fp_rect
			(start -0.508 0.9398)
			(end 0.508 -0.9398)
			(stroke
				(width 0)
				(type default)
			)
			(fill no)
			(layer "F.Fab")
		)
		(pad "1" smd custom
			(at 0 -0.4445 270)
			(size 0.1397 0.1397)
			(layers "F.Cu" "F.Mask" "F.Paste")
			(net "I2C_B_TMP3_A1")
			(options
				(clearance outline)
				(anchor circle)
			)
			(primitives
				(gr_poly
					(pts
						(arc
							(start -0.1778 -0.2794)
							(mid -0.249642 -0.249642)
							(end -0.2794 -0.1778)
						)
						(arc
							(start -0.2794 0.1778)
							(mid -0.249642 0.249642)
							(end -0.1778 0.2794)
						)
						(arc
							(start 0.1778 0.2794)
							(mid 0.249642 0.249642)
							(end 0.2794 0.1778)
						)
						(arc
							(start 0.2794 -0.1778)
							(mid 0.249642 -0.249642)
							(end 0.1778 -0.2794)
						)
					)
					(width 0)
					(fill yes)
				)
			)
		)
		(pad "2" smd custom
			(at 0 0.4445 270)
			(size 0.1397 0.1397)
			(layers "F.Cu" "F.Mask" "F.Paste")
			(net "GND")
			(options
				(clearance outline)
				(anchor circle)
			)
			(primitives
				(gr_poly
					(pts
						(arc
							(start -0.1778 -0.2794)
							(mid -0.249642 -0.249642)
							(end -0.2794 -0.1778)
						)
						(arc
							(start -0.2794 0.1778)
							(mid -0.249642 0.249642)
							(end -0.1778 0.2794)
						)
						(arc
							(start 0.1778 0.2794)
							(mid 0.249642 0.249642)
							(end 0.2794 0.1778)
						)
						(arc
							(start 0.2794 -0.1778)
							(mid 0.249642 -0.249642)
							(end 0.1778 -0.2794)
						)
					)
					(width 0)
					(fill yes)
				)
			)
		)
	)
	(footprint ""
		(layer "F.Cu")
		(at 216.084912 -82.276696 -90)
		(property "Reference" "R163"
			(at 0 0 270)
			(layer "F.SilkS")
			(hide yes)
			(effects
				(font
					(size 1.27 1.27)
				)
			)
		)
		(property "Value" "2R2010J-1-GP"
			(at 0.254 -8.0772 270)
			(unlocked yes)
			(layer "F.Fab")
			(hide yes)
			(effects
				(font
					(size 1.016 1.016)
					(thickness 0.1524)
				)
			)
		)
		(property "Device Type" "R2010H28"
			(at 0.254 -9.6774 270)
			(unlocked yes)
			(layer "F.Fab")
			(hide yes)
			(effects
				(font
					(size 1.016 1.016)
					(thickness 0.1524)
				)
			)
		)
		(duplicate_pad_numbers_are_jumpers no)
		(fp_line
			(start -1.651 3.302)
			(end 1.651 3.302)
			(stroke
				(width 0.1524)
				(type default)
			)
			(layer "F.SilkS")
		)
		(fp_line
			(start 1.651 3.302)
			(end 1.651 -3.302)
			(stroke
				(width 0.1524)
				(type default)
			)
			(layer "F.SilkS")
		)
		(fp_line
			(start -1.651 -3.302)
			(end -1.651 3.302)
			(stroke
				(width 0.1524)
				(type default)
			)
			(layer "F.SilkS")
		)
		(fp_line
			(start 1.651 -3.302)
			(end -1.651 -3.302)
			(stroke
				(width 0.1524)
				(type default)
			)
			(layer "F.SilkS")
		)
		(fp_rect
			(start -1.7272 -3.3782)
			(end 1.7272 3.3782)
			(stroke
				(width 0)
				(type default)
			)
			(fill no)
			(layer "F.CrtYd")
		)
		(fp_poly
			(pts
				(xy 1.7272 3.3782) (xy 1.7272 -3.3782) (xy -1.7272 -3.3782) (xy -1.7272 3.3782)
			)
			(stroke
				(width 0)
				(type default)
			)
			(fill no)
			(layer "F.Fab")
		)
		(pad "1" smd rect
			(at 0 -2.3495 270)
			(size 2.794 1.143)
			(layers "F.Cu" "F.Mask" "F.Paste")
			(net "12V_PRE_4")
		)
		(pad "2" smd rect
			(at 0 2.3495 270)
			(size 2.794 1.143)
			(layers "F.Cu" "F.Mask" "F.Paste")
			(net "P12V_HDD4")
		)
	)
	(footprint ""
		(layer "F.Cu")
		(at 210.946746 -454.1647 -90)
		(property "Reference" "R338"
			(at 0 0 270)
			(layer "F.SilkS")
			(hide yes)
			(effects
				(font
					(size 1.27 1.27)
				)
			)
		)
		(property "Value" "4K7R2J-2-GP"
			(at 0.064008 -3.993896 270)
			(unlocked yes)
			(layer "F.Fab")
			(hide yes)
			(effects
				(font
					(size 1.016 1.016)
					(thickness 0.1524)
				)
			)
		)
		(property "Device Type" "R402H16"
			(at 0.064008 -5.517896 270)
			(unlocked yes)
			(layer "F.Fab")
			(hide yes)
			(effects
				(font
					(size 1.016 1.016)
					(thickness 0.1524)
				)
			)
		)
		(duplicate_pad_numbers_are_jumpers no)
		(fp_line
			(start -0.508 -0.9398)
			(end -0.508 0.9398)
			(stroke
				(width 0.1524)
				(type default)
			)
			(layer "F.SilkS")
		)
		(fp_line
			(start 0.508 -0.9398)
			(end -0.508 -0.9398)
			(stroke
				(width 0.1524)
				(type default)
			)
			(layer "F.SilkS")
		)
		(fp_rect
			(start -0.508 0.9398)
			(end 0.508 -0.9398)
			(stroke
				(width 0)
				(type default)
			)
			(fill no)
			(layer "F.CrtYd")
		)
		(fp_rect
			(start -0.508 0.9398)
			(end 0.508 -0.9398)
			(stroke
				(width 0)
				(type default)
			)
			(fill no)
			(layer "F.Fab")
		)
		(pad "1" smd custom
			(at 0 -0.4445 270)
			(size 0.1397 0.1397)
			(layers "F.Cu" "F.Mask" "F.Paste")
			(net "I2C_B_TMP3_A0")
			(options
				(clearance outline)
				(anchor circle)
			)
			(primitives
				(gr_poly
					(pts
						(arc
							(start -0.1778 -0.2794)
							(mid -0.249642 -0.249642)
							(end -0.2794 -0.1778)
						)
						(arc
							(start -0.2794 0.1778)
							(mid -0.249642 0.249642)
							(end -0.1778 0.2794)
						)
						(arc
							(start 0.1778 0.2794)
							(mid 0.249642 0.249642)
							(end 0.2794 0.1778)
						)
						(arc
							(start 0.2794 -0.1778)
							(mid 0.249642 -0.249642)
							(end 0.1778 -0.2794)
						)
					)
					(width 0)
					(fill yes)
				)
			)
		)
		(pad "2" smd custom
			(at 0 0.4445 270)
			(size 0.1397 0.1397)
			(layers "F.Cu" "F.Mask" "F.Paste")
			(net "GND")
			(options
				(clearance outline)
				(anchor circle)
			)
			(primitives
				(gr_poly
					(pts
						(arc
							(start -0.1778 -0.2794)
							(mid -0.249642 -0.249642)
							(end -0.2794 -0.1778)
						)
						(arc
							(start -0.2794 0.1778)
							(mid -0.249642 0.249642)
							(end -0.1778 0.2794)
						)
						(arc
							(start 0.1778 0.2794)
							(mid 0.249642 0.249642)
							(end 0.2794 0.1778)
						)
						(arc
							(start 0.2794 -0.1778)
							(mid 0.249642 -0.249642)
							(end 0.1778 -0.2794)
						)
					)
					(width 0)
					(fill yes)
				)
			)
		)
	)
	(footprint ""
		(layer "F.Cu")
		(at 78.358746 -90.4367 90)
		(property "Reference" "R233"
			(at 0 0 90)
			(layer "F.SilkS")
			(hide yes)
			(effects
				(font
					(size 1.27 1.27)
				)
			)
		)
		(property "Value" "200KR2F-L-GP"
			(at 0.064008 -3.993896 90)
			(unlocked yes)
			(layer "F.Fab")
			(hide yes)
			(effects
				(font
					(size 1.016 1.016)
					(thickness 0.1524)
				)
			)
		)
		(property "Device Type" "R402H16"
			(at 0.064008 -5.517896 90)
			(unlocked yes)
			(layer "F.Fab")
			(hide yes)
			(effects
				(font
					(size 1.016 1.016)
					(thickness 0.1524)
				)
			)
		)
		(duplicate_pad_numbers_are_jumpers no)
		(fp_line
			(start 0.508 -0.9398)
			(end -0.508 -0.9398)
			(stroke
				(width 0.1524)
				(type default)
			)
			(layer "F.SilkS")
		)
		(fp_line
			(start -0.508 -0.9398)
			(end -0.508 0.9398)
			(stroke
				(width 0.1524)
				(type default)
			)
			(layer "F.SilkS")
		)
		(fp_rect
			(start -0.508 0.9398)
			(end 0.508 -0.9398)
			(stroke
				(width 0)
				(type default)
			)
			(fill no)
			(layer "F.CrtYd")
		)
		(fp_rect
			(start -0.508 0.9398)
			(end 0.508 -0.9398)
			(stroke
				(width 0)
				(type default)
			)
			(fill no)
			(layer "F.Fab")
		)
		(pad "1" smd custom
			(at 0 -0.4445 90)
			(size 0.1397 0.1397)
			(layers "F.Cu" "F.Mask" "F.Paste")
			(net "P12V")
			(options
				(clearance outline)
				(anchor circle)
			)
			(primitives
				(gr_poly
					(pts
						(arc
							(start -0.1778 -0.2794)
							(mid -0.249642 -0.249642)
							(end -0.2794 -0.1778)
						)
						(arc
							(start -0.2794 0.1778)
							(mid -0.249642 0.249642)
							(end -0.1778 0.2794)
						)
						(arc
							(start 0.1778 0.2794)
							(mid 0.249642 0.249642)
							(end 0.2794 0.1778)
						)
						(arc
							(start 0.2794 -0.1778)
							(mid 0.249642 -0.249642)
							(end 0.1778 -0.2794)
						)
					)
					(width 0)
					(fill yes)
				)
			)
		)
		(pad "2" smd custom
			(at 0 0.4445 90)
			(size 0.1397 0.1397)
			(layers "F.Cu" "F.Mask" "F.Paste")
			(net "SW_HDD9_P")
			(options
				(clearance outline)
				(anchor circle)
			)
			(primitives
				(gr_poly
					(pts
						(arc
							(start -0.1778 -0.2794)
							(mid -0.249642 -0.249642)
							(end -0.2794 -0.1778)
						)
						(arc
							(start -0.2794 0.1778)
							(mid -0.249642 0.249642)
							(end -0.1778 0.2794)
						)
						(arc
							(start 0.1778 0.2794)
							(mid 0.249642 0.249642)
							(end 0.2794 0.1778)
						)
						(arc
							(start 0.2794 -0.1778)
							(mid 0.249642 -0.249642)
							(end 0.1778 -0.2794)
						)
					)
					(width 0)
					(fill yes)
				)
			)
		)
	)
	(footprint ""
		(layer "F.Cu")
		(at 207.136746 -454.1647 -90)
		(property "Reference" "R336"
			(at 0 0 270)
			(layer "F.SilkS")
			(hide yes)
			(effects
				(font
					(size 1.27 1.27)
				)
			)
		)
		(property "Value" "4K7R2J-2-GP"
			(at 0.064008 -3.993896 270)
			(unlocked yes)
			(layer "F.Fab")
			(hide yes)
			(effects
				(font
					(size 1.016 1.016)
					(thickness 0.1524)
				)
			)
		)
		(property "Device Type" "R402H16"
			(at 0.064008 -5.517896 270)
			(unlocked yes)
			(layer "F.Fab")
			(hide yes)
			(effects
				(font
					(size 1.016 1.016)
					(thickness 0.1524)
				)
			)
		)
		(duplicate_pad_numbers_are_jumpers no)
		(fp_line
			(start -0.508 -0.9398)
			(end -0.508 0.9398)
			(stroke
				(width 0.1524)
				(type default)
			)
			(layer "F.SilkS")
		)
		(fp_line
			(start 0.508 -0.9398)
			(end -0.508 -0.9398)
			(stroke
				(width 0.1524)
				(type default)
			)
			(layer "F.SilkS")
		)
		(fp_rect
			(start -0.508 0.9398)
			(end 0.508 -0.9398)
			(stroke
				(width 0)
				(type default)
			)
			(fill no)
			(layer "F.CrtYd")
		)
		(fp_rect
			(start -0.508 0.9398)
			(end 0.508 -0.9398)
			(stroke
				(width 0)
				(type default)
			)
			(fill no)
			(layer "F.Fab")
		)
		(pad "1" smd custom
			(at 0 -0.4445 270)
			(size 0.1397 0.1397)
			(layers "F.Cu" "F.Mask" "F.Paste")
			(net "I2C_B_TMP3_A2")
			(options
				(clearance outline)
				(anchor circle)
			)
			(primitives
				(gr_poly
					(pts
						(arc
							(start -0.1778 -0.2794)
							(mid -0.249642 -0.249642)
							(end -0.2794 -0.1778)
						)
						(arc
							(start -0.2794 0.1778)
							(mid -0.249642 0.249642)
							(end -0.1778 0.2794)
						)
						(arc
							(start 0.1778 0.2794)
							(mid 0.249642 0.249642)
							(end 0.2794 0.1778)
						)
						(arc
							(start 0.2794 -0.1778)
							(mid 0.249642 -0.249642)
							(end 0.1778 -0.2794)
						)
					)
					(width 0)
					(fill yes)
				)
			)
		)
		(pad "2" smd custom
			(at 0 0.4445 270)
			(size 0.1397 0.1397)
			(layers "F.Cu" "F.Mask" "F.Paste")
			(net "GND")
			(options
				(clearance outline)
				(anchor circle)
			)
			(primitives
				(gr_poly
					(pts
						(arc
							(start -0.1778 -0.2794)
							(mid -0.249642 -0.249642)
							(end -0.2794 -0.1778)
						)
						(arc
							(start -0.2794 0.1778)
							(mid -0.249642 0.249642)
							(end -0.1778 0.2794)
						)
						(arc
							(start 0.1778 0.2794)
							(mid 0.249642 0.249642)
							(end 0.2794 0.1778)
						)
						(arc
							(start 0.2794 -0.1778)
							(mid 0.249642 -0.249642)
							(end 0.1778 -0.2794)
						)
					)
					(width 0)
					(fill yes)
				)
			)
		)
	)
	(footprint ""
		(layer "F.Cu")
		(at 192.786 -499.11 90)
		(property "Reference" "R478"
			(at 0 0 90)
			(layer "F.SilkS")
			(hide yes)
			(effects
				(font
					(size 1.27 1.27)
				)
			)
		)
		(property "Value" "200KR2F-L-GP"
			(at 0.064008 -3.993896 90)
			(unlocked yes)
			(layer "F.Fab")
			(hide yes)
			(effects
				(font
					(size 1.016 1.016)
					(thickness 0.1524)
				)
			)
		)
		(property "Device Type" "R402H16"
			(at 0.064008 -5.517896 90)
			(unlocked yes)
			(layer "F.Fab")
			(hide yes)
			(effects
				(font
					(size 1.016 1.016)
					(thickness 0.1524)
				)
			)
		)
		(duplicate_pad_numbers_are_jumpers no)
		(fp_line
			(start 0.508 -0.9398)
			(end -0.508 -0.9398)
			(stroke
				(width 0.1524)
				(type default)
			)
			(layer "F.SilkS")
		)
		(fp_line
			(start -0.508 -0.9398)
			(end -0.508 0.9398)
			(stroke
				(width 0.1524)
				(type default)
			)
			(layer "F.SilkS")
		)
		(fp_rect
			(start -0.508 0.9398)
			(end 0.508 -0.9398)
			(stroke
				(width 0)
				(type default)
			)
			(fill no)
			(layer "F.CrtYd")
		)
		(fp_rect
			(start -0.508 0.9398)
			(end 0.508 -0.9398)
			(stroke
				(width 0)
				(type default)
			)
			(fill no)
			(layer "F.Fab")
		)
		(pad "1" smd custom
			(at 0 -0.4445 90)
			(size 0.1397 0.1397)
			(layers "F.Cu" "F.Mask" "F.Paste")
			(net "SW_HDD0_R")
			(options
				(clearance outline)
				(anchor circle)
			)
			(primitives
				(gr_poly
					(pts
						(arc
							(start -0.1778 -0.2794)
							(mid -0.249642 -0.249642)
							(end -0.2794 -0.1778)
						)
						(arc
							(start -0.2794 0.1778)
							(mid -0.249642 0.249642)
							(end -0.1778 0.2794)
						)
						(arc
							(start 0.1778 0.2794)
							(mid 0.249642 0.249642)
							(end 0.2794 0.1778)
						)
						(arc
							(start 0.2794 -0.1778)
							(mid 0.249642 -0.249642)
							(end 0.1778 -0.2794)
						)
					)
					(width 0)
					(fill yes)
				)
			)
		)
		(pad "2" smd custom
			(at 0 0.4445 90)
			(size 0.1397 0.1397)
			(layers "F.Cu" "F.Mask" "F.Paste")
			(net "SW_HDD0_N")
			(options
				(clearance outline)
				(anchor circle)
			)
			(primitives
				(gr_poly
					(pts
						(arc
							(start -0.1778 -0.2794)
							(mid -0.249642 -0.249642)
							(end -0.2794 -0.1778)
						)
						(arc
							(start -0.2794 0.1778)
							(mid -0.249642 0.249642)
							(end -0.1778 0.2794)
						)
						(arc
							(start 0.1778 0.2794)
							(mid 0.249642 0.249642)
							(end 0.2794 0.1778)
						)
						(arc
							(start 0.2794 -0.1778)
							(mid 0.249642 -0.249642)
							(end 0.1778 -0.2794)
						)
					)
					(width 0)
					(fill yes)
				)
			)
		)
	)
	(footprint ""
		(layer "F.Cu")
		(at 5.079746 -492.7727 -90)
		(property "Reference" "R487"
			(at 0 0 270)
			(layer "F.SilkS")
			(hide yes)
			(effects
				(font
					(size 1.27 1.27)
				)
			)
		)
		(property "Value" "2K49R2F-GP"
			(at 0.064008 -3.993896 270)
			(unlocked yes)
			(layer "F.Fab")
			(hide yes)
			(effects
				(font
					(size 1.016 1.016)
					(thickness 0.1524)
				)
			)
		)
		(property "Device Type" "R402H16"
			(at 0.064008 -5.517896 270)
			(unlocked yes)
			(layer "F.Fab")
			(hide yes)
			(effects
				(font
					(size 1.016 1.016)
					(thickness 0.1524)
				)
			)
		)
		(duplicate_pad_numbers_are_jumpers no)
		(fp_line
			(start -0.508 -0.9398)
			(end -0.508 0.9398)
			(stroke
				(width 0.1524)
				(type default)
			)
			(layer "F.SilkS")
		)
		(fp_line
			(start 0.508 -0.9398)
			(end -0.508 -0.9398)
			(stroke
				(width 0.1524)
				(type default)
			)
			(layer "F.SilkS")
		)
		(fp_rect
			(start -0.508 0.9398)
			(end 0.508 -0.9398)
			(stroke
				(width 0)
				(type default)
			)
			(fill no)
			(layer "F.CrtYd")
		)
		(fp_rect
			(start -0.508 0.9398)
			(end 0.508 -0.9398)
			(stroke
				(width 0)
				(type default)
			)
			(fill no)
			(layer "F.Fab")
		)
		(pad "1" smd custom
			(at 0 -0.4445 270)
			(size 0.1397 0.1397)
			(layers "F.Cu" "F.Mask" "F.Paste")
			(net "P5VC_EN")
			(options
				(clearance outline)
				(anchor circle)
			)
			(primitives
				(gr_poly
					(pts
						(arc
							(start -0.1778 -0.2794)
							(mid -0.249642 -0.249642)
							(end -0.2794 -0.1778)
						)
						(arc
							(start -0.2794 0.1778)
							(mid -0.249642 0.249642)
							(end -0.1778 0.2794)
						)
						(arc
							(start 0.1778 0.2794)
							(mid 0.249642 0.249642)
							(end 0.2794 0.1778)
						)
						(arc
							(start 0.2794 -0.1778)
							(mid 0.249642 -0.249642)
							(end 0.1778 -0.2794)
						)
					)
					(width 0)
					(fill yes)
				)
			)
		)
		(pad "2" smd custom
			(at 0 0.4445 270)
			(size 0.1397 0.1397)
			(layers "F.Cu" "F.Mask" "F.Paste")
			(net "GND")
			(options
				(clearance outline)
				(anchor circle)
			)
			(primitives
				(gr_poly
					(pts
						(arc
							(start -0.1778 -0.2794)
							(mid -0.249642 -0.249642)
							(end -0.2794 -0.1778)
						)
						(arc
							(start -0.2794 0.1778)
							(mid -0.249642 0.249642)
							(end -0.1778 0.2794)
						)
						(arc
							(start 0.1778 0.2794)
							(mid 0.249642 0.249642)
							(end 0.2794 0.1778)
						)
						(arc
							(start 0.2794 -0.1778)
							(mid 0.249642 -0.249642)
							(end 0.1778 -0.2794)
						)
					)
					(width 0)
					(fill yes)
				)
			)
		)
	)
	(footprint ""
		(layer "F.Cu")
		(at 221.444058 -350.468184 90)
		(property "Reference" "R115"
			(at 0 0 90)
			(layer "F.SilkS")
			(hide yes)
			(effects
				(font
					(size 1.27 1.27)
				)
			)
		)
		(property "Value" "402R2F-GP"
			(at 0.064008 -3.993896 90)
			(unlocked yes)
			(layer "F.Fab")
			(hide yes)
			(effects
				(font
					(size 1.016 1.016)
					(thickness 0.1524)
				)
			)
		)
		(property "Device Type" "R402H16"
			(at 0.064008 -5.517896 90)
			(unlocked yes)
			(layer "F.Fab")
			(hide yes)
			(effects
				(font
					(size 1.016 1.016)
					(thickness 0.1524)
				)
			)
		)
		(duplicate_pad_numbers_are_jumpers no)
		(fp_line
			(start 0.508 -0.9398)
			(end -0.508 -0.9398)
			(stroke
				(width 0.1524)
				(type default)
			)
			(layer "F.SilkS")
		)
		(fp_line
			(start -0.508 -0.9398)
			(end -0.508 0.9398)
			(stroke
				(width 0.1524)
				(type default)
			)
			(layer "F.SilkS")
		)
		(fp_rect
			(start -0.508 0.9398)
			(end 0.508 -0.9398)
			(stroke
				(width 0)
				(type default)
			)
			(fill no)
			(layer "F.CrtYd")
		)
		(fp_rect
			(start -0.508 0.9398)
			(end 0.508 -0.9398)
			(stroke
				(width 0)
				(type default)
			)
			(fill no)
			(layer "F.Fab")
		)
		(pad "1" smd custom
			(at 0 -0.4445 90)
			(size 0.1397 0.1397)
			(layers "F.Cu" "F.Mask" "F.Paste")
			(net "P5VA_HDD1_LED")
			(options
				(clearance outline)
				(anchor circle)
			)
			(primitives
				(gr_poly
					(pts
						(arc
							(start -0.1778 -0.2794)
							(mid -0.249642 -0.249642)
							(end -0.2794 -0.1778)
						)
						(arc
							(start -0.2794 0.1778)
							(mid -0.249642 0.249642)
							(end -0.1778 0.2794)
						)
						(arc
							(start 0.1778 0.2794)
							(mid 0.249642 0.249642)
							(end 0.2794 0.1778)
						)
						(arc
							(start 0.2794 -0.1778)
							(mid 0.249642 -0.249642)
							(end 0.1778 -0.2794)
						)
					)
					(width 0)
					(fill yes)
				)
			)
		)
		(pad "2" smd custom
			(at 0 0.4445 90)
			(size 0.1397 0.1397)
			(layers "F.Cu" "F.Mask" "F.Paste")
			(net "DRV_ACT_1")
			(options
				(clearance outline)
				(anchor circle)
			)
			(primitives
				(gr_poly
					(pts
						(arc
							(start -0.1778 -0.2794)
							(mid -0.249642 -0.249642)
							(end -0.2794 -0.1778)
						)
						(arc
							(start -0.2794 0.1778)
							(mid -0.249642 0.249642)
							(end -0.1778 0.2794)
						)
						(arc
							(start 0.1778 0.2794)
							(mid 0.249642 0.249642)
							(end 0.2794 0.1778)
						)
						(arc
							(start 0.2794 -0.1778)
							(mid 0.249642 -0.249642)
							(end 0.1778 -0.2794)
						)
					)
					(width 0)
					(fill yes)
				)
			)
		)
	)
	(footprint ""
		(layer "F.Cu")
		(at 39.572946 -138.2395 90)
		(property "Reference" "R319"
			(at 0 0 90)
			(layer "F.SilkS")
			(hide yes)
			(effects
				(font
					(size 1.27 1.27)
				)
			)
		)
		(property "Value" "0R2J-2-GP"
			(at 0.064008 -3.993896 90)
			(unlocked yes)
			(layer "F.Fab")
			(hide yes)
			(effects
				(font
					(size 1.016 1.016)
					(thickness 0.1524)
				)
			)
		)
		(property "Device Type" "R402H16"
			(at 0.064008 -5.517896 90)
			(unlocked yes)
			(layer "F.Fab")
			(hide yes)
			(effects
				(font
					(size 1.016 1.016)
					(thickness 0.1524)
				)
			)
		)
		(duplicate_pad_numbers_are_jumpers no)
		(fp_line
			(start 0.508 -0.9398)
			(end -0.508 -0.9398)
			(stroke
				(width 0.1524)
				(type default)
			)
			(layer "F.SilkS")
		)
		(fp_line
			(start -0.508 -0.9398)
			(end -0.508 0.9398)
			(stroke
				(width 0.1524)
				(type default)
			)
			(layer "F.SilkS")
		)
		(fp_rect
			(start -0.508 0.9398)
			(end 0.508 -0.9398)
			(stroke
				(width 0)
				(type default)
			)
			(fill no)
			(layer "F.CrtYd")
		)
		(fp_rect
			(start -0.508 0.9398)
			(end 0.508 -0.9398)
			(stroke
				(width 0)
				(type default)
			)
			(fill no)
			(layer "F.Fab")
		)
		(pad "1" smd custom
			(at 0 -0.4445 90)
			(size 0.1397 0.1397)
			(layers "F.Cu" "F.Mask" "F.Paste")
			(net "I2C_B_SCL")
			(options
				(clearance outline)
				(anchor circle)
			)
			(primitives
				(gr_poly
					(pts
						(arc
							(start -0.1778 -0.2794)
							(mid -0.249642 -0.249642)
							(end -0.2794 -0.1778)
						)
						(arc
							(start -0.2794 0.1778)
							(mid -0.249642 0.249642)
							(end -0.1778 0.2794)
						)
						(arc
							(start 0.1778 0.2794)
							(mid 0.249642 0.249642)
							(end 0.2794 0.1778)
						)
						(arc
							(start 0.2794 -0.1778)
							(mid 0.249642 -0.249642)
							(end 0.1778 -0.2794)
						)
					)
					(width 0)
					(fill yes)
				)
			)
		)
		(pad "2" smd custom
			(at 0 0.4445 90)
			(size 0.1397 0.1397)
			(layers "F.Cu" "F.Mask" "F.Paste")
			(net "TMP2_SCL")
			(options
				(clearance outline)
				(anchor circle)
			)
			(primitives
				(gr_poly
					(pts
						(arc
							(start -0.1778 -0.2794)
							(mid -0.249642 -0.249642)
							(end -0.2794 -0.1778)
						)
						(arc
							(start -0.2794 0.1778)
							(mid -0.249642 0.249642)
							(end -0.1778 0.2794)
						)
						(arc
							(start 0.1778 0.2794)
							(mid 0.249642 0.249642)
							(end 0.2794 0.1778)
						)
						(arc
							(start 0.2794 -0.1778)
							(mid 0.249642 -0.249642)
							(end 0.1778 -0.2794)
						)
					)
					(width 0)
					(fill yes)
				)
			)
		)
	)
	(footprint ""
		(layer "F.Cu")
		(at 43.052746 -226.215702)
		(property "Reference" "C299"
			(at 0 0 0)
			(layer "F.SilkS")
			(hide yes)
			(effects
				(font
					(size 1.27 1.27)
				)
			)
		)
		(property "Value" "SC10U16V6KX-2GP"
			(at -0.0762 -5.1308 0)
			(unlocked yes)
			(layer "F.Fab")
			(hide yes)
			(effects
				(font
					(size 1.016 1.016)
					(thickness 0.1524)
				)
			)
		)
		(property "Device Type" "C1206H71"
			(at -0.127 -6.6548 0)
			(unlocked yes)
			(layer "F.Fab")
			(hide yes)
			(effects
				(font
					(size 1.016 1.016)
					(thickness 0.1524)
				)
			)
		)
		(duplicate_pad_numbers_are_jumpers no)
		(fp_line
			(start -1.016 -2.2352)
			(end 1.016 -2.2352)
			(stroke
				(width 0.1524)
				(type default)
			)
			(layer "F.SilkS")
		)
		(fp_line
			(start -1.016 -0.8382)
			(end -1.016 -2.2352)
			(stroke
				(width 0.1524)
				(type default)
			)
			(layer "F.SilkS")
		)
		(fp_line
			(start -1.016 2.2352)
			(end -1.016 0.8382)
			(stroke
				(width 0.1524)
				(type default)
			)
			(layer "F.SilkS")
		)
		(fp_line
			(start 1.016 -2.2352)
			(end 1.016 -0.8382)
			(stroke
				(width 0.1524)
				(type default)
			)
			(layer "F.SilkS")
		)
		(fp_line
			(start 1.016 0.8382)
			(end 1.016 2.2352)
			(stroke
				(width 0.1524)
				(type default)
			)
			(layer "F.SilkS")
		)
		(fp_line
			(start 1.016 2.2352)
			(end -1.016 2.2352)
			(stroke
				(width 0.1524)
				(type default)
			)
			(layer "F.SilkS")
		)
		(fp_rect
			(start -1.0922 2.3114)
			(end 1.0922 -2.3114)
			(stroke
				(width 0)
				(type default)
			)
			(fill no)
			(layer "F.CrtYd")
		)
		(fp_poly
			(pts
				(xy 1.0922 -2.3114) (xy 1.0922 2.3114) (xy -1.0922 2.3114) (xy -1.0922 -2.3114)
			)
			(stroke
				(width 0)
				(type default)
			)
			(fill no)
			(layer "F.Fab")
		)
		(pad "1" smd rect
			(at 0 -1.397)
			(size 1.651 1.27)
			(layers "F.Cu" "F.Mask" "F.Paste")
			(net "P5V_HDD12")
		)
		(pad "2" smd rect
			(at 0 1.397)
			(size 1.651 1.27)
			(layers "F.Cu" "F.Mask" "F.Paste")
			(net "GND")
		)
	)
	(footprint ""
		(layer "F.Cu")
		(at 26.034746 -36.8427 90)
		(property "Reference" "C326"
			(at 0 0 90)
			(layer "F.SilkS")
			(hide yes)
			(effects
				(font
					(size 1.27 1.27)
				)
			)
		)
		(property "Value" "SCD01U50V2KX-1GP"
			(at 1.1811 -2.7051 90)
			(unlocked yes)
			(layer "F.Fab")
			(hide yes)
			(effects
				(font
					(size 1.016 1.016)
					(thickness 0.1524)
				)
			)
		)
		(property "Device Type" "C402H22"
			(at 1.1811 -4.2291 90)
			(unlocked yes)
			(layer "F.Fab")
			(hide yes)
			(effects
				(font
					(size 1.016 1.016)
					(thickness 0.1524)
				)
			)
		)
		(duplicate_pad_numbers_are_jumpers no)
		(fp_rect
			(start -0.4318 0.9525)
			(end 0.4318 -0.9525)
			(stroke
				(width 0)
				(type default)
			)
			(fill no)
			(layer "F.CrtYd")
		)
		(fp_rect
			(start -0.4318 0.9525)
			(end 0.4318 -0.9525)
			(stroke
				(width 0)
				(type default)
			)
			(fill no)
			(layer "F.Fab")
		)
		(pad "1" smd custom
			(at 0 -0.4445 90)
			(size 0.1524 0.1524)
			(layers "F.Cu" "F.Mask" "F.Paste")
			(net "SAS2X28_DRIVE_RX_N_A14")
			(options
				(clearance outline)
				(anchor circle)
			)
			(primitives
				(gr_poly
					(pts
						(arc
							(start 0.3048 -0.2032)
							(mid 0.275042 -0.275042)
							(end 0.2032 -0.3048)
						)
						(arc
							(start -0.2032 -0.3048)
							(mid -0.275042 -0.275042)
							(end -0.3048 -0.2032)
						)
						(arc
							(start -0.3048 0.2032)
							(mid -0.275042 0.275042)
							(end -0.2032 0.3048)
						)
						(arc
							(start 0.2032 0.3048)
							(mid 0.275042 0.275042)
							(end 0.3048 0.2032)
						)
					)
					(width 0)
					(fill yes)
				)
			)
		)
		(pad "2" smd custom
			(at 0 0.4445 90)
			(size 0.1524 0.1524)
			(layers "F.Cu" "F.Mask" "F.Paste")
			(net "SAS2X28_A_HDD14_RX_-")
			(options
				(clearance outline)
				(anchor circle)
			)
			(primitives
				(gr_poly
					(pts
						(arc
							(start 0.3048 -0.2032)
							(mid 0.275042 -0.275042)
							(end 0.2032 -0.3048)
						)
						(arc
							(start -0.2032 -0.3048)
							(mid -0.275042 -0.275042)
							(end -0.3048 -0.2032)
						)
						(arc
							(start -0.3048 0.2032)
							(mid -0.275042 0.275042)
							(end -0.2032 0.3048)
						)
						(arc
							(start 0.2032 0.3048)
							(mid 0.275042 0.275042)
							(end 0.3048 0.2032)
						)
					)
					(width 0)
					(fill yes)
				)
			)
		)
	)
	(footprint ""
		(layer "F.Cu")
		(at 5.079746 -499.5037)
		(property "Reference" "PR38"
			(at 0 0 0)
			(layer "F.SilkS")
			(hide yes)
			(effects
				(font
					(size 1.27 1.27)
				)
			)
		)
		(property "Value" "866KR2F-GP"
			(at 0.064008 -3.993896 0)
			(unlocked yes)
			(layer "F.Fab")
			(hide yes)
			(effects
				(font
					(size 1.016 1.016)
					(thickness 0.1524)
				)
			)
		)
		(property "Device Type" "R402H16"
			(at 0.064008 -5.517896 0)
			(unlocked yes)
			(layer "F.Fab")
			(hide yes)
			(effects
				(font
					(size 1.016 1.016)
					(thickness 0.1524)
				)
			)
		)
		(duplicate_pad_numbers_are_jumpers no)
		(fp_line
			(start -0.508 -0.9398)
			(end -0.508 0.9398)
			(stroke
				(width 0.1524)
				(type default)
			)
			(layer "F.SilkS")
		)
		(fp_line
			(start 0.508 -0.9398)
			(end -0.508 -0.9398)
			(stroke
				(width 0.1524)
				(type default)
			)
			(layer "F.SilkS")
		)
		(fp_rect
			(start -0.508 0.9398)
			(end 0.508 -0.9398)
			(stroke
				(width 0)
				(type default)
			)
			(fill no)
			(layer "F.CrtYd")
		)
		(fp_rect
			(start -0.508 0.9398)
			(end 0.508 -0.9398)
			(stroke
				(width 0)
				(type default)
			)
			(fill no)
			(layer "F.Fab")
		)
		(pad "1" smd custom
			(at 0 -0.4445)
			(size 0.1397 0.1397)
			(layers "F.Cu" "F.Mask" "F.Paste")
			(net "P5VC_VREG")
			(options
				(clearance outline)
				(anchor circle)
			)
			(primitives
				(gr_poly
					(pts
						(arc
							(start -0.1778 -0.2794)
							(mid -0.249642 -0.249642)
							(end -0.2794 -0.1778)
						)
						(arc
							(start -0.2794 0.1778)
							(mid -0.249642 0.249642)
							(end -0.1778 0.2794)
						)
						(arc
							(start 0.1778 0.2794)
							(mid 0.249642 0.249642)
							(end 0.2794 0.1778)
						)
						(arc
							(start 0.2794 -0.1778)
							(mid 0.249642 -0.249642)
							(end 0.1778 -0.2794)
						)
					)
					(width 0)
					(fill yes)
				)
			)
		)
		(pad "2" smd custom
			(at 0 0.4445)
			(size 0.1397 0.1397)
			(layers "F.Cu" "F.Mask" "F.Paste")
			(net "P5VC_RF")
			(options
				(clearance outline)
				(anchor circle)
			)
			(primitives
				(gr_poly
					(pts
						(arc
							(start -0.1778 -0.2794)
							(mid -0.249642 -0.249642)
							(end -0.2794 -0.1778)
						)
						(arc
							(start -0.2794 0.1778)
							(mid -0.249642 0.249642)
							(end -0.1778 0.2794)
						)
						(arc
							(start 0.1778 0.2794)
							(mid 0.249642 0.249642)
							(end 0.2794 0.1778)
						)
						(arc
							(start 0.2794 -0.1778)
							(mid 0.249642 -0.249642)
							(end 0.1778 -0.2794)
						)
					)
					(width 0)
					(fill yes)
				)
			)
		)
	)
	(footprint ""
		(layer "F.Cu")
		(at 252.499622 -37.999924)
		(property "Reference" "H16"
			(at 0 0 0)
			(layer "F.SilkS")
			(hide yes)
			(effects
				(font
					(size 1.27 1.27)
				)
			)
		)
		(property "Value" "HOLE315R140"
			(at 0 -7.5692 0)
			(unlocked yes)
			(layer "F.Fab")
			(hide yes)
			(effects
				(font
					(size 1.016 1.016)
					(thickness 0.1524)
				)
			)
		)
		(property "Device Type" "HOLE315R140"
			(at 0 -9.0932 0)
			(unlocked yes)
			(layer "F.Fab")
			(hide yes)
			(effects
				(font
					(size 1.016 1.016)
					(thickness 0.1524)
				)
			)
		)
		(duplicate_pad_numbers_are_jumpers no)
		(fp_poly
			(pts
				(arc
					(start 4.3053 0)
					(mid -4.3053 0)
					(end 4.3053 0)
				)
			)
			(stroke
				(width 0)
				(type default)
			)
			(fill no)
			(layer "F.CrtYd")
		)
		(fp_poly
			(pts
				(arc
					(start 4.3053 0)
					(mid -4.3053 0)
					(end 4.3053 0)
				)
			)
			(stroke
				(width 0)
				(type default)
			)
			(fill no)
			(layer "F.Fab")
		)
		(pad "1" thru_hole circle
			(at 0.00127 0.00127)
			(size 8.001 8.001)
			(drill 3.556)
			(layers "*.Cu" "*.Mask")
			(remove_unused_layers no)
			(net "GND")
			(clearance -1.7145)
			(thermal_gap 0.3048)
			(padstack
				(mode front_inner_back)
				(layer "Inner"
					(shape circle)
					(size 3.9624 3.9624)
					(clearance 0.3048)
				)
				(layer "B.Cu"
					(shape circle)
					(size 8.001 8.001)
					(clearance -1.7145)
				)
			)
		)
	)
	(footprint ""
		(layer "F.Cu")
		(at 34.544 -134.747 180)
		(property "Reference" "R402"
			(at 0 0 180)
			(layer "F.SilkS")
			(hide yes)
			(effects
				(font
					(size 1.27 1.27)
				)
			)
		)
		(property "Value" "0R2J-2-GP"
			(at 0.064008 -3.993896 180)
			(unlocked yes)
			(layer "F.Fab")
			(hide yes)
			(effects
				(font
					(size 1.016 1.016)
					(thickness 0.1524)
				)
			)
		)
		(property "Device Type" "R402H16"
			(at 0.064008 -5.517896 180)
			(unlocked yes)
			(layer "F.Fab")
			(hide yes)
			(effects
				(font
					(size 1.016 1.016)
					(thickness 0.1524)
				)
			)
		)
		(duplicate_pad_numbers_are_jumpers no)
		(fp_line
			(start 0.508 -0.9398)
			(end -0.508 -0.9398)
			(stroke
				(width 0.1524)
				(type default)
			)
			(layer "F.SilkS")
		)
		(fp_line
			(start -0.508 -0.9398)
			(end -0.508 0.9398)
			(stroke
				(width 0.1524)
				(type default)
			)
			(layer "F.SilkS")
		)
		(fp_rect
			(start -0.508 0.9398)
			(end 0.508 -0.9398)
			(stroke
				(width 0)
				(type default)
			)
			(fill no)
			(layer "F.CrtYd")
		)
		(fp_rect
			(start -0.508 0.9398)
			(end 0.508 -0.9398)
			(stroke
				(width 0)
				(type default)
			)
			(fill no)
			(layer "F.Fab")
		)
		(pad "1" smd custom
			(at 0 -0.4445 180)
			(size 0.1397 0.1397)
			(layers "F.Cu" "F.Mask" "F.Paste")
			(net "HDD_PRSNT_NET13")
			(options
				(clearance outline)
				(anchor circle)
			)
			(primitives
				(gr_poly
					(pts
						(arc
							(start -0.1778 -0.2794)
							(mid -0.249642 -0.249642)
							(end -0.2794 -0.1778)
						)
						(arc
							(start -0.2794 0.1778)
							(mid -0.249642 0.249642)
							(end -0.1778 0.2794)
						)
						(arc
							(start 0.1778 0.2794)
							(mid 0.249642 0.249642)
							(end 0.2794 0.1778)
						)
						(arc
							(start 0.2794 -0.1778)
							(mid 0.249642 -0.249642)
							(end 0.1778 -0.2794)
						)
					)
					(width 0)
					(fill yes)
				)
			)
		)
		(pad "2" smd custom
			(at 0 0.4445 180)
			(size 0.1397 0.1397)
			(layers "F.Cu" "F.Mask" "F.Paste")
			(net "HDD13_LED_B")
			(options
				(clearance outline)
				(anchor circle)
			)
			(primitives
				(gr_poly
					(pts
						(arc
							(start -0.1778 -0.2794)
							(mid -0.249642 -0.249642)
							(end -0.2794 -0.1778)
						)
						(arc
							(start -0.2794 0.1778)
							(mid -0.249642 0.249642)
							(end -0.1778 0.2794)
						)
						(arc
							(start 0.1778 0.2794)
							(mid 0.249642 0.249642)
							(end 0.2794 0.1778)
						)
						(arc
							(start 0.2794 -0.1778)
							(mid 0.249642 -0.249642)
							(end 0.1778 -0.2794)
						)
					)
					(width 0)
					(fill yes)
				)
			)
		)
	)
	(footprint ""
		(layer "F.Cu")
		(at 193.04 -398.272 90)
		(property "Reference" "D16"
			(at 0 0 90)
			(layer "F.SilkS")
			(hide yes)
			(effects
				(font
					(size 1.27 1.27)
				)
			)
		)
		(property "Value" "RB551V30-1-GP"
			(at 0 -6.7818 90)
			(unlocked yes)
			(layer "F.Fab")
			(hide yes)
			(effects
				(font
					(size 1.016 1.016)
					(thickness 0.1524)
				)
			)
		)
		(property "Device Type" "SOD323AKH44"
			(at 0 -8.6868 90)
			(unlocked yes)
			(layer "F.Fab")
			(hide yes)
			(effects
				(font
					(size 1.016 1.016)
					(thickness 0.1524)
				)
			)
		)
		(duplicate_pad_numbers_are_jumpers no)
		(fp_line
			(start 0.889 -1.9304)
			(end 0.889 2.159)
			(stroke
				(width 0.1524)
				(type default)
			)
			(layer "F.SilkS")
		)
		(fp_line
			(start -0.889 -1.9304)
			(end 0.889 -1.9304)
			(stroke
				(width 0.1524)
				(type default)
			)
			(layer "F.SilkS")
		)
		(fp_line
			(start 0.762 2.0574)
			(end -0.762 2.0574)
			(stroke
				(width 0.508)
				(type default)
			)
			(layer "F.SilkS")
		)
		(fp_line
			(start 0.889 2.159)
			(end -0.889 2.159)
			(stroke
				(width 0.1524)
				(type default)
			)
			(layer "F.SilkS")
		)
		(fp_line
			(start -0.889 2.159)
			(end -0.889 -1.9304)
			(stroke
				(width 0.1524)
				(type default)
			)
			(layer "F.SilkS")
		)
		(fp_rect
			(start -1.016 2.3114)
			(end 1.016 -2.0066)
			(stroke
				(width 0)
				(type default)
			)
			(fill no)
			(layer "F.CrtYd")
		)
		(fp_poly
			(pts
				(xy -1.016 -2.0066) (xy 1.016 -2.0066) (xy 1.016 2.3114) (xy -1.016 2.3114)
			)
			(stroke
				(width 0)
				(type default)
			)
			(fill no)
			(layer "F.Fab")
		)
		(pad "A" smd rect
			(at 0 -1.143 90)
			(size 0.5588 1.016)
			(layers "F.Cu" "F.Mask" "F.Paste")
			(net "SW_HDD1_R")
		)
		(pad "K" smd rect
			(at 0 1.143 90)
			(size 0.5588 1.016)
			(layers "F.Cu" "F.Mask" "F.Paste")
			(net "SW_HDD1_N")
		)
	)
	(footprint ""
		(layer "F.Cu")
		(at 14.715744 -260.3627 -90)
		(property "Reference" "R272"
			(at 0 0 270)
			(layer "F.SilkS")
			(hide yes)
			(effects
				(font
					(size 1.27 1.27)
				)
			)
		)
		(property "Value" "0R2J-2-GP"
			(at 0.064008 -3.993896 270)
			(unlocked yes)
			(layer "F.Fab")
			(hide yes)
			(effects
				(font
					(size 1.016 1.016)
					(thickness 0.1524)
				)
			)
		)
		(property "Device Type" "R402H16"
			(at 0.064008 -5.517896 270)
			(unlocked yes)
			(layer "F.Fab")
			(hide yes)
			(effects
				(font
					(size 1.016 1.016)
					(thickness 0.1524)
				)
			)
		)
		(duplicate_pad_numbers_are_jumpers no)
		(fp_line
			(start -0.508 -0.9398)
			(end -0.508 0.9398)
			(stroke
				(width 0.1524)
				(type default)
			)
			(layer "F.SilkS")
		)
		(fp_line
			(start 0.508 -0.9398)
			(end -0.508 -0.9398)
			(stroke
				(width 0.1524)
				(type default)
			)
			(layer "F.SilkS")
		)
		(fp_rect
			(start -0.508 0.9398)
			(end 0.508 -0.9398)
			(stroke
				(width 0)
				(type default)
			)
			(fill no)
			(layer "F.CrtYd")
		)
		(fp_rect
			(start -0.508 0.9398)
			(end 0.508 -0.9398)
			(stroke
				(width 0)
				(type default)
			)
			(fill no)
			(layer "F.Fab")
		)
		(pad "1" smd custom
			(at 0 -0.4445 270)
			(size 0.1397 0.1397)
			(layers "F.Cu" "F.Mask" "F.Paste")
			(net "FLT_NET_HDD12")
			(options
				(clearance outline)
				(anchor circle)
			)
			(primitives
				(gr_poly
					(pts
						(arc
							(start -0.1778 -0.2794)
							(mid -0.249642 -0.249642)
							(end -0.2794 -0.1778)
						)
						(arc
							(start -0.2794 0.1778)
							(mid -0.249642 0.249642)
							(end -0.1778 0.2794)
						)
						(arc
							(start 0.1778 0.2794)
							(mid 0.249642 0.249642)
							(end 0.2794 0.1778)
						)
						(arc
							(start 0.2794 -0.1778)
							(mid 0.249642 -0.249642)
							(end 0.1778 -0.2794)
						)
					)
					(width 0)
					(fill yes)
				)
			)
		)
		(pad "2" smd custom
			(at 0 0.4445 270)
			(size 0.1397 0.1397)
			(layers "F.Cu" "F.Mask" "F.Paste")
			(net "FLT_HDD12_DRIVE")
			(options
				(clearance outline)
				(anchor circle)
			)
			(primitives
				(gr_poly
					(pts
						(arc
							(start -0.1778 -0.2794)
							(mid -0.249642 -0.249642)
							(end -0.2794 -0.1778)
						)
						(arc
							(start -0.2794 0.1778)
							(mid -0.249642 0.249642)
							(end -0.1778 0.2794)
						)
						(arc
							(start 0.1778 0.2794)
							(mid 0.249642 0.249642)
							(end 0.2794 0.1778)
						)
						(arc
							(start 0.2794 -0.1778)
							(mid 0.249642 -0.249642)
							(end 0.1778 -0.2794)
						)
					)
					(width 0)
					(fill yes)
				)
			)
		)
	)
	(footprint ""
		(layer "F.Cu")
		(at 199.263 -487.934)
		(property "Reference" "C102"
			(at 0 0 0)
			(layer "F.SilkS")
			(hide yes)
			(effects
				(font
					(size 1.27 1.27)
				)
			)
		)
		(property "Value" "SCD1U10V2KX-5GP"
			(at 1.1811 -2.7051 0)
			(unlocked yes)
			(layer "F.Fab")
			(hide yes)
			(effects
				(font
					(size 1.016 1.016)
					(thickness 0.1524)
				)
			)
		)
		(property "Device Type" "C402H22"
			(at 1.1811 -4.2291 0)
			(unlocked yes)
			(layer "F.Fab")
			(hide yes)
			(effects
				(font
					(size 1.016 1.016)
					(thickness 0.1524)
				)
			)
		)
		(duplicate_pad_numbers_are_jumpers no)
		(fp_rect
			(start -0.4318 0.9525)
			(end 0.4318 -0.9525)
			(stroke
				(width 0)
				(type default)
			)
			(fill no)
			(layer "F.CrtYd")
		)
		(fp_rect
			(start -0.4318 0.9525)
			(end 0.4318 -0.9525)
			(stroke
				(width 0)
				(type default)
			)
			(fill no)
			(layer "F.Fab")
		)
		(pad "1" smd custom
			(at 0 -0.4445)
			(size 0.1524 0.1524)
			(layers "F.Cu" "F.Mask" "F.Paste")
			(net "P3V3")
			(options
				(clearance outline)
				(anchor circle)
			)
			(primitives
				(gr_poly
					(pts
						(arc
							(start 0.3048 -0.2032)
							(mid 0.275042 -0.275042)
							(end 0.2032 -0.3048)
						)
						(arc
							(start -0.2032 -0.3048)
							(mid -0.275042 -0.275042)
							(end -0.3048 -0.2032)
						)
						(arc
							(start -0.3048 0.2032)
							(mid -0.275042 0.275042)
							(end -0.2032 0.3048)
						)
						(arc
							(start 0.2032 0.3048)
							(mid 0.275042 0.275042)
							(end 0.3048 0.2032)
						)
					)
					(width 0)
					(fill yes)
				)
			)
		)
		(pad "2" smd custom
			(at 0 0.4445)
			(size 0.1524 0.1524)
			(layers "F.Cu" "F.Mask" "F.Paste")
			(net "GND")
			(options
				(clearance outline)
				(anchor circle)
			)
			(primitives
				(gr_poly
					(pts
						(arc
							(start 0.3048 -0.2032)
							(mid 0.275042 -0.275042)
							(end 0.2032 -0.3048)
						)
						(arc
							(start -0.2032 -0.3048)
							(mid -0.275042 -0.275042)
							(end -0.3048 -0.2032)
						)
						(arc
							(start -0.3048 0.2032)
							(mid -0.275042 0.275042)
							(end -0.2032 0.3048)
						)
						(arc
							(start 0.2032 0.3048)
							(mid 0.275042 0.275042)
							(end 0.3048 0.2032)
						)
					)
					(width 0)
					(fill yes)
				)
			)
		)
	)
	(footprint ""
		(layer "F.Cu")
		(at 21.399246 -465.483702 -90)
		(property "Reference" "R243"
			(at 0 0 270)
			(layer "F.SilkS")
			(hide yes)
			(effects
				(font
					(size 1.27 1.27)
				)
			)
		)
		(property "Value" "330R2F-GP"
			(at 0.064008 -3.993896 270)
			(unlocked yes)
			(layer "F.Fab")
			(hide yes)
			(effects
				(font
					(size 1.016 1.016)
					(thickness 0.1524)
				)
			)
		)
		(property "Device Type" "R402H16"
			(at 0.064008 -5.517896 270)
			(unlocked yes)
			(layer "F.Fab")
			(hide yes)
			(effects
				(font
					(size 1.016 1.016)
					(thickness 0.1524)
				)
			)
		)
		(duplicate_pad_numbers_are_jumpers no)
		(fp_line
			(start -0.508 -0.9398)
			(end -0.508 0.9398)
			(stroke
				(width 0.1524)
				(type default)
			)
			(layer "F.SilkS")
		)
		(fp_line
			(start 0.508 -0.9398)
			(end -0.508 -0.9398)
			(stroke
				(width 0.1524)
				(type default)
			)
			(layer "F.SilkS")
		)
		(fp_rect
			(start -0.508 0.9398)
			(end 0.508 -0.9398)
			(stroke
				(width 0)
				(type default)
			)
			(fill no)
			(layer "F.CrtYd")
		)
		(fp_rect
			(start -0.508 0.9398)
			(end 0.508 -0.9398)
			(stroke
				(width 0)
				(type default)
			)
			(fill no)
			(layer "F.Fab")
		)
		(pad "1" smd custom
			(at 0 -0.4445 270)
			(size 0.1397 0.1397)
			(layers "F.Cu" "F.Mask" "F.Paste")
			(net "P3V3_HDD10_LED")
			(options
				(clearance outline)
				(anchor circle)
			)
			(primitives
				(gr_poly
					(pts
						(arc
							(start -0.1778 -0.2794)
							(mid -0.249642 -0.249642)
							(end -0.2794 -0.1778)
						)
						(arc
							(start -0.2794 0.1778)
							(mid -0.249642 0.249642)
							(end -0.1778 0.2794)
						)
						(arc
							(start 0.1778 0.2794)
							(mid 0.249642 0.249642)
							(end 0.2794 0.1778)
						)
						(arc
							(start 0.2794 -0.1778)
							(mid 0.249642 -0.249642)
							(end 0.1778 -0.2794)
						)
					)
					(width 0)
					(fill yes)
				)
			)
		)
		(pad "2" smd custom
			(at 0 0.4445 270)
			(size 0.1397 0.1397)
			(layers "F.Cu" "F.Mask" "F.Paste")
			(net "FLT_HDD10")
			(options
				(clearance outline)
				(anchor circle)
			)
			(primitives
				(gr_poly
					(pts
						(arc
							(start -0.1778 -0.2794)
							(mid -0.249642 -0.249642)
							(end -0.2794 -0.1778)
						)
						(arc
							(start -0.2794 0.1778)
							(mid -0.249642 0.249642)
							(end -0.1778 0.2794)
						)
						(arc
							(start 0.1778 0.2794)
							(mid 0.249642 0.249642)
							(end 0.2794 0.1778)
						)
						(arc
							(start 0.2794 -0.1778)
							(mid 0.249642 -0.249642)
							(end 0.1778 -0.2794)
						)
					)
					(width 0)
					(fill yes)
				)
			)
		)
	)
	(footprint ""
		(layer "F.Cu")
		(at 171.335446 -459.901036 -90)
		(property "Reference" "U53"
			(at 0 0 270)
			(layer "F.SilkS")
			(hide yes)
			(effects
				(font
					(size 1.27 1.27)
				)
			)
		)
		(property "Value" "ADS1015IDGSR-GP"
			(at 0 -11.1252 270)
			(unlocked yes)
			(layer "F.Fab")
			(hide yes)
			(effects
				(font
					(size 1.016 1.016)
					(thickness 0.1524)
				)
			)
		)
		(property "Device Type" "MSOP10H44"
			(at 0 -12.6492 270)
			(unlocked yes)
			(layer "F.Fab")
			(hide yes)
			(effects
				(font
					(size 1.016 1.016)
					(thickness 0.1524)
				)
			)
		)
		(duplicate_pad_numbers_are_jumpers no)
		(fp_line
			(start -2.0066 1.016)
			(end -2.0066 -1.016)
			(stroke
				(width 0.1524)
				(type default)
			)
			(layer "F.SilkS")
		)
		(fp_line
			(start -1.8288 1.016)
			(end -1.8288 3.048)
			(stroke
				(width 0.508)
				(type default)
			)
			(layer "F.SilkS")
		)
		(fp_line
			(start 1.143 1.016)
			(end -2.0066 1.016)
			(stroke
				(width 0.1524)
				(type default)
			)
			(layer "F.SilkS")
		)
		(fp_line
			(start -1.5748 0)
			(end -1.9558 0.381)
			(stroke
				(width 0.1524)
				(type default)
			)
			(layer "F.SilkS")
		)
		(fp_line
			(start -1.5748 0)
			(end -1.9558 -0.381)
			(stroke
				(width 0.1524)
				(type default)
			)
			(layer "F.SilkS")
		)
		(fp_line
			(start -2.0066 -1.016)
			(end 1.143 -1.016)
			(stroke
				(width 0.1524)
				(type default)
			)
			(layer "F.SilkS")
		)
		(fp_line
			(start 1.143 -1.016)
			(end 1.143 1.016)
			(stroke
				(width 0.1524)
				(type default)
			)
			(layer "F.SilkS")
		)
		(fp_poly
			(pts
				(xy -2.0828 3.3401) (xy 2.0828 3.3401) (xy 2.0828 -3.3401) (xy -2.0828 -3.3401)
			)
			(stroke
				(width 0)
				(type default)
			)
			(fill no)
			(layer "F.CrtYd")
		)
		(fp_poly
			(pts
				(xy -2.0828 3.3401) (xy 2.0828 3.3401) (xy 2.0828 -3.3401) (xy -2.0828 -3.3401)
			)
			(stroke
				(width 0)
				(type default)
			)
			(fill no)
			(layer "F.Fab")
		)
		(pad "1" smd rect
			(at -0.99949 2.0701 270)
			(size 0.3048 1.524)
			(layers "F.Cu" "F.Mask" "F.Paste")
			(net "VOL_SEN_ADDR")
		)
		(pad "2" smd rect
			(at -0.50038 2.0701 270)
			(size 0.3048 1.524)
			(layers "F.Cu" "F.Mask" "F.Paste")
			(net "VOL_SEN_ALERT")
		)
		(pad "3" smd rect
			(at 0 2.0701 270)
			(size 0.3048 1.524)
			(layers "F.Cu" "F.Mask" "F.Paste")
			(net "GND")
		)
		(pad "4" smd rect
			(at 0.50038 2.0701 270)
			(size 0.3048 1.524)
			(layers "F.Cu" "F.Mask" "F.Paste")
			(net "P5VA_SENSE")
		)
		(pad "5" smd rect
			(at 0.99949 2.0701 270)
			(size 0.3048 1.524)
			(layers "F.Cu" "F.Mask" "F.Paste")
			(net "P5VB_SENSE")
		)
		(pad "6" smd rect
			(at 0.99949 -2.0701 270)
			(size 0.3048 1.524)
			(layers "F.Cu" "F.Mask" "F.Paste")
			(net "P5VC_SENSE")
		)
		(pad "7" smd rect
			(at 0.50038 -2.0701 270)
			(size 0.3048 1.524)
			(layers "F.Cu" "F.Mask" "F.Paste")
			(net "P12V_SENSE")
		)
		(pad "8" smd rect
			(at 0 -2.0701 270)
			(size 0.3048 1.524)
			(layers "F.Cu" "F.Mask" "F.Paste")
			(net "P3V3")
		)
		(pad "9" smd rect
			(at -0.50038 -2.0701 270)
			(size 0.3048 1.524)
			(layers "F.Cu" "F.Mask" "F.Paste")
			(net "VOL_SEN_SDA")
		)
		(pad "10" smd rect
			(at -0.99949 -2.0701 270)
			(size 0.3048 1.524)
			(layers "F.Cu" "F.Mask" "F.Paste")
			(net "VOL_SEN_SCL")
		)
	)
	(footprint ""
		(layer "F.Cu")
		(at 229.615746 -25.1587 90)
		(property "Reference" "PR8"
			(at 0 0 90)
			(layer "F.SilkS")
			(hide yes)
			(effects
				(font
					(size 1.27 1.27)
				)
			)
		)
		(property "Value" "3D01R2F-GP"
			(at 0.064008 -3.993896 90)
			(unlocked yes)
			(layer "F.Fab")
			(hide yes)
			(effects
				(font
					(size 1.016 1.016)
					(thickness 0.1524)
				)
			)
		)
		(property "Device Type" "R402H16"
			(at 0.064008 -5.517896 90)
			(unlocked yes)
			(layer "F.Fab")
			(hide yes)
			(effects
				(font
					(size 1.016 1.016)
					(thickness 0.1524)
				)
			)
		)
		(duplicate_pad_numbers_are_jumpers no)
		(fp_line
			(start 0.508 -0.9398)
			(end -0.508 -0.9398)
			(stroke
				(width 0.1524)
				(type default)
			)
			(layer "F.SilkS")
		)
		(fp_line
			(start -0.508 -0.9398)
			(end -0.508 0.9398)
			(stroke
				(width 0.1524)
				(type default)
			)
			(layer "F.SilkS")
		)
		(fp_rect
			(start -0.508 0.9398)
			(end 0.508 -0.9398)
			(stroke
				(width 0)
				(type default)
			)
			(fill no)
			(layer "F.CrtYd")
		)
		(fp_rect
			(start -0.508 0.9398)
			(end 0.508 -0.9398)
			(stroke
				(width 0)
				(type default)
			)
			(fill no)
			(layer "F.Fab")
		)
		(pad "1" smd custom
			(at 0 -0.4445 90)
			(size 0.1397 0.1397)
			(layers "F.Cu" "F.Mask" "F.Paste")
			(net "GND")
			(options
				(clearance outline)
				(anchor circle)
			)
			(primitives
				(gr_poly
					(pts
						(arc
							(start -0.1778 -0.2794)
							(mid -0.249642 -0.249642)
							(end -0.2794 -0.1778)
						)
						(arc
							(start -0.2794 0.1778)
							(mid -0.249642 0.249642)
							(end -0.1778 0.2794)
						)
						(arc
							(start 0.1778 0.2794)
							(mid 0.249642 0.249642)
							(end 0.2794 0.1778)
						)
						(arc
							(start 0.2794 -0.1778)
							(mid 0.249642 -0.249642)
							(end 0.1778 -0.2794)
						)
					)
					(width 0)
					(fill yes)
				)
			)
		)
		(pad "2" smd custom
			(at 0 0.4445 90)
			(size 0.1397 0.1397)
			(layers "F.Cu" "F.Mask" "F.Paste")
			(net "P5VA_SNB")
			(options
				(clearance outline)
				(anchor circle)
			)
			(primitives
				(gr_poly
					(pts
						(arc
							(start -0.1778 -0.2794)
							(mid -0.249642 -0.249642)
							(end -0.2794 -0.1778)
						)
						(arc
							(start -0.2794 0.1778)
							(mid -0.249642 0.249642)
							(end -0.1778 0.2794)
						)
						(arc
							(start 0.1778 0.2794)
							(mid 0.249642 0.249642)
							(end 0.2794 0.1778)
						)
						(arc
							(start 0.2794 -0.1778)
							(mid 0.249642 -0.249642)
							(end 0.1778 -0.2794)
						)
					)
					(width 0)
					(fill yes)
				)
			)
		)
	)
	(footprint ""
		(layer "F.Cu")
		(at 195.453 -290.449 180)
		(property "Reference" "R410"
			(at 0 0 180)
			(layer "F.SilkS")
			(hide yes)
			(effects
				(font
					(size 1.27 1.27)
				)
			)
		)
		(property "Value" "0R2J-2-GP"
			(at 0.064008 -3.993896 180)
			(unlocked yes)
			(layer "F.Fab")
			(hide yes)
			(effects
				(font
					(size 1.016 1.016)
					(thickness 0.1524)
				)
			)
		)
		(property "Device Type" "R402H16"
			(at 0.064008 -5.517896 180)
			(unlocked yes)
			(layer "F.Fab")
			(hide yes)
			(effects
				(font
					(size 1.016 1.016)
					(thickness 0.1524)
				)
			)
		)
		(duplicate_pad_numbers_are_jumpers no)
		(fp_line
			(start 0.508 -0.9398)
			(end -0.508 -0.9398)
			(stroke
				(width 0.1524)
				(type default)
			)
			(layer "F.SilkS")
		)
		(fp_line
			(start -0.508 -0.9398)
			(end -0.508 0.9398)
			(stroke
				(width 0.1524)
				(type default)
			)
			(layer "F.SilkS")
		)
		(fp_rect
			(start -0.508 0.9398)
			(end 0.508 -0.9398)
			(stroke
				(width 0)
				(type default)
			)
			(fill no)
			(layer "F.CrtYd")
		)
		(fp_rect
			(start -0.508 0.9398)
			(end 0.508 -0.9398)
			(stroke
				(width 0)
				(type default)
			)
			(fill no)
			(layer "F.Fab")
		)
		(pad "1" smd custom
			(at 0 -0.4445 180)
			(size 0.1397 0.1397)
			(layers "F.Cu" "F.Mask" "F.Paste")
			(net "SW_HDD2_G")
			(options
				(clearance outline)
				(anchor circle)
			)
			(primitives
				(gr_poly
					(pts
						(arc
							(start -0.1778 -0.2794)
							(mid -0.249642 -0.249642)
							(end -0.2794 -0.1778)
						)
						(arc
							(start -0.2794 0.1778)
							(mid -0.249642 0.249642)
							(end -0.1778 0.2794)
						)
						(arc
							(start 0.1778 0.2794)
							(mid 0.249642 0.249642)
							(end 0.2794 0.1778)
						)
						(arc
							(start 0.2794 -0.1778)
							(mid 0.249642 -0.249642)
							(end 0.1778 -0.2794)
						)
					)
					(width 0)
					(fill yes)
				)
			)
		)
		(pad "2" smd custom
			(at 0 0.4445 180)
			(size 0.1397 0.1397)
			(layers "F.Cu" "F.Mask" "F.Paste")
			(net "SW_HDD2_R")
			(options
				(clearance outline)
				(anchor circle)
			)
			(primitives
				(gr_poly
					(pts
						(arc
							(start -0.1778 -0.2794)
							(mid -0.249642 -0.249642)
							(end -0.2794 -0.1778)
						)
						(arc
							(start -0.2794 0.1778)
							(mid -0.249642 0.249642)
							(end -0.1778 0.2794)
						)
						(arc
							(start 0.1778 0.2794)
							(mid 0.249642 0.249642)
							(end 0.2794 0.1778)
						)
						(arc
							(start 0.2794 -0.1778)
							(mid 0.249642 -0.249642)
							(end 0.1778 -0.2794)
						)
					)
					(width 0)
					(fill yes)
				)
			)
		)
	)
	(footprint ""
		(layer "F.Cu")
		(at 217.799412 -63.353696 -90)
		(property "Reference" "C168"
			(at 0 0 270)
			(layer "F.SilkS")
			(hide yes)
			(effects
				(font
					(size 1.27 1.27)
				)
			)
		)
		(property "Value" "SCD01U50V2KX-1GP"
			(at 1.1811 -2.7051 270)
			(unlocked yes)
			(layer "F.Fab")
			(hide yes)
			(effects
				(font
					(size 1.016 1.016)
					(thickness 0.1524)
				)
			)
		)
		(property "Device Type" "C402H22"
			(at 1.1811 -4.2291 270)
			(unlocked yes)
			(layer "F.Fab")
			(hide yes)
			(effects
				(font
					(size 1.016 1.016)
					(thickness 0.1524)
				)
			)
		)
		(duplicate_pad_numbers_are_jumpers no)
		(fp_rect
			(start -0.4318 0.9525)
			(end 0.4318 -0.9525)
			(stroke
				(width 0)
				(type default)
			)
			(fill no)
			(layer "F.CrtYd")
		)
		(fp_rect
			(start -0.4318 0.9525)
			(end 0.4318 -0.9525)
			(stroke
				(width 0)
				(type default)
			)
			(fill no)
			(layer "F.Fab")
		)
		(pad "1" smd custom
			(at 0 -0.4445 270)
			(size 0.1524 0.1524)
			(layers "F.Cu" "F.Mask" "F.Paste")
			(net "SAS2X28_DRIVE_RX_N_B4")
			(options
				(clearance outline)
				(anchor circle)
			)
			(primitives
				(gr_poly
					(pts
						(arc
							(start 0.3048 -0.2032)
							(mid 0.275042 -0.275042)
							(end 0.2032 -0.3048)
						)
						(arc
							(start -0.2032 -0.3048)
							(mid -0.275042 -0.275042)
							(end -0.3048 -0.2032)
						)
						(arc
							(start -0.3048 0.2032)
							(mid -0.275042 0.275042)
							(end -0.2032 0.3048)
						)
						(arc
							(start 0.2032 0.3048)
							(mid 0.275042 0.275042)
							(end 0.3048 0.2032)
						)
					)
					(width 0)
					(fill yes)
				)
			)
		)
		(pad "2" smd custom
			(at 0 0.4445 270)
			(size 0.1524 0.1524)
			(layers "F.Cu" "F.Mask" "F.Paste")
			(net "SAS2X28_B_HDD4_RX_-")
			(options
				(clearance outline)
				(anchor circle)
			)
			(primitives
				(gr_poly
					(pts
						(arc
							(start 0.3048 -0.2032)
							(mid 0.275042 -0.275042)
							(end 0.2032 -0.3048)
						)
						(arc
							(start -0.2032 -0.3048)
							(mid -0.275042 -0.275042)
							(end -0.3048 -0.2032)
						)
						(arc
							(start -0.3048 0.2032)
							(mid -0.275042 0.275042)
							(end -0.2032 0.3048)
						)
						(arc
							(start 0.2032 0.3048)
							(mid 0.275042 0.275042)
							(end 0.3048 0.2032)
						)
					)
					(width 0)
					(fill yes)
				)
			)
		)
	)
	(footprint ""
		(layer "F.Cu")
		(at 77.469746 -395.8717 -90)
		(property "Reference" "R197"
			(at 0 0 270)
			(layer "F.SilkS")
			(hide yes)
			(effects
				(font
					(size 1.27 1.27)
				)
			)
		)
		(property "Value" "0R2J-2-GP"
			(at 0.064008 -3.993896 270)
			(unlocked yes)
			(layer "F.Fab")
			(hide yes)
			(effects
				(font
					(size 1.016 1.016)
					(thickness 0.1524)
				)
			)
		)
		(property "Device Type" "R402H16"
			(at 0.064008 -5.517896 270)
			(unlocked yes)
			(layer "F.Fab")
			(hide yes)
			(effects
				(font
					(size 1.016 1.016)
					(thickness 0.1524)
				)
			)
		)
		(duplicate_pad_numbers_are_jumpers no)
		(fp_line
			(start -0.508 -0.9398)
			(end -0.508 0.9398)
			(stroke
				(width 0.1524)
				(type default)
			)
			(layer "F.SilkS")
		)
		(fp_line
			(start 0.508 -0.9398)
			(end -0.508 -0.9398)
			(stroke
				(width 0.1524)
				(type default)
			)
			(layer "F.SilkS")
		)
		(fp_rect
			(start -0.508 0.9398)
			(end 0.508 -0.9398)
			(stroke
				(width 0)
				(type default)
			)
			(fill no)
			(layer "F.CrtYd")
		)
		(fp_rect
			(start -0.508 0.9398)
			(end 0.508 -0.9398)
			(stroke
				(width 0)
				(type default)
			)
			(fill no)
			(layer "F.Fab")
		)
		(pad "1" smd custom
			(at 0 -0.4445 270)
			(size 0.1397 0.1397)
			(layers "F.Cu" "F.Mask" "F.Paste")
			(net "DRIVE_PWR6")
			(options
				(clearance outline)
				(anchor circle)
			)
			(primitives
				(gr_poly
					(pts
						(arc
							(start -0.1778 -0.2794)
							(mid -0.249642 -0.249642)
							(end -0.2794 -0.1778)
						)
						(arc
							(start -0.2794 0.1778)
							(mid -0.249642 0.249642)
							(end -0.1778 0.2794)
						)
						(arc
							(start 0.1778 0.2794)
							(mid 0.249642 0.249642)
							(end 0.2794 0.1778)
						)
						(arc
							(start 0.2794 -0.1778)
							(mid 0.249642 -0.249642)
							(end 0.1778 -0.2794)
						)
					)
					(width 0)
					(fill yes)
				)
			)
		)
		(pad "2" smd custom
			(at 0 0.4445 270)
			(size 0.1397 0.1397)
			(layers "F.Cu" "F.Mask" "F.Paste")
			(net "SW_PWR_HDD6")
			(options
				(clearance outline)
				(anchor circle)
			)
			(primitives
				(gr_poly
					(pts
						(arc
							(start -0.1778 -0.2794)
							(mid -0.249642 -0.249642)
							(end -0.2794 -0.1778)
						)
						(arc
							(start -0.2794 0.1778)
							(mid -0.249642 0.249642)
							(end -0.1778 0.2794)
						)
						(arc
							(start 0.1778 0.2794)
							(mid 0.249642 0.249642)
							(end 0.2794 0.1778)
						)
						(arc
							(start 0.2794 -0.1778)
							(mid 0.249642 -0.249642)
							(end 0.1778 -0.2794)
						)
					)
					(width 0)
					(fill yes)
				)
			)
		)
	)
	(footprint ""
		(layer "F.Cu")
		(at 43.865546 -133.3119 -90)
		(property "Reference" "R325"
			(at 0 0 270)
			(layer "F.SilkS")
			(hide yes)
			(effects
				(font
					(size 1.27 1.27)
				)
			)
		)
		(property "Value" "4K7R2J-2-GP"
			(at 0.064008 -3.993896 270)
			(unlocked yes)
			(layer "F.Fab")
			(hide yes)
			(effects
				(font
					(size 1.016 1.016)
					(thickness 0.1524)
				)
			)
		)
		(property "Device Type" "R402H16"
			(at 0.064008 -5.517896 270)
			(unlocked yes)
			(layer "F.Fab")
			(hide yes)
			(effects
				(font
					(size 1.016 1.016)
					(thickness 0.1524)
				)
			)
		)
		(duplicate_pad_numbers_are_jumpers no)
		(fp_line
			(start -0.508 -0.9398)
			(end -0.508 0.9398)
			(stroke
				(width 0.1524)
				(type default)
			)
			(layer "F.SilkS")
		)
		(fp_line
			(start 0.508 -0.9398)
			(end -0.508 -0.9398)
			(stroke
				(width 0.1524)
				(type default)
			)
			(layer "F.SilkS")
		)
		(fp_rect
			(start -0.508 0.9398)
			(end 0.508 -0.9398)
			(stroke
				(width 0)
				(type default)
			)
			(fill no)
			(layer "F.CrtYd")
		)
		(fp_rect
			(start -0.508 0.9398)
			(end 0.508 -0.9398)
			(stroke
				(width 0)
				(type default)
			)
			(fill no)
			(layer "F.Fab")
		)
		(pad "1" smd custom
			(at 0 -0.4445 270)
			(size 0.1397 0.1397)
			(layers "F.Cu" "F.Mask" "F.Paste")
			(net "I2C_B_TMP2_A0")
			(options
				(clearance outline)
				(anchor circle)
			)
			(primitives
				(gr_poly
					(pts
						(arc
							(start -0.1778 -0.2794)
							(mid -0.249642 -0.249642)
							(end -0.2794 -0.1778)
						)
						(arc
							(start -0.2794 0.1778)
							(mid -0.249642 0.249642)
							(end -0.1778 0.2794)
						)
						(arc
							(start 0.1778 0.2794)
							(mid 0.249642 0.249642)
							(end 0.2794 0.1778)
						)
						(arc
							(start 0.2794 -0.1778)
							(mid 0.249642 -0.249642)
							(end 0.1778 -0.2794)
						)
					)
					(width 0)
					(fill yes)
				)
			)
		)
		(pad "2" smd custom
			(at 0 0.4445 270)
			(size 0.1397 0.1397)
			(layers "F.Cu" "F.Mask" "F.Paste")
			(net "GND")
			(options
				(clearance outline)
				(anchor circle)
			)
			(primitives
				(gr_poly
					(pts
						(arc
							(start -0.1778 -0.2794)
							(mid -0.249642 -0.249642)
							(end -0.2794 -0.1778)
						)
						(arc
							(start -0.2794 0.1778)
							(mid -0.249642 0.249642)
							(end -0.1778 0.2794)
						)
						(arc
							(start 0.1778 0.2794)
							(mid 0.249642 0.249642)
							(end 0.2794 0.1778)
						)
						(arc
							(start 0.2794 -0.1778)
							(mid 0.249642 -0.249642)
							(end 0.1778 -0.2794)
						)
					)
					(width 0)
					(fill yes)
				)
			)
		)
	)
	(footprint ""
		(layer "F.Cu")
		(at 215.3412 -377.9774 -90)
		(property "Reference" "R353"
			(at 0 0 270)
			(layer "F.SilkS")
			(hide yes)
			(effects
				(font
					(size 1.27 1.27)
				)
			)
		)
		(property "Value" "0R2J-2-GP"
			(at 0.064008 -3.993896 270)
			(unlocked yes)
			(layer "F.Fab")
			(hide yes)
			(effects
				(font
					(size 1.016 1.016)
					(thickness 0.1524)
				)
			)
		)
		(property "Device Type" "R402H16"
			(at 0.064008 -5.517896 270)
			(unlocked yes)
			(layer "F.Fab")
			(hide yes)
			(effects
				(font
					(size 1.016 1.016)
					(thickness 0.1524)
				)
			)
		)
		(duplicate_pad_numbers_are_jumpers no)
		(fp_line
			(start -0.508 -0.9398)
			(end -0.508 0.9398)
			(stroke
				(width 0.1524)
				(type default)
			)
			(layer "F.SilkS")
		)
		(fp_line
			(start 0.508 -0.9398)
			(end -0.508 -0.9398)
			(stroke
				(width 0.1524)
				(type default)
			)
			(layer "F.SilkS")
		)
		(fp_rect
			(start -0.508 0.9398)
			(end 0.508 -0.9398)
			(stroke
				(width 0)
				(type default)
			)
			(fill no)
			(layer "F.CrtYd")
		)
		(fp_rect
			(start -0.508 0.9398)
			(end 0.508 -0.9398)
			(stroke
				(width 0)
				(type default)
			)
			(fill no)
			(layer "F.Fab")
		)
		(pad "1" smd custom
			(at 0 -0.4445 270)
			(size 0.1397 0.1397)
			(layers "F.Cu" "F.Mask" "F.Paste")
			(net "HDD_PRSNT_NET1")
			(options
				(clearance outline)
				(anchor circle)
			)
			(primitives
				(gr_poly
					(pts
						(arc
							(start -0.1778 -0.2794)
							(mid -0.249642 -0.249642)
							(end -0.2794 -0.1778)
						)
						(arc
							(start -0.2794 0.1778)
							(mid -0.249642 0.249642)
							(end -0.1778 0.2794)
						)
						(arc
							(start 0.1778 0.2794)
							(mid 0.249642 0.249642)
							(end 0.2794 0.1778)
						)
						(arc
							(start 0.2794 -0.1778)
							(mid 0.249642 -0.249642)
							(end 0.1778 -0.2794)
						)
					)
					(width 0)
					(fill yes)
				)
			)
		)
		(pad "2" smd custom
			(at 0 0.4445 270)
			(size 0.1397 0.1397)
			(layers "F.Cu" "F.Mask" "F.Paste")
			(net "HDD1_LED_B")
			(options
				(clearance outline)
				(anchor circle)
			)
			(primitives
				(gr_poly
					(pts
						(arc
							(start -0.1778 -0.2794)
							(mid -0.249642 -0.249642)
							(end -0.2794 -0.1778)
						)
						(arc
							(start -0.2794 0.1778)
							(mid -0.249642 0.249642)
							(end -0.1778 0.2794)
						)
						(arc
							(start 0.1778 0.2794)
							(mid 0.249642 0.249642)
							(end 0.2794 0.1778)
						)
						(arc
							(start 0.2794 -0.1778)
							(mid 0.249642 -0.249642)
							(end 0.1778 -0.2794)
						)
					)
					(width 0)
					(fill yes)
				)
			)
		)
	)
	(footprint ""
		(layer "F.Cu")
		(at 17.500092 -258.83997)
		(property "Reference" "LED13"
			(at 0 0 0)
			(layer "F.SilkS")
			(hide yes)
			(effects
				(font
					(size 1.27 1.27)
				)
			)
		)
		(property "Value" "LED-RB-4-GP"
			(at 5.88899 1.80848 0)
			(unlocked yes)
			(layer "F.Fab")
			(hide yes)
			(effects
				(font
					(size 1.016 1.016)
					(thickness 0.1524)
				)
			)
		)
		(property "Device Type" "LED1613-4PH20"
			(at 5.88899 0.28448 0)
			(unlocked yes)
			(layer "F.Fab")
			(hide yes)
			(effects
				(font
					(size 1.016 1.016)
					(thickness 0.1524)
				)
			)
		)
		(duplicate_pad_numbers_are_jumpers no)
		(fp_line
			(start -1.4478 -0.9652)
			(end 1.4478 -0.9652)
			(stroke
				(width 0.1524)
				(type default)
			)
			(layer "F.SilkS")
		)
		(fp_line
			(start -1.4478 0.9652)
			(end -1.4478 -0.9652)
			(stroke
				(width 0.1524)
				(type default)
			)
			(layer "F.SilkS")
		)
		(fp_line
			(start -1.4478 0.9652)
			(end -1.4478 -0.9652)
			(stroke
				(width 0.508)
				(type default)
			)
			(layer "F.SilkS")
		)
		(fp_line
			(start 1.4478 -0.9652)
			(end 1.4478 0.9652)
			(stroke
				(width 0.1524)
				(type default)
			)
			(layer "F.SilkS")
		)
		(fp_line
			(start 1.4478 0.9652)
			(end -1.4478 0.9652)
			(stroke
				(width 0.1524)
				(type default)
			)
			(layer "F.SilkS")
		)
		(fp_rect
			(start -0.8001 0.6477)
			(end 0.8001 -0.6477)
			(stroke
				(width 0)
				(type default)
			)
			(fill no)
			(layer "F.CrtYd")
		)
		(fp_poly
			(pts
				(xy -1.7018 1.2192) (xy -1.7018 -0.06223) (xy -0.8001 -0.06223) (xy -0.8001 0.6477) (xy 0.8001 0.6477)
				(xy 0.8001 -0.6477) (xy -0.8001 -0.6477) (xy -0.8001 -0.0635) (xy -1.7018 -0.0635) (xy -1.7018 -1.2192)
				(xy 1.7018 -1.2192) (xy 1.7018 1.2192)
			)
			(stroke
				(width 0)
				(type default)
			)
			(fill no)
			(layer "F.CrtYd")
		)
		(fp_rect
			(start -1.7018 1.2192)
			(end 1.7018 -1.2192)
			(stroke
				(width 0)
				(type default)
			)
			(fill no)
			(layer "F.Fab")
		)
		(pad "1" smd rect
			(at -0.73025 0.4064)
			(size 0.9144 0.6096)
			(layers "F.Cu" "F.Mask" "F.Paste")
			(net "DRV_ACT_NET12")
		)
		(pad "2" smd rect
			(at -0.73025 -0.4064)
			(size 0.9144 0.6096)
			(layers "F.Cu" "F.Mask" "F.Paste")
			(net "FLT_NET_HDD12")
		)
		(pad "3" smd rect
			(at 0.73025 -0.4064)
			(size 0.9144 0.6096)
			(layers "F.Cu" "F.Mask" "F.Paste")
			(net "FLT_HDD12")
		)
		(pad "4" smd rect
			(at 0.73025 0.4064)
			(size 0.9144 0.6096)
			(layers "F.Cu" "F.Mask" "F.Paste")
			(net "DRV_ACT_12")
		)
	)
	(footprint ""
		(layer "F.Cu")
		(at 58.895488 -23.513288 -90)
		(property "Reference" "PR28"
			(at 0 0 270)
			(layer "F.SilkS")
			(hide yes)
			(effects
				(font
					(size 1.27 1.27)
				)
			)
		)
		(property "Value" "0R2J-2-GP"
			(at 0.064008 -3.993896 270)
			(unlocked yes)
			(layer "F.Fab")
			(hide yes)
			(effects
				(font
					(size 1.016 1.016)
					(thickness 0.1524)
				)
			)
		)
		(property "Device Type" "R402H16"
			(at 0.064008 -5.517896 270)
			(unlocked yes)
			(layer "F.Fab")
			(hide yes)
			(effects
				(font
					(size 1.016 1.016)
					(thickness 0.1524)
				)
			)
		)
		(duplicate_pad_numbers_are_jumpers no)
		(fp_line
			(start -0.508 -0.9398)
			(end -0.508 0.9398)
			(stroke
				(width 0.1524)
				(type default)
			)
			(layer "F.SilkS")
		)
		(fp_line
			(start 0.508 -0.9398)
			(end -0.508 -0.9398)
			(stroke
				(width 0.1524)
				(type default)
			)
			(layer "F.SilkS")
		)
		(fp_rect
			(start -0.508 0.9398)
			(end 0.508 -0.9398)
			(stroke
				(width 0)
				(type default)
			)
			(fill no)
			(layer "F.CrtYd")
		)
		(fp_rect
			(start -0.508 0.9398)
			(end 0.508 -0.9398)
			(stroke
				(width 0)
				(type default)
			)
			(fill no)
			(layer "F.Fab")
		)
		(pad "1" smd custom
			(at 0 -0.4445 270)
			(size 0.1397 0.1397)
			(layers "F.Cu" "F.Mask" "F.Paste")
			(net "P5VB_MODE_PG")
			(options
				(clearance outline)
				(anchor circle)
			)
			(primitives
				(gr_poly
					(pts
						(arc
							(start -0.1778 -0.2794)
							(mid -0.249642 -0.249642)
							(end -0.2794 -0.1778)
						)
						(arc
							(start -0.2794 0.1778)
							(mid -0.249642 0.249642)
							(end -0.1778 0.2794)
						)
						(arc
							(start 0.1778 0.2794)
							(mid 0.249642 0.249642)
							(end 0.2794 0.1778)
						)
						(arc
							(start 0.2794 -0.1778)
							(mid 0.249642 -0.249642)
							(end 0.1778 -0.2794)
						)
					)
					(width 0)
					(fill yes)
				)
			)
		)
		(pad "2" smd custom
			(at 0 0.4445 270)
			(size 0.1397 0.1397)
			(layers "F.Cu" "F.Mask" "F.Paste")
			(net "P5VB_MODE")
			(options
				(clearance outline)
				(anchor circle)
			)
			(primitives
				(gr_poly
					(pts
						(arc
							(start -0.1778 -0.2794)
							(mid -0.249642 -0.249642)
							(end -0.2794 -0.1778)
						)
						(arc
							(start -0.2794 0.1778)
							(mid -0.249642 0.249642)
							(end -0.1778 0.2794)
						)
						(arc
							(start 0.1778 0.2794)
							(mid 0.249642 0.249642)
							(end 0.2794 0.1778)
						)
						(arc
							(start 0.2794 -0.1778)
							(mid 0.249642 -0.249642)
							(end 0.1778 -0.2794)
						)
					)
					(width 0)
					(fill yes)
				)
			)
		)
	)
	(footprint ""
		(layer "F.Cu")
		(at 164.858446 -460.409036)
		(property "Reference" "R362"
			(at 0 0 0)
			(layer "F.SilkS")
			(hide yes)
			(effects
				(font
					(size 1.27 1.27)
				)
			)
		)
		(property "Value" "4K7R2F-GP"
			(at 0.064008 -3.993896 0)
			(unlocked yes)
			(layer "F.Fab")
			(hide yes)
			(effects
				(font
					(size 1.016 1.016)
					(thickness 0.1524)
				)
			)
		)
		(property "Device Type" "R402H16"
			(at 0.064008 -5.517896 0)
			(unlocked yes)
			(layer "F.Fab")
			(hide yes)
			(effects
				(font
					(size 1.016 1.016)
					(thickness 0.1524)
				)
			)
		)
		(duplicate_pad_numbers_are_jumpers no)
		(fp_line
			(start -0.508 -0.9398)
			(end -0.508 0.9398)
			(stroke
				(width 0.1524)
				(type default)
			)
			(layer "F.SilkS")
		)
		(fp_line
			(start 0.508 -0.9398)
			(end -0.508 -0.9398)
			(stroke
				(width 0.1524)
				(type default)
			)
			(layer "F.SilkS")
		)
		(fp_rect
			(start -0.508 0.9398)
			(end 0.508 -0.9398)
			(stroke
				(width 0)
				(type default)
			)
			(fill no)
			(layer "F.CrtYd")
		)
		(fp_rect
			(start -0.508 0.9398)
			(end 0.508 -0.9398)
			(stroke
				(width 0)
				(type default)
			)
			(fill no)
			(layer "F.Fab")
		)
		(pad "1" smd custom
			(at 0 -0.4445)
			(size 0.1397 0.1397)
			(layers "F.Cu" "F.Mask" "F.Paste")
			(net "P3V3")
			(options
				(clearance outline)
				(anchor circle)
			)
			(primitives
				(gr_poly
					(pts
						(arc
							(start -0.1778 -0.2794)
							(mid -0.249642 -0.249642)
							(end -0.2794 -0.1778)
						)
						(arc
							(start -0.2794 0.1778)
							(mid -0.249642 0.249642)
							(end -0.1778 0.2794)
						)
						(arc
							(start 0.1778 0.2794)
							(mid 0.249642 0.249642)
							(end 0.2794 0.1778)
						)
						(arc
							(start 0.2794 -0.1778)
							(mid 0.249642 -0.249642)
							(end 0.1778 -0.2794)
						)
					)
					(width 0)
					(fill yes)
				)
			)
		)
		(pad "2" smd custom
			(at 0 0.4445)
			(size 0.1397 0.1397)
			(layers "F.Cu" "F.Mask" "F.Paste")
			(net "VOL_SEN_ALERT")
			(options
				(clearance outline)
				(anchor circle)
			)
			(primitives
				(gr_poly
					(pts
						(arc
							(start -0.1778 -0.2794)
							(mid -0.249642 -0.249642)
							(end -0.2794 -0.1778)
						)
						(arc
							(start -0.2794 0.1778)
							(mid -0.249642 0.249642)
							(end -0.1778 0.2794)
						)
						(arc
							(start 0.1778 0.2794)
							(mid 0.249642 0.249642)
							(end 0.2794 0.1778)
						)
						(arc
							(start 0.2794 -0.1778)
							(mid 0.249642 -0.249642)
							(end 0.1778 -0.2794)
						)
					)
					(width 0)
					(fill yes)
				)
			)
		)
	)
	(footprint ""
		(layer "F.Cu")
		(at 17.500092 -464.840066)
		(property "Reference" "LED11"
			(at 0 0 0)
			(layer "F.SilkS")
			(hide yes)
			(effects
				(font
					(size 1.27 1.27)
				)
			)
		)
		(property "Value" "LED-RB-4-GP"
			(at 5.88899 1.80848 0)
			(unlocked yes)
			(layer "F.Fab")
			(hide yes)
			(effects
				(font
					(size 1.016 1.016)
					(thickness 0.1524)
				)
			)
		)
		(property "Device Type" "LED1613-4PH20"
			(at 5.88899 0.28448 0)
			(unlocked yes)
			(layer "F.Fab")
			(hide yes)
			(effects
				(font
					(size 1.016 1.016)
					(thickness 0.1524)
				)
			)
		)
		(duplicate_pad_numbers_are_jumpers no)
		(fp_line
			(start -1.4478 -0.9652)
			(end 1.4478 -0.9652)
			(stroke
				(width 0.1524)
				(type default)
			)
			(layer "F.SilkS")
		)
		(fp_line
			(start -1.4478 0.9652)
			(end -1.4478 -0.9652)
			(stroke
				(width 0.1524)
				(type default)
			)
			(layer "F.SilkS")
		)
		(fp_line
			(start -1.4478 0.9652)
			(end -1.4478 -0.9652)
			(stroke
				(width 0.508)
				(type default)
			)
			(layer "F.SilkS")
		)
		(fp_line
			(start 1.4478 -0.9652)
			(end 1.4478 0.9652)
			(stroke
				(width 0.1524)
				(type default)
			)
			(layer "F.SilkS")
		)
		(fp_line
			(start 1.4478 0.9652)
			(end -1.4478 0.9652)
			(stroke
				(width 0.1524)
				(type default)
			)
			(layer "F.SilkS")
		)
		(fp_rect
			(start -0.8001 0.6477)
			(end 0.8001 -0.6477)
			(stroke
				(width 0)
				(type default)
			)
			(fill no)
			(layer "F.CrtYd")
		)
		(fp_poly
			(pts
				(xy -1.7018 1.2192) (xy -1.7018 -0.06223) (xy -0.8001 -0.06223) (xy -0.8001 0.6477) (xy 0.8001 0.6477)
				(xy 0.8001 -0.6477) (xy -0.8001 -0.6477) (xy -0.8001 -0.0635) (xy -1.7018 -0.0635) (xy -1.7018 -1.2192)
				(xy 1.7018 -1.2192) (xy 1.7018 1.2192)
			)
			(stroke
				(width 0)
				(type default)
			)
			(fill no)
			(layer "F.CrtYd")
		)
		(fp_rect
			(start -1.7018 1.2192)
			(end 1.7018 -1.2192)
			(stroke
				(width 0)
				(type default)
			)
			(fill no)
			(layer "F.Fab")
		)
		(pad "1" smd rect
			(at -0.73025 0.4064)
			(size 0.9144 0.6096)
			(layers "F.Cu" "F.Mask" "F.Paste")
			(net "DRV_ACT_NET10")
		)
		(pad "2" smd rect
			(at -0.73025 -0.4064)
			(size 0.9144 0.6096)
			(layers "F.Cu" "F.Mask" "F.Paste")
			(net "FLT_NET_HDD10")
		)
		(pad "3" smd rect
			(at 0.73025 -0.4064)
			(size 0.9144 0.6096)
			(layers "F.Cu" "F.Mask" "F.Paste")
			(net "FLT_HDD10")
		)
		(pad "4" smd rect
			(at 0.73025 0.4064)
			(size 0.9144 0.6096)
			(layers "F.Cu" "F.Mask" "F.Paste")
			(net "DRV_ACT_10")
		)
	)
	(footprint ""
		(layer "F.Cu")
		(at 216.026746 -492.8997 -90)
		(property "Reference" "R110"
			(at 0 0 270)
			(layer "F.SilkS")
			(hide yes)
			(effects
				(font
					(size 1.27 1.27)
				)
			)
		)
		(property "Value" "2R2010J-1-GP"
			(at 0.254 -8.0772 270)
			(unlocked yes)
			(layer "F.Fab")
			(hide yes)
			(effects
				(font
					(size 1.016 1.016)
					(thickness 0.1524)
				)
			)
		)
		(property "Device Type" "R2010H28"
			(at 0.254 -9.6774 270)
			(unlocked yes)
			(layer "F.Fab")
			(hide yes)
			(effects
				(font
					(size 1.016 1.016)
					(thickness 0.1524)
				)
			)
		)
		(duplicate_pad_numbers_are_jumpers no)
		(fp_line
			(start -1.651 3.302)
			(end 1.651 3.302)
			(stroke
				(width 0.1524)
				(type default)
			)
			(layer "F.SilkS")
		)
		(fp_line
			(start 1.651 3.302)
			(end 1.651 -3.302)
			(stroke
				(width 0.1524)
				(type default)
			)
			(layer "F.SilkS")
		)
		(fp_line
			(start -1.651 -3.302)
			(end -1.651 3.302)
			(stroke
				(width 0.1524)
				(type default)
			)
			(layer "F.SilkS")
		)
		(fp_line
			(start 1.651 -3.302)
			(end -1.651 -3.302)
			(stroke
				(width 0.1524)
				(type default)
			)
			(layer "F.SilkS")
		)
		(fp_rect
			(start -1.7272 -3.3782)
			(end 1.7272 3.3782)
			(stroke
				(width 0)
				(type default)
			)
			(fill no)
			(layer "F.CrtYd")
		)
		(fp_poly
			(pts
				(xy 1.7272 3.3782) (xy 1.7272 -3.3782) (xy -1.7272 -3.3782) (xy -1.7272 3.3782)
			)
			(stroke
				(width 0)
				(type default)
			)
			(fill no)
			(layer "F.Fab")
		)
		(pad "1" smd rect
			(at 0 -2.3495 270)
			(size 2.794 1.143)
			(layers "F.Cu" "F.Mask" "F.Paste")
			(net "12V_PRE_0")
		)
		(pad "2" smd rect
			(at 0 2.3495 270)
			(size 2.794 1.143)
			(layers "F.Cu" "F.Mask" "F.Paste")
			(net "P12V_HDD0")
		)
	)
	(footprint ""
		(layer "F.Cu")
		(at 193.548 -384.81)
		(property "Reference" "C117"
			(at 0 0 0)
			(layer "F.SilkS")
			(hide yes)
			(effects
				(font
					(size 1.27 1.27)
				)
			)
		)
		(property "Value" "SCD1U10V2KX-5GP"
			(at 1.1811 -2.7051 0)
			(unlocked yes)
			(layer "F.Fab")
			(hide yes)
			(effects
				(font
					(size 1.016 1.016)
					(thickness 0.1524)
				)
			)
		)
		(property "Device Type" "C402H22"
			(at 1.1811 -4.2291 0)
			(unlocked yes)
			(layer "F.Fab")
			(hide yes)
			(effects
				(font
					(size 1.016 1.016)
					(thickness 0.1524)
				)
			)
		)
		(duplicate_pad_numbers_are_jumpers no)
		(fp_rect
			(start -0.4318 0.9525)
			(end 0.4318 -0.9525)
			(stroke
				(width 0)
				(type default)
			)
			(fill no)
			(layer "F.CrtYd")
		)
		(fp_rect
			(start -0.4318 0.9525)
			(end 0.4318 -0.9525)
			(stroke
				(width 0)
				(type default)
			)
			(fill no)
			(layer "F.Fab")
		)
		(pad "1" smd custom
			(at 0 -0.4445)
			(size 0.1524 0.1524)
			(layers "F.Cu" "F.Mask" "F.Paste")
			(net "P3V3")
			(options
				(clearance outline)
				(anchor circle)
			)
			(primitives
				(gr_poly
					(pts
						(arc
							(start 0.3048 -0.2032)
							(mid 0.275042 -0.275042)
							(end 0.2032 -0.3048)
						)
						(arc
							(start -0.2032 -0.3048)
							(mid -0.275042 -0.275042)
							(end -0.3048 -0.2032)
						)
						(arc
							(start -0.3048 0.2032)
							(mid -0.275042 0.275042)
							(end -0.2032 0.3048)
						)
						(arc
							(start 0.2032 0.3048)
							(mid 0.275042 0.275042)
							(end 0.3048 0.2032)
						)
					)
					(width 0)
					(fill yes)
				)
			)
		)
		(pad "2" smd custom
			(at 0 0.4445)
			(size 0.1524 0.1524)
			(layers "F.Cu" "F.Mask" "F.Paste")
			(net "GND")
			(options
				(clearance outline)
				(anchor circle)
			)
			(primitives
				(gr_poly
					(pts
						(arc
							(start 0.3048 -0.2032)
							(mid 0.275042 -0.275042)
							(end 0.2032 -0.3048)
						)
						(arc
							(start -0.2032 -0.3048)
							(mid -0.275042 -0.275042)
							(end -0.3048 -0.2032)
						)
						(arc
							(start -0.3048 0.2032)
							(mid -0.275042 0.275042)
							(end -0.2032 0.3048)
						)
						(arc
							(start 0.2032 0.3048)
							(mid 0.275042 0.275042)
							(end 0.3048 0.2032)
						)
					)
					(width 0)
					(fill yes)
				)
			)
		)
	)
	(footprint ""
		(layer "F.Cu")
		(at 83.058 -399.415 180)
		(property "Reference" "C370"
			(at 0 0 180)
			(layer "F.SilkS")
			(hide yes)
			(effects
				(font
					(size 1.27 1.27)
				)
			)
		)
		(property "Value" "SCD033U25V2KX-GP"
			(at 1.1811 -2.7051 180)
			(unlocked yes)
			(layer "F.Fab")
			(hide yes)
			(effects
				(font
					(size 1.016 1.016)
					(thickness 0.1524)
				)
			)
		)
		(property "Device Type" "C402H22"
			(at 1.1811 -4.2291 180)
			(unlocked yes)
			(layer "F.Fab")
			(hide yes)
			(effects
				(font
					(size 1.016 1.016)
					(thickness 0.1524)
				)
			)
		)
		(duplicate_pad_numbers_are_jumpers no)
		(fp_rect
			(start -0.4318 0.9525)
			(end 0.4318 -0.9525)
			(stroke
				(width 0)
				(type default)
			)
			(fill no)
			(layer "F.CrtYd")
		)
		(fp_rect
			(start -0.4318 0.9525)
			(end 0.4318 -0.9525)
			(stroke
				(width 0)
				(type default)
			)
			(fill no)
			(layer "F.Fab")
		)
		(pad "1" smd custom
			(at 0 -0.4445 180)
			(size 0.1524 0.1524)
			(layers "F.Cu" "F.Mask" "F.Paste")
			(net "SW_HDD6_P")
			(options
				(clearance outline)
				(anchor circle)
			)
			(primitives
				(gr_poly
					(pts
						(arc
							(start 0.3048 -0.2032)
							(mid 0.275042 -0.275042)
							(end 0.2032 -0.3048)
						)
						(arc
							(start -0.2032 -0.3048)
							(mid -0.275042 -0.275042)
							(end -0.3048 -0.2032)
						)
						(arc
							(start -0.3048 0.2032)
							(mid -0.275042 0.275042)
							(end -0.2032 0.3048)
						)
						(arc
							(start 0.2032 0.3048)
							(mid 0.275042 0.275042)
							(end 0.3048 0.2032)
						)
					)
					(width 0)
					(fill yes)
				)
			)
		)
		(pad "2" smd custom
			(at 0 0.4445 180)
			(size 0.1524 0.1524)
			(layers "F.Cu" "F.Mask" "F.Paste")
			(net "GND")
			(options
				(clearance outline)
				(anchor circle)
			)
			(primitives
				(gr_poly
					(pts
						(arc
							(start 0.3048 -0.2032)
							(mid 0.275042 -0.275042)
							(end 0.2032 -0.3048)
						)
						(arc
							(start -0.2032 -0.3048)
							(mid -0.275042 -0.275042)
							(end -0.3048 -0.2032)
						)
						(arc
							(start -0.3048 0.2032)
							(mid -0.275042 0.275042)
							(end -0.2032 0.3048)
						)
						(arc
							(start 0.2032 0.3048)
							(mid 0.275042 0.275042)
							(end 0.3048 0.2032)
						)
					)
					(width 0)
					(fill yes)
				)
			)
		)
	)
	(footprint ""
		(layer "F.Cu")
		(at 213.063582 -291.310568 180)
		(property "Reference" "C143"
			(at 0 0 180)
			(layer "F.SilkS")
			(hide yes)
			(effects
				(font
					(size 1.27 1.27)
				)
			)
		)
		(property "Value" "SC10U25V6KX-1GP"
			(at -0.0762 -5.1308 180)
			(unlocked yes)
			(layer "F.Fab")
			(hide yes)
			(effects
				(font
					(size 1.016 1.016)
					(thickness 0.1524)
				)
			)
		)
		(property "Device Type" "C1206H71"
			(at -0.127 -6.6548 180)
			(unlocked yes)
			(layer "F.Fab")
			(hide yes)
			(effects
				(font
					(size 1.016 1.016)
					(thickness 0.1524)
				)
			)
		)
		(duplicate_pad_numbers_are_jumpers no)
		(fp_line
			(start 1.016 2.2352)
			(end -1.016 2.2352)
			(stroke
				(width 0.1524)
				(type default)
			)
			(layer "F.SilkS")
		)
		(fp_line
			(start 1.016 0.8382)
			(end 1.016 2.2352)
			(stroke
				(width 0.1524)
				(type default)
			)
			(layer "F.SilkS")
		)
		(fp_line
			(start 1.016 -2.2352)
			(end 1.016 -0.8382)
			(stroke
				(width 0.1524)
				(type default)
			)
			(layer "F.SilkS")
		)
		(fp_line
			(start -1.016 2.2352)
			(end -1.016 0.8382)
			(stroke
				(width 0.1524)
				(type default)
			)
			(layer "F.SilkS")
		)
		(fp_line
			(start -1.016 -0.8382)
			(end -1.016 -2.2352)
			(stroke
				(width 0.1524)
				(type default)
			)
			(layer "F.SilkS")
		)
		(fp_line
			(start -1.016 -2.2352)
			(end 1.016 -2.2352)
			(stroke
				(width 0.1524)
				(type default)
			)
			(layer "F.SilkS")
		)
		(fp_rect
			(start -1.0922 2.3114)
			(end 1.0922 -2.3114)
			(stroke
				(width 0)
				(type default)
			)
			(fill no)
			(layer "F.CrtYd")
		)
		(fp_poly
			(pts
				(xy 1.0922 -2.3114) (xy 1.0922 2.3114) (xy -1.0922 2.3114) (xy -1.0922 -2.3114)
			)
			(stroke
				(width 0)
				(type default)
			)
			(fill no)
			(layer "F.Fab")
		)
		(pad "1" smd rect
			(at 0 -1.397 180)
			(size 1.651 1.27)
			(layers "F.Cu" "F.Mask" "F.Paste")
			(net "P12V_HDD2")
		)
		(pad "2" smd rect
			(at 0 1.397 180)
			(size 1.651 1.27)
			(layers "F.Cu" "F.Mask" "F.Paste")
			(net "GND")
		)
	)
	(footprint ""
		(layer "F.Cu")
		(at 17.500092 -361.840018)
		(property "Reference" "LED12"
			(at 0 0 0)
			(layer "F.SilkS")
			(hide yes)
			(effects
				(font
					(size 1.27 1.27)
				)
			)
		)
		(property "Value" "LED-RB-4-GP"
			(at 5.88899 1.80848 0)
			(unlocked yes)
			(layer "F.Fab")
			(hide yes)
			(effects
				(font
					(size 1.016 1.016)
					(thickness 0.1524)
				)
			)
		)
		(property "Device Type" "LED1613-4PH20"
			(at 5.88899 0.28448 0)
			(unlocked yes)
			(layer "F.Fab")
			(hide yes)
			(effects
				(font
					(size 1.016 1.016)
					(thickness 0.1524)
				)
			)
		)
		(duplicate_pad_numbers_are_jumpers no)
		(fp_line
			(start -1.4478 -0.9652)
			(end 1.4478 -0.9652)
			(stroke
				(width 0.1524)
				(type default)
			)
			(layer "F.SilkS")
		)
		(fp_line
			(start -1.4478 0.9652)
			(end -1.4478 -0.9652)
			(stroke
				(width 0.1524)
				(type default)
			)
			(layer "F.SilkS")
		)
		(fp_line
			(start -1.4478 0.9652)
			(end -1.4478 -0.9652)
			(stroke
				(width 0.508)
				(type default)
			)
			(layer "F.SilkS")
		)
		(fp_line
			(start 1.4478 -0.9652)
			(end 1.4478 0.9652)
			(stroke
				(width 0.1524)
				(type default)
			)
			(layer "F.SilkS")
		)
		(fp_line
			(start 1.4478 0.9652)
			(end -1.4478 0.9652)
			(stroke
				(width 0.1524)
				(type default)
			)
			(layer "F.SilkS")
		)
		(fp_rect
			(start -0.8001 0.6477)
			(end 0.8001 -0.6477)
			(stroke
				(width 0)
				(type default)
			)
			(fill no)
			(layer "F.CrtYd")
		)
		(fp_poly
			(pts
				(xy -1.7018 1.2192) (xy -1.7018 -0.06223) (xy -0.8001 -0.06223) (xy -0.8001 0.6477) (xy 0.8001 0.6477)
				(xy 0.8001 -0.6477) (xy -0.8001 -0.6477) (xy -0.8001 -0.0635) (xy -1.7018 -0.0635) (xy -1.7018 -1.2192)
				(xy 1.7018 -1.2192) (xy 1.7018 1.2192)
			)
			(stroke
				(width 0)
				(type default)
			)
			(fill no)
			(layer "F.CrtYd")
		)
		(fp_rect
			(start -1.7018 1.2192)
			(end 1.7018 -1.2192)
			(stroke
				(width 0)
				(type default)
			)
			(fill no)
			(layer "F.Fab")
		)
		(pad "1" smd rect
			(at -0.73025 0.4064)
			(size 0.9144 0.6096)
			(layers "F.Cu" "F.Mask" "F.Paste")
			(net "DRV_ACT_NET11")
		)
		(pad "2" smd rect
			(at -0.73025 -0.4064)
			(size 0.9144 0.6096)
			(layers "F.Cu" "F.Mask" "F.Paste")
			(net "FLT_NET_HDD11")
		)
		(pad "3" smd rect
			(at 0.73025 -0.4064)
			(size 0.9144 0.6096)
			(layers "F.Cu" "F.Mask" "F.Paste")
			(net "FLT_HDD11")
		)
		(pad "4" smd rect
			(at 0.73025 0.4064)
			(size 0.9144 0.6096)
			(layers "F.Cu" "F.Mask" "F.Paste")
			(net "DRV_ACT_11")
		)
	)
	(footprint ""
		(layer "F.Cu")
		(at 40.513 -208.28)
		(property "Reference" "C301"
			(at 0 0 0)
			(layer "F.SilkS")
			(hide yes)
			(effects
				(font
					(size 1.27 1.27)
				)
			)
		)
		(property "Value" "SCD1U10V2KX-5GP"
			(at 1.1811 -2.7051 0)
			(unlocked yes)
			(layer "F.Fab")
			(hide yes)
			(effects
				(font
					(size 1.016 1.016)
					(thickness 0.1524)
				)
			)
		)
		(property "Device Type" "C402H22"
			(at 1.1811 -4.2291 0)
			(unlocked yes)
			(layer "F.Fab")
			(hide yes)
			(effects
				(font
					(size 1.016 1.016)
					(thickness 0.1524)
				)
			)
		)
		(duplicate_pad_numbers_are_jumpers no)
		(fp_rect
			(start -0.4318 0.9525)
			(end 0.4318 -0.9525)
			(stroke
				(width 0)
				(type default)
			)
			(fill no)
			(layer "F.CrtYd")
		)
		(fp_rect
			(start -0.4318 0.9525)
			(end 0.4318 -0.9525)
			(stroke
				(width 0)
				(type default)
			)
			(fill no)
			(layer "F.Fab")
		)
		(pad "1" smd custom
			(at 0 -0.4445)
			(size 0.1524 0.1524)
			(layers "F.Cu" "F.Mask" "F.Paste")
			(net "P3V3")
			(options
				(clearance outline)
				(anchor circle)
			)
			(primitives
				(gr_poly
					(pts
						(arc
							(start 0.3048 -0.2032)
							(mid 0.275042 -0.275042)
							(end 0.2032 -0.3048)
						)
						(arc
							(start -0.2032 -0.3048)
							(mid -0.275042 -0.275042)
							(end -0.3048 -0.2032)
						)
						(arc
							(start -0.3048 0.2032)
							(mid -0.275042 0.275042)
							(end -0.2032 0.3048)
						)
						(arc
							(start 0.2032 0.3048)
							(mid 0.275042 0.275042)
							(end 0.3048 0.2032)
						)
					)
					(width 0)
					(fill yes)
				)
			)
		)
		(pad "2" smd custom
			(at 0 0.4445)
			(size 0.1524 0.1524)
			(layers "F.Cu" "F.Mask" "F.Paste")
			(net "GND")
			(options
				(clearance outline)
				(anchor circle)
			)
			(primitives
				(gr_poly
					(pts
						(arc
							(start 0.3048 -0.2032)
							(mid 0.275042 -0.275042)
							(end 0.2032 -0.3048)
						)
						(arc
							(start -0.2032 -0.3048)
							(mid -0.275042 -0.275042)
							(end -0.3048 -0.2032)
						)
						(arc
							(start -0.3048 0.2032)
							(mid -0.275042 0.275042)
							(end -0.2032 0.3048)
						)
						(arc
							(start 0.2032 0.3048)
							(mid 0.275042 0.275042)
							(end 0.3048 0.2032)
						)
					)
					(width 0)
					(fill yes)
				)
			)
		)
	)
	(footprint ""
		(layer "F.Cu")
		(at 217.854784 -167.229028 -90)
		(property "Reference" "C153"
			(at 0 0 270)
			(layer "F.SilkS")
			(hide yes)
			(effects
				(font
					(size 1.27 1.27)
				)
			)
		)
		(property "Value" "SCD01U50V2KX-1GP"
			(at 1.1811 -2.7051 270)
			(unlocked yes)
			(layer "F.Fab")
			(hide yes)
			(effects
				(font
					(size 1.016 1.016)
					(thickness 0.1524)
				)
			)
		)
		(property "Device Type" "C402H22"
			(at 1.1811 -4.2291 270)
			(unlocked yes)
			(layer "F.Fab")
			(hide yes)
			(effects
				(font
					(size 1.016 1.016)
					(thickness 0.1524)
				)
			)
		)
		(duplicate_pad_numbers_are_jumpers no)
		(fp_rect
			(start -0.4318 0.9525)
			(end 0.4318 -0.9525)
			(stroke
				(width 0)
				(type default)
			)
			(fill no)
			(layer "F.CrtYd")
		)
		(fp_rect
			(start -0.4318 0.9525)
			(end 0.4318 -0.9525)
			(stroke
				(width 0)
				(type default)
			)
			(fill no)
			(layer "F.Fab")
		)
		(pad "1" smd custom
			(at 0 -0.4445 270)
			(size 0.1524 0.1524)
			(layers "F.Cu" "F.Mask" "F.Paste")
			(net "SAS2X28_DRIVE_RX_P_B3")
			(options
				(clearance outline)
				(anchor circle)
			)
			(primitives
				(gr_poly
					(pts
						(arc
							(start 0.3048 -0.2032)
							(mid 0.275042 -0.275042)
							(end 0.2032 -0.3048)
						)
						(arc
							(start -0.2032 -0.3048)
							(mid -0.275042 -0.275042)
							(end -0.3048 -0.2032)
						)
						(arc
							(start -0.3048 0.2032)
							(mid -0.275042 0.275042)
							(end -0.2032 0.3048)
						)
						(arc
							(start 0.2032 0.3048)
							(mid 0.275042 0.275042)
							(end 0.3048 0.2032)
						)
					)
					(width 0)
					(fill yes)
				)
			)
		)
		(pad "2" smd custom
			(at 0 0.4445 270)
			(size 0.1524 0.1524)
			(layers "F.Cu" "F.Mask" "F.Paste")
			(net "SAS2X28_B_HDD3_RX_+")
			(options
				(clearance outline)
				(anchor circle)
			)
			(primitives
				(gr_poly
					(pts
						(arc
							(start 0.3048 -0.2032)
							(mid 0.275042 -0.275042)
							(end 0.2032 -0.3048)
						)
						(arc
							(start -0.2032 -0.3048)
							(mid -0.275042 -0.275042)
							(end -0.3048 -0.2032)
						)
						(arc
							(start -0.3048 0.2032)
							(mid -0.275042 0.275042)
							(end -0.2032 0.3048)
						)
						(arc
							(start 0.2032 0.3048)
							(mid 0.275042 0.275042)
							(end 0.3048 0.2032)
						)
					)
					(width 0)
					(fill yes)
				)
			)
		)
	)
	(footprint ""
		(layer "F.Cu")
		(at 28.50007 -379.240034 180)
		(property "Reference" "U46"
			(at 0 0 180)
			(layer "F.SilkS")
			(hide yes)
			(effects
				(font
					(size 1.27 1.27)
				)
			)
		)
		(property "Value" "TMP75AIDGKR-GP"
			(at -0.1143 -9.1948 180)
			(unlocked yes)
			(layer "F.Fab")
			(hide yes)
			(effects
				(font
					(size 1.016 1.016)
					(thickness 0.1524)
				)
			)
		)
		(property "Device Type" "MSOP8-1H44"
			(at -0.1143 -10.795 180)
			(unlocked yes)
			(layer "F.Fab")
			(hide yes)
			(effects
				(font
					(size 1.016 1.016)
					(thickness 0.1524)
				)
			)
		)
		(duplicate_pad_numbers_are_jumpers no)
		(fp_line
			(start 1.0795 1.016)
			(end 1.0795 -1.016)
			(stroke
				(width 0.1524)
				(type default)
			)
			(layer "F.SilkS")
		)
		(fp_line
			(start 1.0795 -1.016)
			(end -1.9558 -1.016)
			(stroke
				(width 0.1524)
				(type default)
			)
			(layer "F.SilkS")
		)
		(fp_line
			(start -1.4478 -0.0381)
			(end -1.9558 0.4699)
			(stroke
				(width 0.1524)
				(type default)
			)
			(layer "F.SilkS")
		)
		(fp_line
			(start -1.778 1.0922)
			(end -1.778 3.048)
			(stroke
				(width 0.508)
				(type default)
			)
			(layer "F.SilkS")
		)
		(fp_line
			(start -1.9558 1.016)
			(end 1.0795 1.016)
			(stroke
				(width 0.1524)
				(type default)
			)
			(layer "F.SilkS")
		)
		(fp_line
			(start -1.9558 -0.5461)
			(end -1.4478 -0.0381)
			(stroke
				(width 0.1524)
				(type default)
			)
			(layer "F.SilkS")
		)
		(fp_line
			(start -1.9558 -1.016)
			(end -1.9558 1.016)
			(stroke
				(width 0.1524)
				(type default)
			)
			(layer "F.SilkS")
		)
		(fp_poly
			(pts
				(xy -1.1557 -1.016) (xy -1.1557 1.016) (xy 1.1557 1.016) (xy 1.1557 -1.016)
			)
			(stroke
				(width 0)
				(type default)
			)
			(fill yes)
			(layer "F.SilkS")
		)
		(fp_rect
			(start -1.4986 2.4511)
			(end 1.4986 -2.4511)
			(stroke
				(width 0)
				(type default)
			)
			(fill no)
			(layer "F.CrtYd")
		)
		(fp_poly
			(pts
				(xy -2.032 3.302) (xy -2.032 -3.302) (xy 2.032 -3.302) (xy 2.032 -2.1209) (xy 1.4986 -2.1209) (xy 1.4986 -2.4511)
				(xy -1.4986 -2.4511) (xy -1.4986 2.4511) (xy 1.4986 2.4511) (xy 1.4986 -2.1082) (xy 2.032 -2.1082)
				(xy 2.032 3.302)
			)
			(stroke
				(width 0)
				(type default)
			)
			(fill no)
			(layer "F.CrtYd")
		)
		(fp_rect
			(start -2.032 3.302)
			(end 2.032 -3.302)
			(stroke
				(width 0)
				(type default)
			)
			(fill no)
			(layer "F.Fab")
		)
		(pad "1" smd rect
			(at -0.97536 2.05486 180)
			(size 0.3556 1.524)
			(layers "F.Cu" "F.Mask" "F.Paste")
			(net "TMP1_SDA")
		)
		(pad "2" smd rect
			(at -0.32512 2.05486 180)
			(size 0.3556 1.524)
			(layers "F.Cu" "F.Mask" "F.Paste")
			(net "TMP1_SCL")
		)
		(pad "3" smd rect
			(at 0.32512 2.05486 180)
			(size 0.3556 1.524)
			(layers "F.Cu" "F.Mask" "F.Paste")
			(net "I2C_B_TMP1_ALERT")
		)
		(pad "4" smd rect
			(at 0.97536 2.05486 180)
			(size 0.3556 1.524)
			(layers "F.Cu" "F.Mask" "F.Paste")
			(net "GND")
		)
		(pad "5" smd rect
			(at 0.97536 -2.05486 180)
			(size 0.3556 1.524)
			(layers "F.Cu" "F.Mask" "F.Paste")
			(net "I2C_B_TMP1_A2")
		)
		(pad "6" smd rect
			(at 0.32512 -2.05486 180)
			(size 0.3556 1.524)
			(layers "F.Cu" "F.Mask" "F.Paste")
			(net "I2C_B_TMP1_A1")
		)
		(pad "7" smd rect
			(at -0.32512 -2.05486 180)
			(size 0.3556 1.524)
			(layers "F.Cu" "F.Mask" "F.Paste")
			(net "I2C_B_TMP1_A0")
		)
		(pad "8" smd rect
			(at -0.97536 -2.05486 180)
			(size 0.3556 1.524)
			(layers "F.Cu" "F.Mask" "F.Paste")
			(net "P3V3")
		)
	)
	(footprint ""
		(layer "F.Cu")
		(at 215.263984 -188.488828 180)
		(property "Reference" "C161"
			(at 0 0 180)
			(layer "F.SilkS")
			(hide yes)
			(effects
				(font
					(size 1.27 1.27)
				)
			)
		)
		(property "Value" "SC10U25V6KX-1GP"
			(at -0.0762 -5.1308 180)
			(unlocked yes)
			(layer "F.Fab")
			(hide yes)
			(effects
				(font
					(size 1.016 1.016)
					(thickness 0.1524)
				)
			)
		)
		(property "Device Type" "C1206H71"
			(at -0.127 -6.6548 180)
			(unlocked yes)
			(layer "F.Fab")
			(hide yes)
			(effects
				(font
					(size 1.016 1.016)
					(thickness 0.1524)
				)
			)
		)
		(duplicate_pad_numbers_are_jumpers no)
		(fp_line
			(start 1.016 2.2352)
			(end -1.016 2.2352)
			(stroke
				(width 0.1524)
				(type default)
			)
			(layer "F.SilkS")
		)
		(fp_line
			(start 1.016 0.8382)
			(end 1.016 2.2352)
			(stroke
				(width 0.1524)
				(type default)
			)
			(layer "F.SilkS")
		)
		(fp_line
			(start 1.016 -2.2352)
			(end 1.016 -0.8382)
			(stroke
				(width 0.1524)
				(type default)
			)
			(layer "F.SilkS")
		)
		(fp_line
			(start -1.016 2.2352)
			(end -1.016 0.8382)
			(stroke
				(width 0.1524)
				(type default)
			)
			(layer "F.SilkS")
		)
		(fp_line
			(start -1.016 -0.8382)
			(end -1.016 -2.2352)
			(stroke
				(width 0.1524)
				(type default)
			)
			(layer "F.SilkS")
		)
		(fp_line
			(start -1.016 -2.2352)
			(end 1.016 -2.2352)
			(stroke
				(width 0.1524)
				(type default)
			)
			(layer "F.SilkS")
		)
		(fp_rect
			(start -1.0922 2.3114)
			(end 1.0922 -2.3114)
			(stroke
				(width 0)
				(type default)
			)
			(fill no)
			(layer "F.CrtYd")
		)
		(fp_poly
			(pts
				(xy 1.0922 -2.3114) (xy 1.0922 2.3114) (xy -1.0922 2.3114) (xy -1.0922 -2.3114)
			)
			(stroke
				(width 0)
				(type default)
			)
			(fill no)
			(layer "F.Fab")
		)
		(pad "1" smd rect
			(at 0 -1.397 180)
			(size 1.651 1.27)
			(layers "F.Cu" "F.Mask" "F.Paste")
			(net "P12V_HDD3")
		)
		(pad "2" smd rect
			(at 0 1.397 180)
			(size 1.651 1.27)
			(layers "F.Cu" "F.Mask" "F.Paste")
			(net "GND")
		)
	)
	(footprint ""
		(layer "F.Cu")
		(at 5.969 -34.036 -90)
		(property "Reference" "PC47"
			(at 0 0 270)
			(layer "F.SilkS")
			(hide yes)
			(effects
				(font
					(size 1.27 1.27)
				)
			)
		)
		(property "Value" "SC22U25V5MX-GP"
			(at -0.0762 -6.1214 270)
			(unlocked yes)
			(layer "F.Fab")
			(hide yes)
			(effects
				(font
					(size 1.016 1.016)
					(thickness 0.1524)
				)
			)
		)
		(property "Device Type" "C805H58"
			(at -0.0762 -8.1534 270)
			(unlocked yes)
			(layer "F.Fab")
			(hide yes)
			(effects
				(font
					(size 1.016 1.016)
					(thickness 0.1524)
				)
			)
		)
		(duplicate_pad_numbers_are_jumpers no)
		(fp_line
			(start 0.635 0)
			(end -0.635 0)
			(stroke
				(width 0.508)
				(type default)
			)
			(layer "F.SilkS")
		)
		(fp_rect
			(start -0.9652 1.778)
			(end 0.9652 -1.778)
			(stroke
				(width 0)
				(type default)
			)
			(fill no)
			(layer "F.CrtYd")
		)
		(fp_poly
			(pts
				(xy -0.9652 -1.778) (xy 0.9652 -1.778) (xy 0.9652 1.778) (xy -0.9652 1.778)
			)
			(stroke
				(width 0)
				(type default)
			)
			(fill no)
			(layer "F.Fab")
		)
		(pad "1" smd rect
			(at 0 -0.9652 270)
			(size 1.397 1.143)
			(layers "F.Cu" "F.Mask" "F.Paste")
			(net "P12V")
		)
		(pad "2" smd rect
			(at 0 0.9652 270)
			(size 1.397 1.143)
			(layers "F.Cu" "F.Mask" "F.Paste")
			(net "GND")
		)
	)
	(footprint ""
		(layer "F.Cu")
		(at 93.8022 -18.8214 180)
		(property "Reference" "C324"
			(at 0 0 180)
			(layer "F.SilkS")
			(hide yes)
			(effects
				(font
					(size 1.27 1.27)
				)
			)
		)
		(property "Value" "SCD1U10V2KX-5GP"
			(at 1.1811 -2.7051 180)
			(unlocked yes)
			(layer "F.Fab")
			(hide yes)
			(effects
				(font
					(size 1.016 1.016)
					(thickness 0.1524)
				)
			)
		)
		(property "Device Type" "C402H22"
			(at 1.1811 -4.2291 180)
			(unlocked yes)
			(layer "F.Fab")
			(hide yes)
			(effects
				(font
					(size 1.016 1.016)
					(thickness 0.1524)
				)
			)
		)
		(duplicate_pad_numbers_are_jumpers no)
		(fp_rect
			(start -0.4318 0.9525)
			(end 0.4318 -0.9525)
			(stroke
				(width 0)
				(type default)
			)
			(fill no)
			(layer "F.CrtYd")
		)
		(fp_rect
			(start -0.4318 0.9525)
			(end 0.4318 -0.9525)
			(stroke
				(width 0)
				(type default)
			)
			(fill no)
			(layer "F.Fab")
		)
		(pad "1" smd custom
			(at 0 -0.4445 180)
			(size 0.1524 0.1524)
			(layers "F.Cu" "F.Mask" "F.Paste")
			(net "P3V3")
			(options
				(clearance outline)
				(anchor circle)
			)
			(primitives
				(gr_poly
					(pts
						(arc
							(start 0.3048 -0.2032)
							(mid 0.275042 -0.275042)
							(end 0.2032 -0.3048)
						)
						(arc
							(start -0.2032 -0.3048)
							(mid -0.275042 -0.275042)
							(end -0.3048 -0.2032)
						)
						(arc
							(start -0.3048 0.2032)
							(mid -0.275042 0.275042)
							(end -0.2032 0.3048)
						)
						(arc
							(start 0.2032 0.3048)
							(mid 0.275042 0.275042)
							(end 0.3048 0.2032)
						)
					)
					(width 0)
					(fill yes)
				)
			)
		)
		(pad "2" smd custom
			(at 0 0.4445 180)
			(size 0.1524 0.1524)
			(layers "F.Cu" "F.Mask" "F.Paste")
			(net "GND")
			(options
				(clearance outline)
				(anchor circle)
			)
			(primitives
				(gr_poly
					(pts
						(arc
							(start 0.3048 -0.2032)
							(mid 0.275042 -0.275042)
							(end 0.2032 -0.3048)
						)
						(arc
							(start -0.2032 -0.3048)
							(mid -0.275042 -0.275042)
							(end -0.3048 -0.2032)
						)
						(arc
							(start -0.3048 0.2032)
							(mid -0.275042 0.275042)
							(end -0.2032 0.3048)
						)
						(arc
							(start 0.2032 0.3048)
							(mid 0.275042 0.275042)
							(end 0.3048 0.2032)
						)
					)
					(width 0)
					(fill yes)
				)
			)
		)
	)
	(footprint ""
		(layer "F.Cu")
		(at 2.500122 -460.004668 -90)
		(property "Reference" "CN5"
			(at 0 0 270)
			(layer "F.SilkS")
			(hide yes)
			(effects
				(font
					(size 1.27 1.27)
				)
			)
		)
		(property "Value" "PCISLT36-27-GP"
			(at 5.281422 -7.491476 270)
			(unlocked yes)
			(layer "F.Fab")
			(hide yes)
			(effects
				(font
					(size 1.016 1.016)
					(thickness 0.1524)
				)
			)
		)
		(property "Device Type" "G630H3612248EU"
			(at 5.281422 -9.015476 270)
			(unlocked yes)
			(layer "F.Fab")
			(hide yes)
			(effects
				(font
					(size 1.016 1.016)
					(thickness 0.1524)
				)
			)
		)
		(duplicate_pad_numbers_are_jumpers no)
		(fp_line
			(start -14.899894 2.499868)
			(end -1.450086 2.499868)
			(stroke
				(width 0.1524)
				(type default)
			)
			(layer "F.SilkS")
		)
		(fp_line
			(start -1.450086 2.499868)
			(end -0.94996 1.999742)
			(stroke
				(width 0.1524)
				(type default)
			)
			(layer "F.SilkS")
		)
		(fp_line
			(start 1.450086 2.499868)
			(end 18.899886 2.499868)
			(stroke
				(width 0.1524)
				(type default)
			)
			(layer "F.SilkS")
		)
		(fp_line
			(start 18.899886 2.499868)
			(end 19.400012 1.999742)
			(stroke
				(width 0.1524)
				(type default)
			)
			(layer "F.SilkS")
		)
		(fp_line
			(start -15.40002 1.999742)
			(end -14.899894 2.499868)
			(stroke
				(width 0.1524)
				(type default)
			)
			(layer "F.SilkS")
		)
		(fp_line
			(start -0.94996 1.999742)
			(end -0.94996 -2.55016)
			(stroke
				(width 0.1524)
				(type default)
			)
			(layer "F.SilkS")
		)
		(fp_line
			(start 0.94996 1.999742)
			(end 1.450086 2.499868)
			(stroke
				(width 0.1524)
				(type default)
			)
			(layer "F.SilkS")
		)
		(fp_line
			(start 19.400012 1.999742)
			(end 19.400012 -4.064)
			(stroke
				(width 0.1524)
				(type default)
			)
			(layer "F.SilkS")
		)
		(fp_line
			(start 0.94996 -2.539746)
			(end 0.94996 1.999742)
			(stroke
				(width 0.1524)
				(type default)
			)
			(layer "F.SilkS")
		)
		(fp_line
			(start 0.94996 -2.55016)
			(end 0.94996 -2.539746)
			(stroke
				(width 0.1524)
				(type default)
			)
			(layer "F.SilkS")
		)
		(fp_line
			(start -15.40002 -4.064)
			(end -15.40002 1.999742)
			(stroke
				(width 0.1524)
				(type default)
			)
			(layer "F.SilkS")
		)
		(fp_line
			(start 19.400012 -4.064)
			(end -15.40002 -4.064)
			(stroke
				(width 0.1524)
				(type default)
			)
			(layer "F.SilkS")
		)
		(fp_line
			(start 11.6713 -4.1529)
			(end 11.2903 -4.1529)
			(stroke
				(width 0.3302)
				(type default)
			)
			(layer "F.SilkS")
		)
		(fp_arc
			(start -0.94996 -2.55016)
			(mid 0 -3.50012)
			(end 0.94996 -2.55016)
			(stroke
				(width 0.1524)
				(type default)
			)
			(layer "F.SilkS")
		)
		(fp_poly
			(pts
				(xy 11.474704 -4.1402) (xy 10.966704 -4.6482) (xy 11.982704 -4.6482)
			)
			(stroke
				(width 0)
				(type default)
			)
			(fill yes)
			(layer "F.SilkS")
		)
		(fp_poly
			(pts
				(xy -10.4902 14.986) (xy -10.4902 4.8006) (xy -15.3924 4.8006) (xy -15.3924 -3.81) (xy 19.4056 -3.81)
				(xy 19.4056 4.8006) (xy 14.5034 4.8006) (xy 14.5034 14.986)
			)
			(stroke
				(width 0)
				(type default)
			)
			(fill no)
			(layer "B.CrtYd")
		)
		(fp_poly
			(pts
				(xy -10.9982 15.494) (xy -10.9982 5.3086) (xy -15.9004 5.3086) (xy -15.9004 -4.318) (xy 19.9136 -4.318)
				(xy 19.9136 5.3086) (xy 15.0114 5.3086) (xy 15.0114 15.494) (xy 0.00254 15.494) (xy 0.00254 14.986)
				(xy 14.5034 14.986) (xy 14.5034 4.8006) (xy 19.4056 4.8006) (xy 19.4056 -3.81) (xy -15.3924 -3.81)
				(xy -15.3924 4.8006) (xy -10.4902 4.8006) (xy -10.4902 14.986) (xy -0.00254 14.986) (xy -0.00254 15.494)
			)
			(stroke
				(width 0)
				(type default)
			)
			(fill no)
			(layer "B.CrtYd")
		)
		(fp_poly
			(pts
				(xy -10.4902 14.986) (xy -10.4902 4.8006) (xy -15.3924 4.8006) (xy -15.3924 -3.81) (xy 19.4056 -3.81)
				(xy 19.4056 4.8006) (xy 14.5034 4.8006) (xy 14.5034 14.986)
			)
			(stroke
				(width 0)
				(type default)
			)
			(fill no)
			(layer "F.CrtYd")
		)
		(fp_poly
			(pts
				(xy -10.9982 15.494) (xy -10.9982 5.3086) (xy -15.9004 5.3086) (xy -15.9004 -4.318) (xy 19.9136 -4.318)
				(xy 19.9136 5.3086) (xy 15.0114 5.3086) (xy 15.0114 15.494) (xy 0.00254 15.494) (xy 0.00254 14.986)
				(xy 14.5034 14.986) (xy 14.5034 4.8006) (xy 19.4056 4.8006) (xy 19.4056 -3.81) (xy -15.3924 -3.81)
				(xy -15.3924 4.8006) (xy -10.4902 4.8006) (xy -10.4902 14.986) (xy -0.00254 14.986) (xy -0.00254 15.494)
			)
			(stroke
				(width 0)
				(type default)
			)
			(fill no)
			(layer "F.CrtYd")
		)
		(fp_poly
			(pts
				(xy -10.9982 15.494) (xy -10.9982 5.3086) (xy -15.9004 5.3086) (xy -15.9004 -4.318) (xy 19.9136 -4.318)
				(xy 19.9136 5.3086) (xy 15.0114 5.3086) (xy 15.0114 15.494)
			)
			(stroke
				(width 0)
				(type default)
			)
			(fill no)
			(layer "B.Fab")
		)
		(fp_poly
			(pts
				(xy -10.9982 15.494) (xy -10.9982 5.3086) (xy -15.9004 5.3086) (xy -15.9004 -4.318) (xy 19.9136 -4.318)
				(xy 19.9136 5.3086) (xy 15.0114 5.3086) (xy 15.0114 15.494)
			)
			(stroke
				(width 0)
				(type default)
			)
			(fill no)
			(layer "F.Fab")
		)
		(fp_text user "Slit"
			(at 1.9304 5.260086 270)
			(unlocked yes)
			(layer "F.SilkS")
			(effects
				(font
					(size 0.635 0.635)
					(thickness 0.1524)
				)
				(justify left)
			)
		)
		(pad "" np_thru_hole circle
			(at -12.300204 0 270)
			(size 0.254 0.254)
			(drill 2.3114)
			(layers "*.Cu" "*.Mask")
			(clearance 1.3843)
			(thermal_gap 1.3843)
		)
		(pad "" np_thru_hole circle
			(at 16.299942 0 270)
			(size 0.254 0.254)
			(drill 2.3114)
			(layers "*.Cu" "*.Mask")
			(clearance 1.3843)
			(thermal_gap 1.3843)
		)
		(pad "A1" smd rect
			(at 11.500104 -0.309118 270)
			(size 0.7112 3.6068)
			(drill
				(offset 0 -0.381)
			)
			(layers "F.Cu" "F.Mask" "F.Paste")
			(net "HDD_PRSNT11")
		)
		(pad "A2" smd rect
			(at 10.500106 -0.309118 270)
			(size 0.7112 3.6068)
			(drill
				(offset 0 -0.381)
			)
			(layers "F.Cu" "F.Mask" "F.Paste")
			(net "HDD_PRSNT12")
		)
		(pad "A3" smd rect
			(at 9.500108 -0.309118 270)
			(size 0.7112 3.6068)
			(drill
				(offset 0 -0.381)
			)
			(layers "F.Cu" "F.Mask" "F.Paste")
			(net "HDD_PRSNT13")
		)
		(pad "A4" smd rect
			(at 8.50011 -0.309118 270)
			(size 0.7112 3.6068)
			(drill
				(offset 0 -0.381)
			)
			(layers "F.Cu" "F.Mask" "F.Paste")
			(net "HDD_PRSNT14")
		)
		(pad "A5" smd rect
			(at 7.500112 -0.309118 270)
			(size 0.7112 3.6068)
			(drill
				(offset 0 -0.381)
			)
			(layers "F.Cu" "F.Mask" "F.Paste")
			(net "HDD_PRSNT9")
		)
		(pad "A6" smd rect
			(at 6.500114 -0.309118 270)
			(size 0.7112 3.6068)
			(drill
				(offset 0 -0.381)
			)
			(layers "F.Cu" "F.Mask" "F.Paste")
			(net "HDD_PRSNT8")
		)
		(pad "A7" smd rect
			(at 5.500116 -0.309118 270)
			(size 0.7112 3.6068)
			(drill
				(offset 0 -0.381)
			)
			(layers "F.Cu" "F.Mask" "F.Paste")
			(net "HDD_PRSNT7")
		)
		(pad "A8" smd rect
			(at 4.500118 -0.309118 270)
			(size 0.7112 3.6068)
			(drill
				(offset 0 -0.381)
			)
			(layers "F.Cu" "F.Mask" "F.Paste")
			(net "HDD_PRSNT4")
		)
		(pad "A9" smd rect
			(at 3.50012 -0.309118 270)
			(size 0.7112 3.6068)
			(drill
				(offset 0 -0.381)
			)
			(layers "F.Cu" "F.Mask" "F.Paste")
			(net "HDD_PRSNT3")
		)
		(pad "A10" smd rect
			(at 2.500122 -0.309118 270)
			(size 0.7112 3.6068)
			(drill
				(offset 0 -0.381)
			)
			(layers "F.Cu" "F.Mask" "F.Paste")
			(net "HDD_PRSNT6")
		)
		(pad "A11" smd rect
			(at 1.500124 -0.309118 270)
			(size 0.7112 3.6068)
			(drill
				(offset 0 -0.381)
			)
			(layers "F.Cu" "F.Mask" "F.Paste")
			(net "HDD_PRSNT2")
		)
		(pad "A12" smd rect
			(at -1.500124 -0.309118 270)
			(size 0.7112 3.6068)
			(drill
				(offset 0 -0.381)
			)
			(layers "F.Cu" "F.Mask" "F.Paste")
			(net "HDD_PRSNT1")
		)
		(pad "A13" smd rect
			(at -2.500122 -0.309118 270)
			(size 0.7112 3.6068)
			(drill
				(offset 0 -0.381)
			)
			(layers "F.Cu" "F.Mask" "F.Paste")
			(net "HDD_PRSNT10")
		)
		(pad "A14" smd rect
			(at -3.50012 -0.309118 270)
			(size 0.7112 3.6068)
			(drill
				(offset 0 -0.381)
			)
			(layers "F.Cu" "F.Mask" "F.Paste")
			(net "HDD_PRSNT0")
		)
		(pad "A15" smd rect
			(at -4.500118 -0.309118 270)
			(size 0.7112 3.6068)
			(drill
				(offset 0 -0.381)
			)
			(layers "F.Cu" "F.Mask" "F.Paste")
			(net "HDD_PRSNT5")
		)
		(pad "A16" smd rect
			(at -5.500116 -0.309118 270)
			(size 0.7112 3.6068)
			(drill
				(offset 0 -0.381)
			)
			(layers "F.Cu" "F.Mask" "F.Paste")
			(net "SELF_TRAY_PRESENT")
		)
		(pad "A17" smd rect
			(at -6.500114 -0.309118 270)
			(size 0.7112 3.6068)
			(drill
				(offset 0 -0.381)
			)
			(layers "F.Cu" "F.Mask" "F.Paste")
			(net "PEER_TRAY_PRESENT")
		)
		(pad "A18" smd rect
			(at -7.500112 -0.309118 270)
			(size 0.7112 3.6068)
			(drill
				(offset 0 -0.381)
			)
			(layers "F.Cu" "F.Mask" "F.Paste")
			(net "EXP_A_PRNST_TX")
		)
		(pad "B1" smd rect
			(at 11.500104 -0.690118 270)
			(size 0.7112 3.6068)
			(layers "F.Cu" "F.Mask" "F.Paste")
			(net "SAS_EXP_A_PWR11")
		)
		(pad "B2" smd rect
			(at 10.500106 -0.690118 270)
			(size 0.7112 3.6068)
			(layers "F.Cu" "F.Mask" "F.Paste")
			(net "SAS_EXP_A_PWR12")
		)
		(pad "B3" smd rect
			(at 9.500108 -0.690118 270)
			(size 0.7112 3.6068)
			(layers "F.Cu" "F.Mask" "F.Paste")
			(net "SAS_EXP_A_PWR13")
		)
		(pad "B4" smd rect
			(at 8.50011 -0.690118 270)
			(size 0.7112 3.6068)
			(layers "F.Cu" "F.Mask" "F.Paste")
			(net "SAS_EXP_A_PWR14")
		)
		(pad "B5" smd rect
			(at 7.500112 -0.690118 270)
			(size 0.7112 3.6068)
			(layers "F.Cu" "F.Mask" "F.Paste")
			(net "SAS_EXP_A_PWR9")
		)
		(pad "B6" smd rect
			(at 6.500114 -0.690118 270)
			(size 0.7112 3.6068)
			(layers "F.Cu" "F.Mask" "F.Paste")
			(net "SAS_EXP_A_PWR8")
		)
		(pad "B7" smd rect
			(at 5.500116 -0.690118 270)
			(size 0.7112 3.6068)
			(layers "F.Cu" "F.Mask" "F.Paste")
			(net "SAS_EXP_A_PWR7")
		)
		(pad "B8" smd rect
			(at 4.500118 -0.690118 270)
			(size 0.7112 3.6068)
			(layers "F.Cu" "F.Mask" "F.Paste")
			(net "SAS_EXP_A_PWR4")
		)
		(pad "B9" smd rect
			(at 3.50012 -0.690118 270)
			(size 0.7112 3.6068)
			(layers "F.Cu" "F.Mask" "F.Paste")
			(net "SAS_EXP_A_PWR3")
		)
		(pad "B10" smd rect
			(at 2.500122 -0.690118 270)
			(size 0.7112 3.6068)
			(layers "F.Cu" "F.Mask" "F.Paste")
			(net "SAS_EXP_A_PWR6")
		)
		(pad "B11" smd rect
			(at 1.500124 -0.690118 270)
			(size 0.7112 3.6068)
			(layers "F.Cu" "F.Mask" "F.Paste")
			(net "SAS_EXP_A_PWR2")
		)
		(pad "B12" smd rect
			(at -1.500124 -0.690118 270)
			(size 0.7112 3.6068)
			(layers "F.Cu" "F.Mask" "F.Paste")
			(net "SAS_EXP_A_PWR1")
		)
		(pad "B13" smd rect
			(at -2.500122 -0.690118 270)
			(size 0.7112 3.6068)
			(layers "F.Cu" "F.Mask" "F.Paste")
			(net "SAS_EXP_A_PWR10")
		)
		(pad "B14" smd rect
			(at -3.50012 -0.690118 270)
			(size 0.7112 3.6068)
			(layers "F.Cu" "F.Mask" "F.Paste")
			(net "SAS_EXP_A_PWR0")
		)
		(pad "B15" smd rect
			(at -4.500118 -0.690118 270)
			(size 0.7112 3.6068)
			(layers "F.Cu" "F.Mask" "F.Paste")
			(net "SAS_EXP_A_PWR5")
		)
		(pad "B16" smd rect
			(at -5.500116 -0.690118 270)
			(size 0.7112 3.6068)
			(layers "F.Cu" "F.Mask" "F.Paste")
			(net "SAS_EXP_A_PWR15")
		)
		(pad "B17" smd rect
			(at -6.500114 -0.690118 270)
			(size 0.7112 3.6068)
			(layers "F.Cu" "F.Mask" "F.Paste")
			(net "PCIE_MATED#_A")
		)
		(pad "B18" smd rect
			(at -7.500112 -0.690118 270)
			(size 0.7112 3.6068)
			(layers "F.Cu" "F.Mask" "F.Paste")
			(net "EXP_B_PRNST_RX")
		)
		(zone
			(layers "F.Cu" "B.Cu" "In1.Cu" "In2.Cu" "In3.Cu" "In4.Cu" "In5.Cu" "In6.Cu")
			(hatch none 0.5)
			(connect_pads
				(clearance 0)
			)
			(min_thickness 0.25)
			(keepout
				(tracks not_allowed)
				(vias allowed)
				(pads allowed)
				(copperpour not_allowed)
				(footprints allowed)
			)
			(placement
				(enabled no)
				(sheetname "")
			)
			(fill
				(thermal_gap 0.5)
				(thermal_bridge_width 0.5)
				(island_removal_mode 0)
			)
			(polygon
				(pts
					(arc
						(start 3.960622 -472.304872)
						(mid 1.039622 -472.304872)
						(end 3.960622 -472.304872)
					)
				)
			)
		)
		(zone
			(layers "F.Cu" "B.Cu" "In1.Cu" "In2.Cu" "In3.Cu" "In4.Cu" "In5.Cu" "In6.Cu")
			(hatch none 0.5)
			(connect_pads
				(clearance 0)
			)
			(min_thickness 0.25)
			(keepout
				(tracks not_allowed)
				(vias allowed)
				(pads allowed)
				(copperpour not_allowed)
				(footprints allowed)
			)
			(placement
				(enabled no)
				(sheetname "")
			)
			(fill
				(thermal_gap 0.5)
				(thermal_bridge_width 0.5)
				(island_removal_mode 0)
			)
			(polygon
				(pts
					(arc
						(start 3.960622 -443.704726)
						(mid 1.039622 -443.704726)
						(end 3.960622 -443.704726)
					)
				)
			)
		)
	)
	(footprint ""
		(layer "F.Cu")
		(at 28.320746 -314.734702)
		(property "Reference" "C290"
			(at 0 0 0)
			(layer "F.SilkS")
			(hide yes)
			(effects
				(font
					(size 1.27 1.27)
				)
			)
		)
		(property "Value" "SC10U25V6KX-1GP"
			(at -0.0762 -5.1308 0)
			(unlocked yes)
			(layer "F.Fab")
			(hide yes)
			(effects
				(font
					(size 1.016 1.016)
					(thickness 0.1524)
				)
			)
		)
		(property "Device Type" "C1206H71"
			(at -0.127 -6.6548 0)
			(unlocked yes)
			(layer "F.Fab")
			(hide yes)
			(effects
				(font
					(size 1.016 1.016)
					(thickness 0.1524)
				)
			)
		)
		(duplicate_pad_numbers_are_jumpers no)
		(fp_line
			(start -1.016 -2.2352)
			(end 1.016 -2.2352)
			(stroke
				(width 0.1524)
				(type default)
			)
			(layer "F.SilkS")
		)
		(fp_line
			(start -1.016 -0.8382)
			(end -1.016 -2.2352)
			(stroke
				(width 0.1524)
				(type default)
			)
			(layer "F.SilkS")
		)
		(fp_line
			(start -1.016 2.2352)
			(end -1.016 0.8382)
			(stroke
				(width 0.1524)
				(type default)
			)
			(layer "F.SilkS")
		)
		(fp_line
			(start 1.016 -2.2352)
			(end 1.016 -0.8382)
			(stroke
				(width 0.1524)
				(type default)
			)
			(layer "F.SilkS")
		)
		(fp_line
			(start 1.016 0.8382)
			(end 1.016 2.2352)
			(stroke
				(width 0.1524)
				(type default)
			)
			(layer "F.SilkS")
		)
		(fp_line
			(start 1.016 2.2352)
			(end -1.016 2.2352)
			(stroke
				(width 0.1524)
				(type default)
			)
			(layer "F.SilkS")
		)
		(fp_rect
			(start -1.0922 2.3114)
			(end 1.0922 -2.3114)
			(stroke
				(width 0)
				(type default)
			)
			(fill no)
			(layer "F.CrtYd")
		)
		(fp_poly
			(pts
				(xy 1.0922 -2.3114) (xy 1.0922 2.3114) (xy -1.0922 2.3114) (xy -1.0922 -2.3114)
			)
			(stroke
				(width 0)
				(type default)
			)
			(fill no)
			(layer "F.Fab")
		)
		(pad "1" smd rect
			(at 0 -1.397)
			(size 1.651 1.27)
			(layers "F.Cu" "F.Mask" "F.Paste")
			(net "P12V_HDD11")
		)
		(pad "2" smd rect
			(at 0 1.397)
			(size 1.651 1.27)
			(layers "F.Cu" "F.Mask" "F.Paste")
			(net "GND")
		)
	)
	(footprint ""
		(layer "F.Cu")
		(at 45.338746 -144.2847 90)
		(property "Reference" "R214"
			(at 0 0 90)
			(layer "F.SilkS")
			(hide yes)
			(effects
				(font
					(size 1.27 1.27)
				)
			)
		)
		(property "Value" "0R2J-2-GP"
			(at 0.064008 -3.993896 90)
			(unlocked yes)
			(layer "F.Fab")
			(hide yes)
			(effects
				(font
					(size 1.016 1.016)
					(thickness 0.1524)
				)
			)
		)
		(property "Device Type" "R402H16"
			(at 0.064008 -5.517896 90)
			(unlocked yes)
			(layer "F.Fab")
			(hide yes)
			(effects
				(font
					(size 1.016 1.016)
					(thickness 0.1524)
				)
			)
		)
		(duplicate_pad_numbers_are_jumpers no)
		(fp_line
			(start 0.508 -0.9398)
			(end -0.508 -0.9398)
			(stroke
				(width 0.1524)
				(type default)
			)
			(layer "F.SilkS")
		)
		(fp_line
			(start -0.508 -0.9398)
			(end -0.508 0.9398)
			(stroke
				(width 0.1524)
				(type default)
			)
			(layer "F.SilkS")
		)
		(fp_rect
			(start -0.508 0.9398)
			(end 0.508 -0.9398)
			(stroke
				(width 0)
				(type default)
			)
			(fill no)
			(layer "F.CrtYd")
		)
		(fp_rect
			(start -0.508 0.9398)
			(end 0.508 -0.9398)
			(stroke
				(width 0)
				(type default)
			)
			(fill no)
			(layer "F.Fab")
		)
		(pad "1" smd custom
			(at 0 -0.4445 90)
			(size 0.1397 0.1397)
			(layers "F.Cu" "F.Mask" "F.Paste")
			(net "DRV_ACT_NET8")
			(options
				(clearance outline)
				(anchor circle)
			)
			(primitives
				(gr_poly
					(pts
						(arc
							(start -0.1778 -0.2794)
							(mid -0.249642 -0.249642)
							(end -0.2794 -0.1778)
						)
						(arc
							(start -0.2794 0.1778)
							(mid -0.249642 0.249642)
							(end -0.1778 0.2794)
						)
						(arc
							(start 0.1778 0.2794)
							(mid 0.249642 0.249642)
							(end 0.2794 0.1778)
						)
						(arc
							(start 0.2794 -0.1778)
							(mid 0.249642 -0.249642)
							(end 0.1778 -0.2794)
						)
					)
					(width 0)
					(fill yes)
				)
			)
		)
		(pad "2" smd custom
			(at 0 0.4445 90)
			(size 0.1397 0.1397)
			(layers "F.Cu" "F.Mask" "F.Paste")
			(net "DRIVE_ACT_8")
			(options
				(clearance outline)
				(anchor circle)
			)
			(primitives
				(gr_poly
					(pts
						(arc
							(start -0.1778 -0.2794)
							(mid -0.249642 -0.249642)
							(end -0.2794 -0.1778)
						)
						(arc
							(start -0.2794 0.1778)
							(mid -0.249642 0.249642)
							(end -0.1778 0.2794)
						)
						(arc
							(start 0.1778 0.2794)
							(mid 0.249642 0.249642)
							(end 0.2794 0.1778)
						)
						(arc
							(start 0.2794 -0.1778)
							(mid 0.249642 -0.249642)
							(end 0.1778 -0.2794)
						)
					)
					(width 0)
					(fill yes)
				)
			)
		)
	)
	(footprint ""
		(layer "F.Cu")
		(at 11.175746 -499.5037 180)
		(property "Reference" "PC30"
			(at 0 0 180)
			(layer "F.SilkS")
			(hide yes)
			(effects
				(font
					(size 1.27 1.27)
				)
			)
		)
		(property "Value" "SC1U10V2KX-1GP"
			(at 1.1811 -2.7051 180)
			(unlocked yes)
			(layer "F.Fab")
			(hide yes)
			(effects
				(font
					(size 1.016 1.016)
					(thickness 0.1524)
				)
			)
		)
		(property "Device Type" "C402H22"
			(at 1.1811 -4.2291 180)
			(unlocked yes)
			(layer "F.Fab")
			(hide yes)
			(effects
				(font
					(size 1.016 1.016)
					(thickness 0.1524)
				)
			)
		)
		(duplicate_pad_numbers_are_jumpers no)
		(fp_rect
			(start -0.4318 0.9525)
			(end 0.4318 -0.9525)
			(stroke
				(width 0)
				(type default)
			)
			(fill no)
			(layer "F.CrtYd")
		)
		(fp_rect
			(start -0.4318 0.9525)
			(end 0.4318 -0.9525)
			(stroke
				(width 0)
				(type default)
			)
			(fill no)
			(layer "F.Fab")
		)
		(pad "1" smd custom
			(at 0 -0.4445 180)
			(size 0.1524 0.1524)
			(layers "F.Cu" "F.Mask" "F.Paste")
			(net "P5VC_VREG")
			(options
				(clearance outline)
				(anchor circle)
			)
			(primitives
				(gr_poly
					(pts
						(arc
							(start 0.3048 -0.2032)
							(mid 0.275042 -0.275042)
							(end 0.2032 -0.3048)
						)
						(arc
							(start -0.2032 -0.3048)
							(mid -0.275042 -0.275042)
							(end -0.3048 -0.2032)
						)
						(arc
							(start -0.3048 0.2032)
							(mid -0.275042 0.275042)
							(end -0.2032 0.3048)
						)
						(arc
							(start 0.2032 0.3048)
							(mid 0.275042 0.275042)
							(end 0.3048 0.2032)
						)
					)
					(width 0)
					(fill yes)
				)
			)
		)
		(pad "2" smd custom
			(at 0 0.4445 180)
			(size 0.1524 0.1524)
			(layers "F.Cu" "F.Mask" "F.Paste")
			(net "GND")
			(options
				(clearance outline)
				(anchor circle)
			)
			(primitives
				(gr_poly
					(pts
						(arc
							(start 0.3048 -0.2032)
							(mid 0.275042 -0.275042)
							(end 0.2032 -0.3048)
						)
						(arc
							(start -0.2032 -0.3048)
							(mid -0.275042 -0.275042)
							(end -0.3048 -0.2032)
						)
						(arc
							(start -0.3048 0.2032)
							(mid -0.275042 0.275042)
							(end -0.2032 0.3048)
						)
						(arc
							(start 0.2032 0.3048)
							(mid 0.275042 0.275042)
							(end 0.3048 0.2032)
						)
					)
					(width 0)
					(fill yes)
				)
			)
		)
	)
	(footprint ""
		(layer "F.Cu")
		(at 62.610746 -185.8137)
		(property "Reference" "C239"
			(at 0 0 0)
			(layer "F.SilkS")
			(hide yes)
			(effects
				(font
					(size 1.27 1.27)
				)
			)
		)
		(property "Value" "SC10U25V6KX-1GP"
			(at -0.0762 -5.1308 0)
			(unlocked yes)
			(layer "F.Fab")
			(hide yes)
			(effects
				(font
					(size 1.016 1.016)
					(thickness 0.1524)
				)
			)
		)
		(property "Device Type" "C1206H71"
			(at -0.127 -6.6548 0)
			(unlocked yes)
			(layer "F.Fab")
			(hide yes)
			(effects
				(font
					(size 1.016 1.016)
					(thickness 0.1524)
				)
			)
		)
		(duplicate_pad_numbers_are_jumpers no)
		(fp_line
			(start -1.016 -2.2352)
			(end 1.016 -2.2352)
			(stroke
				(width 0.1524)
				(type default)
			)
			(layer "F.SilkS")
		)
		(fp_line
			(start -1.016 -0.8382)
			(end -1.016 -2.2352)
			(stroke
				(width 0.1524)
				(type default)
			)
			(layer "F.SilkS")
		)
		(fp_line
			(start -1.016 2.2352)
			(end -1.016 0.8382)
			(stroke
				(width 0.1524)
				(type default)
			)
			(layer "F.SilkS")
		)
		(fp_line
			(start 1.016 -2.2352)
			(end 1.016 -0.8382)
			(stroke
				(width 0.1524)
				(type default)
			)
			(layer "F.SilkS")
		)
		(fp_line
			(start 1.016 0.8382)
			(end 1.016 2.2352)
			(stroke
				(width 0.1524)
				(type default)
			)
			(layer "F.SilkS")
		)
		(fp_line
			(start 1.016 2.2352)
			(end -1.016 2.2352)
			(stroke
				(width 0.1524)
				(type default)
			)
			(layer "F.SilkS")
		)
		(fp_rect
			(start -1.0922 2.3114)
			(end 1.0922 -2.3114)
			(stroke
				(width 0)
				(type default)
			)
			(fill no)
			(layer "F.CrtYd")
		)
		(fp_poly
			(pts
				(xy 1.0922 -2.3114) (xy 1.0922 2.3114) (xy -1.0922 2.3114) (xy -1.0922 -2.3114)
			)
			(stroke
				(width 0)
				(type default)
			)
			(fill no)
			(layer "F.Fab")
		)
		(pad "1" smd rect
			(at 0 -1.397)
			(size 1.651 1.27)
			(layers "F.Cu" "F.Mask" "F.Paste")
			(net "P12V_HDD8")
		)
		(pad "2" smd rect
			(at 0 1.397)
			(size 1.651 1.27)
			(layers "F.Cu" "F.Mask" "F.Paste")
			(net "GND")
		)
	)
	(footprint ""
		(layer "F.Cu")
		(at 68.999608 -273.999706)
		(property "Reference" "H8"
			(at 0 0 0)
			(layer "F.SilkS")
			(hide yes)
			(effects
				(font
					(size 1.27 1.27)
				)
			)
		)
		(property "Value" "HOLE315R140"
			(at 0 -7.5692 0)
			(unlocked yes)
			(layer "F.Fab")
			(hide yes)
			(effects
				(font
					(size 1.016 1.016)
					(thickness 0.1524)
				)
			)
		)
		(property "Device Type" "HOLE315R140"
			(at 0 -9.0932 0)
			(unlocked yes)
			(layer "F.Fab")
			(hide yes)
			(effects
				(font
					(size 1.016 1.016)
					(thickness 0.1524)
				)
			)
		)
		(duplicate_pad_numbers_are_jumpers no)
		(fp_poly
			(pts
				(arc
					(start 4.3053 0)
					(mid -4.3053 0)
					(end 4.3053 0)
				)
			)
			(stroke
				(width 0)
				(type default)
			)
			(fill no)
			(layer "F.CrtYd")
		)
		(fp_poly
			(pts
				(arc
					(start 4.3053 0)
					(mid -4.3053 0)
					(end 4.3053 0)
				)
			)
			(stroke
				(width 0)
				(type default)
			)
			(fill no)
			(layer "F.Fab")
		)
		(pad "1" thru_hole circle
			(at 0.00127 0.00127)
			(size 8.001 8.001)
			(drill 3.556)
			(layers "*.Cu" "*.Mask")
			(remove_unused_layers no)
			(net "GND")
			(clearance -1.7145)
			(thermal_gap 0.3048)
			(padstack
				(mode front_inner_back)
				(layer "Inner"
					(shape circle)
					(size 3.9624 3.9624)
					(clearance 0.3048)
				)
				(layer "B.Cu"
					(shape circle)
					(size 8.001 8.001)
					(clearance -1.7145)
				)
			)
		)
	)
	(footprint ""
		(layer "F.Cu")
		(at 55.2704 -285.75 180)
		(property "Reference" "C220"
			(at 0 0 180)
			(layer "F.SilkS")
			(hide yes)
			(effects
				(font
					(size 1.27 1.27)
				)
			)
		)
		(property "Value" "SC1U16V3KX-5GP"
			(at 0 -2.8194 180)
			(unlocked yes)
			(layer "F.Fab")
			(hide yes)
			(effects
				(font
					(size 1.016 1.016)
					(thickness 0.1524)
				)
			)
		)
		(property "Device Type" "C603H36"
			(at 0 -4.3434 180)
			(unlocked yes)
			(layer "F.Fab")
			(hide yes)
			(effects
				(font
					(size 1.016 1.016)
					(thickness 0.1524)
				)
			)
		)
		(duplicate_pad_numbers_are_jumpers no)
		(fp_line
			(start 0.508 0)
			(end -0.508 0)
			(stroke
				(width 0.2032)
				(type default)
			)
			(layer "F.SilkS")
		)
		(fp_rect
			(start -0.5842 1.3335)
			(end 0.5842 -1.3335)
			(stroke
				(width 0)
				(type default)
			)
			(fill no)
			(layer "F.CrtYd")
		)
		(fp_rect
			(start -0.5842 1.3335)
			(end 0.5842 -1.3335)
			(stroke
				(width 0)
				(type default)
			)
			(fill no)
			(layer "F.Fab")
		)
		(pad "1" smd custom
			(at 0 -0.762 180)
			(size 0.2159 0.2159)
			(layers "F.Cu" "F.Mask" "F.Paste")
			(net "P5V_HDD7")
			(options
				(clearance outline)
				(anchor circle)
			)
			(primitives
				(gr_poly
					(pts
						(arc
							(start -0.3302 -0.4318)
							(mid -0.402042 -0.402042)
							(end -0.4318 -0.3302)
						)
						(arc
							(start -0.4318 0.3302)
							(mid -0.402042 0.402042)
							(end -0.3302 0.4318)
						)
						(arc
							(start 0.3302 0.4318)
							(mid 0.402042 0.402042)
							(end 0.4318 0.3302)
						)
						(arc
							(start 0.4318 -0.3302)
							(mid 0.402042 -0.402042)
							(end 0.3302 -0.4318)
						)
					)
					(width 0)
					(fill yes)
				)
			)
		)
		(pad "2" smd custom
			(at 0 0.762 180)
			(size 0.2159 0.2159)
			(layers "F.Cu" "F.Mask" "F.Paste")
			(net "GND")
			(options
				(clearance outline)
				(anchor circle)
			)
			(primitives
				(gr_poly
					(pts
						(arc
							(start -0.3302 -0.4318)
							(mid -0.402042 -0.402042)
							(end -0.4318 -0.3302)
						)
						(arc
							(start -0.4318 0.3302)
							(mid -0.402042 0.402042)
							(end -0.3302 0.4318)
						)
						(arc
							(start 0.3302 0.4318)
							(mid 0.402042 0.402042)
							(end 0.4318 0.3302)
						)
						(arc
							(start 0.4318 -0.3302)
							(mid 0.402042 -0.402042)
							(end 0.3302 -0.4318)
						)
					)
					(width 0)
					(fill yes)
				)
			)
		)
	)
	(footprint ""
		(layer "F.Cu")
		(at 33.893252 -166.25951 -90)
		(property "Reference" "C232"
			(at 0 0 270)
			(layer "F.SilkS")
			(hide yes)
			(effects
				(font
					(size 1.27 1.27)
				)
			)
		)
		(property "Value" "SCD01U50V2KX-1GP"
			(at 1.1811 -2.7051 270)
			(unlocked yes)
			(layer "F.Fab")
			(hide yes)
			(effects
				(font
					(size 1.016 1.016)
					(thickness 0.1524)
				)
			)
		)
		(property "Device Type" "C402H22"
			(at 1.1811 -4.2291 270)
			(unlocked yes)
			(layer "F.Fab")
			(hide yes)
			(effects
				(font
					(size 1.016 1.016)
					(thickness 0.1524)
				)
			)
		)
		(duplicate_pad_numbers_are_jumpers no)
		(fp_rect
			(start -0.4318 0.9525)
			(end 0.4318 -0.9525)
			(stroke
				(width 0)
				(type default)
			)
			(fill no)
			(layer "F.CrtYd")
		)
		(fp_rect
			(start -0.4318 0.9525)
			(end 0.4318 -0.9525)
			(stroke
				(width 0)
				(type default)
			)
			(fill no)
			(layer "F.Fab")
		)
		(pad "1" smd custom
			(at 0 -0.4445 270)
			(size 0.1524 0.1524)
			(layers "F.Cu" "F.Mask" "F.Paste")
			(net "SAS2X28_DRIVE_RX_N_B8")
			(options
				(clearance outline)
				(anchor circle)
			)
			(primitives
				(gr_poly
					(pts
						(arc
							(start 0.3048 -0.2032)
							(mid 0.275042 -0.275042)
							(end 0.2032 -0.3048)
						)
						(arc
							(start -0.2032 -0.3048)
							(mid -0.275042 -0.275042)
							(end -0.3048 -0.2032)
						)
						(arc
							(start -0.3048 0.2032)
							(mid -0.275042 0.275042)
							(end -0.2032 0.3048)
						)
						(arc
							(start 0.2032 0.3048)
							(mid 0.275042 0.275042)
							(end 0.3048 0.2032)
						)
					)
					(width 0)
					(fill yes)
				)
			)
		)
		(pad "2" smd custom
			(at 0 0.4445 270)
			(size 0.1524 0.1524)
			(layers "F.Cu" "F.Mask" "F.Paste")
			(net "SAS2X28_B_HDD8_RX_-")
			(options
				(clearance outline)
				(anchor circle)
			)
			(primitives
				(gr_poly
					(pts
						(arc
							(start 0.3048 -0.2032)
							(mid 0.275042 -0.275042)
							(end 0.2032 -0.3048)
						)
						(arc
							(start -0.2032 -0.3048)
							(mid -0.275042 -0.275042)
							(end -0.3048 -0.2032)
						)
						(arc
							(start -0.3048 0.2032)
							(mid -0.275042 0.275042)
							(end -0.2032 0.3048)
						)
						(arc
							(start 0.2032 0.3048)
							(mid 0.275042 0.275042)
							(end 0.3048 0.2032)
						)
					)
					(width 0)
					(fill yes)
				)
			)
		)
	)
	(footprint ""
		(layer "F.Cu")
		(at 33.527746 -433.0827 180)
		(property "Reference" "R463"
			(at 0 0 180)
			(layer "F.SilkS")
			(hide yes)
			(effects
				(font
					(size 1.27 1.27)
				)
			)
		)
		(property "Value" "4K7R2J-2-GP"
			(at 0.064008 -3.993896 180)
			(unlocked yes)
			(layer "F.Fab")
			(hide yes)
			(effects
				(font
					(size 1.016 1.016)
					(thickness 0.1524)
				)
			)
		)
		(property "Device Type" "R402H16"
			(at 0.064008 -5.517896 180)
			(unlocked yes)
			(layer "F.Fab")
			(hide yes)
			(effects
				(font
					(size 1.016 1.016)
					(thickness 0.1524)
				)
			)
		)
		(duplicate_pad_numbers_are_jumpers no)
		(fp_line
			(start 0.508 -0.9398)
			(end -0.508 -0.9398)
			(stroke
				(width 0.1524)
				(type default)
			)
			(layer "F.SilkS")
		)
		(fp_line
			(start -0.508 -0.9398)
			(end -0.508 0.9398)
			(stroke
				(width 0.1524)
				(type default)
			)
			(layer "F.SilkS")
		)
		(fp_rect
			(start -0.508 0.9398)
			(end 0.508 -0.9398)
			(stroke
				(width 0)
				(type default)
			)
			(fill no)
			(layer "F.CrtYd")
		)
		(fp_rect
			(start -0.508 0.9398)
			(end 0.508 -0.9398)
			(stroke
				(width 0)
				(type default)
			)
			(fill no)
			(layer "F.Fab")
		)
		(pad "1" smd custom
			(at 0 -0.4445 180)
			(size 0.1397 0.1397)
			(layers "F.Cu" "F.Mask" "F.Paste")
			(net "P3V3")
			(options
				(clearance outline)
				(anchor circle)
			)
			(primitives
				(gr_poly
					(pts
						(arc
							(start -0.1778 -0.2794)
							(mid -0.249642 -0.249642)
							(end -0.2794 -0.1778)
						)
						(arc
							(start -0.2794 0.1778)
							(mid -0.249642 0.249642)
							(end -0.1778 0.2794)
						)
						(arc
							(start 0.1778 0.2794)
							(mid 0.249642 0.249642)
							(end 0.2794 0.1778)
						)
						(arc
							(start 0.2794 -0.1778)
							(mid 0.249642 -0.249642)
							(end 0.1778 -0.2794)
						)
					)
					(width 0)
					(fill yes)
				)
			)
		)
		(pad "2" smd custom
			(at 0 0.4445 180)
			(size 0.1397 0.1397)
			(layers "F.Cu" "F.Mask" "F.Paste")
			(net "SAS_EXP_B_PWR10")
			(options
				(clearance outline)
				(anchor circle)
			)
			(primitives
				(gr_poly
					(pts
						(arc
							(start -0.1778 -0.2794)
							(mid -0.249642 -0.249642)
							(end -0.2794 -0.1778)
						)
						(arc
							(start -0.2794 0.1778)
							(mid -0.249642 0.249642)
							(end -0.1778 0.2794)
						)
						(arc
							(start 0.1778 0.2794)
							(mid 0.249642 0.249642)
							(end 0.2794 0.1778)
						)
						(arc
							(start 0.2794 -0.1778)
							(mid 0.249642 -0.249642)
							(end 0.1778 -0.2794)
						)
					)
					(width 0)
					(fill yes)
				)
			)
		)
	)
	(footprint ""
		(layer "F.Cu")
		(at 58.038746 -392.6967 90)
		(property "Reference" "R195"
			(at 0 0 90)
			(layer "F.SilkS")
			(hide yes)
			(effects
				(font
					(size 1.27 1.27)
				)
			)
		)
		(property "Value" "2R2010J-1-GP"
			(at 0.254 -8.0772 90)
			(unlocked yes)
			(layer "F.Fab")
			(hide yes)
			(effects
				(font
					(size 1.016 1.016)
					(thickness 0.1524)
				)
			)
		)
		(property "Device Type" "R2010H28"
			(at 0.254 -9.6774 90)
			(unlocked yes)
			(layer "F.Fab")
			(hide yes)
			(effects
				(font
					(size 1.016 1.016)
					(thickness 0.1524)
				)
			)
		)
		(duplicate_pad_numbers_are_jumpers no)
		(fp_line
			(start 1.651 -3.302)
			(end -1.651 -3.302)
			(stroke
				(width 0.1524)
				(type default)
			)
			(layer "F.SilkS")
		)
		(fp_line
			(start -1.651 -3.302)
			(end -1.651 3.302)
			(stroke
				(width 0.1524)
				(type default)
			)
			(layer "F.SilkS")
		)
		(fp_line
			(start 1.651 3.302)
			(end 1.651 -3.302)
			(stroke
				(width 0.1524)
				(type default)
			)
			(layer "F.SilkS")
		)
		(fp_line
			(start -1.651 3.302)
			(end 1.651 3.302)
			(stroke
				(width 0.1524)
				(type default)
			)
			(layer "F.SilkS")
		)
		(fp_rect
			(start -1.7272 -3.3782)
			(end 1.7272 3.3782)
			(stroke
				(width 0)
				(type default)
			)
			(fill no)
			(layer "F.CrtYd")
		)
		(fp_poly
			(pts
				(xy 1.7272 3.3782) (xy 1.7272 -3.3782) (xy -1.7272 -3.3782) (xy -1.7272 3.3782)
			)
			(stroke
				(width 0)
				(type default)
			)
			(fill no)
			(layer "F.Fab")
		)
		(pad "1" smd rect
			(at 0 -2.3495 90)
			(size 2.794 1.143)
			(layers "F.Cu" "F.Mask" "F.Paste")
			(net "12V_PRE_6")
		)
		(pad "2" smd rect
			(at 0 2.3495 90)
			(size 2.794 1.143)
			(layers "F.Cu" "F.Mask" "F.Paste")
			(net "P12V_HDD6")
		)
	)
	(footprint ""
		(layer "F.Cu")
		(at 54.2544 -497.7384 180)
		(property "Reference" "C195"
			(at 0 0 180)
			(layer "F.SilkS")
			(hide yes)
			(effects
				(font
					(size 1.27 1.27)
				)
			)
		)
		(property "Value" "SC1U25V3KX-1-GP"
			(at 0 -2.8194 180)
			(unlocked yes)
			(layer "F.Fab")
			(hide yes)
			(effects
				(font
					(size 1.016 1.016)
					(thickness 0.1524)
				)
			)
		)
		(property "Device Type" "C603H36"
			(at 0 -4.3434 180)
			(unlocked yes)
			(layer "F.Fab")
			(hide yes)
			(effects
				(font
					(size 1.016 1.016)
					(thickness 0.1524)
				)
			)
		)
		(duplicate_pad_numbers_are_jumpers no)
		(fp_line
			(start 0.508 0)
			(end -0.508 0)
			(stroke
				(width 0.2032)
				(type default)
			)
			(layer "F.SilkS")
		)
		(fp_rect
			(start -0.5842 1.3335)
			(end 0.5842 -1.3335)
			(stroke
				(width 0)
				(type default)
			)
			(fill no)
			(layer "F.CrtYd")
		)
		(fp_rect
			(start -0.5842 1.3335)
			(end 0.5842 -1.3335)
			(stroke
				(width 0)
				(type default)
			)
			(fill no)
			(layer "F.Fab")
		)
		(pad "1" smd custom
			(at 0 -0.762 180)
			(size 0.2159 0.2159)
			(layers "F.Cu" "F.Mask" "F.Paste")
			(net "P12V_HDD5")
			(options
				(clearance outline)
				(anchor circle)
			)
			(primitives
				(gr_poly
					(pts
						(arc
							(start -0.3302 -0.4318)
							(mid -0.402042 -0.402042)
							(end -0.4318 -0.3302)
						)
						(arc
							(start -0.4318 0.3302)
							(mid -0.402042 0.402042)
							(end -0.3302 0.4318)
						)
						(arc
							(start 0.3302 0.4318)
							(mid 0.402042 0.402042)
							(end 0.4318 0.3302)
						)
						(arc
							(start 0.4318 -0.3302)
							(mid 0.402042 -0.402042)
							(end 0.3302 -0.4318)
						)
					)
					(width 0)
					(fill yes)
				)
			)
		)
		(pad "2" smd custom
			(at 0 0.762 180)
			(size 0.2159 0.2159)
			(layers "F.Cu" "F.Mask" "F.Paste")
			(net "GND")
			(options
				(clearance outline)
				(anchor circle)
			)
			(primitives
				(gr_poly
					(pts
						(arc
							(start -0.3302 -0.4318)
							(mid -0.402042 -0.402042)
							(end -0.4318 -0.3302)
						)
						(arc
							(start -0.4318 0.3302)
							(mid -0.402042 0.402042)
							(end -0.3302 0.4318)
						)
						(arc
							(start 0.3302 0.4318)
							(mid 0.402042 0.402042)
							(end 0.4318 0.3302)
						)
						(arc
							(start 0.4318 -0.3302)
							(mid 0.402042 -0.402042)
							(end 0.3302 -0.4318)
						)
					)
					(width 0)
					(fill yes)
				)
			)
		)
	)
	(footprint ""
		(layer "F.Cu")
		(at 48.208946 -144.3736 90)
		(property "Reference" "Q42"
			(at 0 0 90)
			(layer "F.SilkS")
			(hide yes)
			(effects
				(font
					(size 1.27 1.27)
				)
			)
		)
		(property "Value" "PMBS3904-1-GP"
			(at 0 -9.0932 90)
			(unlocked yes)
			(layer "F.Fab")
			(hide yes)
			(effects
				(font
					(size 1.016 1.016)
					(thickness 0.1524)
				)
			)
		)
		(property "Device Type" "SOT-23-10H44"
			(at 0 -10.6172 90)
			(unlocked yes)
			(layer "F.Fab")
			(hide yes)
			(effects
				(font
					(size 1.016 1.016)
					(thickness 0.1524)
				)
			)
		)
		(duplicate_pad_numbers_are_jumpers no)
		(fp_line
			(start 1.651 -1.778)
			(end -1.651 -1.778)
			(stroke
				(width 0.1524)
				(type default)
			)
			(layer "F.SilkS")
		)
		(fp_line
			(start -1.651 -1.778)
			(end -1.651 1.778)
			(stroke
				(width 0.1524)
				(type default)
			)
			(layer "F.SilkS")
		)
		(fp_line
			(start 1.651 1.778)
			(end 1.651 -1.778)
			(stroke
				(width 0.1524)
				(type default)
			)
			(layer "F.SilkS")
		)
		(fp_line
			(start -1.651 1.778)
			(end 1.651 1.778)
			(stroke
				(width 0.1524)
				(type default)
			)
			(layer "F.SilkS")
		)
		(fp_line
			(start -0.9906 1.86309)
			(end -0.701294 2.15265)
			(stroke
				(width 0.0127)
				(type default)
			)
			(layer "F.SilkS")
		)
		(fp_line
			(start -0.994156 1.8669)
			(end -0.987044 1.8669)
			(stroke
				(width 0.0127)
				(type default)
			)
			(layer "F.SilkS")
		)
		(fp_line
			(start -1.003808 1.876552)
			(end -0.977646 1.876552)
			(stroke
				(width 0.0127)
				(type default)
			)
			(layer "F.SilkS")
		)
		(fp_line
			(start -0.635 1.8796)
			(end -1.7526 1.8796)
			(stroke
				(width 0.3302)
				(type default)
			)
			(layer "F.SilkS")
		)
		(fp_line
			(start -1.7526 1.8796)
			(end -1.7526 0.9906)
			(stroke
				(width 0.3302)
				(type default)
			)
			(layer "F.SilkS")
		)
		(fp_line
			(start -1.013206 1.88595)
			(end -0.967994 1.88595)
			(stroke
				(width 0.0127)
				(type default)
			)
			(layer "F.SilkS")
		)
		(fp_line
			(start -1.022858 1.895602)
			(end -0.958596 1.895602)
			(stroke
				(width 0.0127)
				(type default)
			)
			(layer "F.SilkS")
		)
		(fp_line
			(start -1.032256 1.905)
			(end -0.948944 1.905)
			(stroke
				(width 0.0127)
				(type default)
			)
			(layer "F.SilkS")
		)
		(fp_line
			(start -1.041908 1.914652)
			(end -0.939546 1.914652)
			(stroke
				(width 0.0127)
				(type default)
			)
			(layer "F.SilkS")
		)
		(fp_line
			(start -1.051306 1.92405)
			(end -0.929894 1.92405)
			(stroke
				(width 0.0127)
				(type default)
			)
			(layer "F.SilkS")
		)
		(fp_line
			(start -1.060958 1.933702)
			(end -0.920496 1.933702)
			(stroke
				(width 0.0127)
				(type default)
			)
			(layer "F.SilkS")
		)
		(fp_line
			(start -1.070356 1.9431)
			(end -0.910844 1.9431)
			(stroke
				(width 0.0127)
				(type default)
			)
			(layer "F.SilkS")
		)
		(fp_line
			(start -1.080008 1.952752)
			(end -0.901446 1.952752)
			(stroke
				(width 0.0127)
				(type default)
			)
			(layer "F.SilkS")
		)
		(fp_line
			(start -1.089406 1.96215)
			(end -0.891794 1.96215)
			(stroke
				(width 0.0127)
				(type default)
			)
			(layer "F.SilkS")
		)
		(fp_line
			(start -1.099058 1.971802)
			(end -0.882396 1.971802)
			(stroke
				(width 0.0127)
				(type default)
			)
			(layer "F.SilkS")
		)
		(fp_line
			(start -1.108456 1.9812)
			(end -0.872744 1.9812)
			(stroke
				(width 0.0127)
				(type default)
			)
			(layer "F.SilkS")
		)
		(fp_line
			(start -1.118108 1.990852)
			(end -0.863346 1.990852)
			(stroke
				(width 0.0127)
				(type default)
			)
			(layer "F.SilkS")
		)
		(fp_line
			(start -1.127506 2.00025)
			(end -0.853694 2.00025)
			(stroke
				(width 0.0127)
				(type default)
			)
			(layer "F.SilkS")
		)
		(fp_line
			(start -1.137158 2.009902)
			(end -0.844296 2.009902)
			(stroke
				(width 0.0127)
				(type default)
			)
			(layer "F.SilkS")
		)
		(fp_line
			(start -1.146556 2.0193)
			(end -0.834644 2.0193)
			(stroke
				(width 0.0127)
				(type default)
			)
			(layer "F.SilkS")
		)
		(fp_line
			(start -1.156208 2.028952)
			(end -0.825246 2.028952)
			(stroke
				(width 0.0127)
				(type default)
			)
			(layer "F.SilkS")
		)
		(fp_line
			(start -1.165606 2.03835)
			(end -0.815594 2.03835)
			(stroke
				(width 0.0127)
				(type default)
			)
			(layer "F.SilkS")
		)
		(fp_line
			(start -1.175258 2.048002)
			(end -0.806196 2.048002)
			(stroke
				(width 0.0127)
				(type default)
			)
			(layer "F.SilkS")
		)
		(fp_line
			(start -1.184656 2.0574)
			(end -0.796544 2.0574)
			(stroke
				(width 0.0127)
				(type default)
			)
			(layer "F.SilkS")
		)
		(fp_line
			(start -1.194308 2.067052)
			(end -0.787146 2.067052)
			(stroke
				(width 0.0127)
				(type default)
			)
			(layer "F.SilkS")
		)
		(fp_line
			(start -1.203706 2.07645)
			(end -0.777494 2.07645)
			(stroke
				(width 0.0127)
				(type default)
			)
			(layer "F.SilkS")
		)
		(fp_line
			(start -1.213358 2.086102)
			(end -0.768096 2.086102)
			(stroke
				(width 0.0127)
				(type default)
			)
			(layer "F.SilkS")
		)
		(fp_line
			(start -1.222756 2.0955)
			(end -0.758444 2.0955)
			(stroke
				(width 0.0127)
				(type default)
			)
			(layer "F.SilkS")
		)
		(fp_line
			(start -1.232408 2.105152)
			(end -0.749046 2.105152)
			(stroke
				(width 0.0127)
				(type default)
			)
			(layer "F.SilkS")
		)
		(fp_line
			(start -1.241806 2.11455)
			(end -0.739394 2.11455)
			(stroke
				(width 0.0127)
				(type default)
			)
			(layer "F.SilkS")
		)
		(fp_line
			(start -1.251458 2.124202)
			(end -0.729996 2.124202)
			(stroke
				(width 0.0127)
				(type default)
			)
			(layer "F.SilkS")
		)
		(fp_line
			(start -1.260856 2.1336)
			(end -0.720344 2.1336)
			(stroke
				(width 0.0127)
				(type default)
			)
			(layer "F.SilkS")
		)
		(fp_line
			(start -0.719074 2.145538)
			(end -1.265936 2.14122)
			(stroke
				(width 0.0127)
				(type default)
			)
			(layer "F.SilkS")
		)
		(fp_line
			(start -1.279398 2.152142)
			(end -0.9906 1.86309)
			(stroke
				(width 0.0127)
				(type default)
			)
			(layer "F.SilkS")
		)
		(fp_line
			(start -0.71628 2.15265)
			(end -1.26492 2.15265)
			(stroke
				(width 0.0127)
				(type default)
			)
			(layer "F.SilkS")
		)
		(fp_line
			(start -1.279144 2.15265)
			(end -0.701294 2.15265)
			(stroke
				(width 0.0127)
				(type default)
			)
			(layer "F.SilkS")
		)
		(fp_poly
			(pts
				(xy -1.285748 2.159) (xy -1.285748 1.8796) (xy -1.778 1.8796) (xy -1.778 -1.8796) (xy 1.778 -1.8796)
				(xy 1.778 1.8796) (xy -0.694944 1.8796) (xy -0.694944 2.159)
			)
			(stroke
				(width 0)
				(type default)
			)
			(fill no)
			(layer "F.CrtYd")
		)
		(fp_poly
			(pts
				(xy -1.285748 2.159) (xy -1.285748 1.8796) (xy -1.778 1.8796) (xy -1.778 -1.8796) (xy 1.778 -1.8796)
				(xy 1.778 1.8796) (xy -0.694944 1.8796) (xy -0.694944 2.159)
			)
			(stroke
				(width 0)
				(type default)
			)
			(fill no)
			(layer "F.Fab")
		)
		(pad "1" smd rect
			(at -0.98425 0.9525 90)
			(size 0.762 1.143)
			(layers "F.Cu" "F.Mask" "F.Paste")
			(net "FLT_HDD8_B")
		)
		(pad "2" smd rect
			(at 0.98425 0.9525 90)
			(size 0.762 1.143)
			(layers "F.Cu" "F.Mask" "F.Paste")
			(net "GND")
		)
		(pad "3" smd rect
			(at 0 -0.9525 90)
			(size 0.762 1.143)
			(layers "F.Cu" "F.Mask" "F.Paste")
			(net "DRIVE_ACT_8")
		)
	)
	(footprint ""
		(layer "F.Cu")
		(at 46.100746 -25.1587 90)
		(property "Reference" "PC21"
			(at 0 0 90)
			(layer "F.SilkS")
			(hide yes)
			(effects
				(font
					(size 1.27 1.27)
				)
			)
		)
		(property "Value" "SCD1U25V2KX-GP"
			(at 1.1811 -2.7051 90)
			(unlocked yes)
			(layer "F.Fab")
			(hide yes)
			(effects
				(font
					(size 1.016 1.016)
					(thickness 0.1524)
				)
			)
		)
		(property "Device Type" "C402H22"
			(at 1.1811 -4.2291 90)
			(unlocked yes)
			(layer "F.Fab")
			(hide yes)
			(effects
				(font
					(size 1.016 1.016)
					(thickness 0.1524)
				)
			)
		)
		(duplicate_pad_numbers_are_jumpers no)
		(fp_rect
			(start -0.4318 0.9525)
			(end 0.4318 -0.9525)
			(stroke
				(width 0)
				(type default)
			)
			(fill no)
			(layer "F.CrtYd")
		)
		(fp_rect
			(start -0.4318 0.9525)
			(end 0.4318 -0.9525)
			(stroke
				(width 0)
				(type default)
			)
			(fill no)
			(layer "F.Fab")
		)
		(pad "1" smd custom
			(at 0 -0.4445 90)
			(size 0.1524 0.1524)
			(layers "F.Cu" "F.Mask" "F.Paste")
			(net "P5VB")
			(options
				(clearance outline)
				(anchor circle)
			)
			(primitives
				(gr_poly
					(pts
						(arc
							(start 0.3048 -0.2032)
							(mid 0.275042 -0.275042)
							(end 0.2032 -0.3048)
						)
						(arc
							(start -0.2032 -0.3048)
							(mid -0.275042 -0.275042)
							(end -0.3048 -0.2032)
						)
						(arc
							(start -0.3048 0.2032)
							(mid -0.275042 0.275042)
							(end -0.2032 0.3048)
						)
						(arc
							(start 0.2032 0.3048)
							(mid 0.275042 0.275042)
							(end 0.3048 0.2032)
						)
					)
					(width 0)
					(fill yes)
				)
			)
		)
		(pad "2" smd custom
			(at 0 0.4445 90)
			(size 0.1524 0.1524)
			(layers "F.Cu" "F.Mask" "F.Paste")
			(net "P5VB_LL_NET")
			(options
				(clearance outline)
				(anchor circle)
			)
			(primitives
				(gr_poly
					(pts
						(arc
							(start 0.3048 -0.2032)
							(mid 0.275042 -0.275042)
							(end 0.2032 -0.3048)
						)
						(arc
							(start -0.2032 -0.3048)
							(mid -0.275042 -0.275042)
							(end -0.3048 -0.2032)
						)
						(arc
							(start -0.3048 0.2032)
							(mid -0.275042 0.275042)
							(end -0.2032 0.3048)
						)
						(arc
							(start 0.2032 0.3048)
							(mid 0.275042 0.275042)
							(end 0.3048 0.2032)
						)
					)
					(width 0)
					(fill yes)
				)
			)
		)
	)
	(footprint ""
		(layer "F.Cu")
		(at 60.9854 -478.5868 180)
		(property "Reference" "Q57"
			(at 0 0 180)
			(layer "F.SilkS")
			(hide yes)
			(effects
				(font
					(size 1.27 1.27)
				)
			)
		)
		(property "Value" "2N7002-11-GP"
			(at 0.127 -8.9662 180)
			(unlocked yes)
			(layer "F.Fab")
			(hide yes)
			(effects
				(font
					(size 1.016 1.016)
					(thickness 0.1524)
				)
			)
		)
		(property "Device Type" "SOT23DGS2D4H44"
			(at 0.127 -10.4902 180)
			(unlocked yes)
			(layer "F.Fab")
			(hide yes)
			(effects
				(font
					(size 1.016 1.016)
					(thickness 0.1524)
				)
			)
		)
		(duplicate_pad_numbers_are_jumpers no)
		(fp_line
			(start 1.651 1.778)
			(end 1.651 -1.778)
			(stroke
				(width 0.1524)
				(type default)
			)
			(layer "F.SilkS")
		)
		(fp_line
			(start 1.651 -1.778)
			(end -1.651 -1.778)
			(stroke
				(width 0.1524)
				(type default)
			)
			(layer "F.SilkS")
		)
		(fp_line
			(start -1.651 1.778)
			(end 1.651 1.778)
			(stroke
				(width 0.1524)
				(type default)
			)
			(layer "F.SilkS")
		)
		(fp_line
			(start -1.651 -1.778)
			(end -1.651 1.778)
			(stroke
				(width 0.1524)
				(type default)
			)
			(layer "F.SilkS")
		)
		(fp_poly
			(pts
				(xy -1.778 1.8796) (xy -1.778 -1.8796) (xy 1.778 -1.8796) (xy 1.778 1.8796)
			)
			(stroke
				(width 0)
				(type default)
			)
			(fill no)
			(layer "F.CrtYd")
		)
		(fp_poly
			(pts
				(xy -1.778 1.8796) (xy -1.778 -1.8796) (xy 1.778 -1.8796) (xy 1.778 1.8796)
			)
			(stroke
				(width 0)
				(type default)
			)
			(fill no)
			(layer "F.Fab")
		)
		(pad "D" smd custom
			(at 0 -0.9525 180)
			(size 0.1905 0.1905)
			(layers "F.Cu" "F.Mask" "F.Paste")
			(net "HDD5_LED_G")
			(options
				(clearance outline)
				(anchor circle)
			)
			(primitives
				(gr_poly
					(pts
						(arc
							(start -0.1778 0.5715)
							(mid -0.321484 0.511984)
							(end -0.381 0.3683)
						)
						(arc
							(start -0.381 -0.3683)
							(mid -0.321484 -0.511984)
							(end -0.1778 -0.5715)
						)
						(arc
							(start 0.1778 -0.5715)
							(mid 0.321484 -0.511984)
							(end 0.381 -0.3683)
						)
						(arc
							(start 0.381 0.3683)
							(mid 0.321484 0.511984)
							(end 0.1778 0.5715)
						)
					)
					(width 0)
					(fill yes)
				)
			)
		)
		(pad "G" smd custom
			(at -0.98425 0.9525 180)
			(size 0.1905 0.1905)
			(layers "F.Cu" "F.Mask" "F.Paste")
			(net "HDD5_LED_B")
			(options
				(clearance outline)
				(anchor circle)
			)
			(primitives
				(gr_poly
					(pts
						(arc
							(start -0.1778 0.5715)
							(mid -0.321484 0.511984)
							(end -0.381 0.3683)
						)
						(arc
							(start -0.381 -0.3683)
							(mid -0.321484 -0.511984)
							(end -0.1778 -0.5715)
						)
						(arc
							(start 0.1778 -0.5715)
							(mid 0.321484 -0.511984)
							(end 0.381 -0.3683)
						)
						(arc
							(start 0.381 0.3683)
							(mid 0.321484 0.511984)
							(end 0.1778 0.5715)
						)
					)
					(width 0)
					(fill yes)
				)
			)
		)
		(pad "S" smd custom
			(at 0.98425 0.9525 180)
			(size 0.1905 0.1905)
			(layers "F.Cu" "F.Mask" "F.Paste")
			(net "GND")
			(options
				(clearance outline)
				(anchor circle)
			)
			(primitives
				(gr_poly
					(pts
						(arc
							(start -0.1778 0.5715)
							(mid -0.321484 0.511984)
							(end -0.381 0.3683)
						)
						(arc
							(start -0.381 -0.3683)
							(mid -0.321484 -0.511984)
							(end -0.1778 -0.5715)
						)
						(arc
							(start 0.1778 -0.5715)
							(mid 0.321484 -0.511984)
							(end 0.381 -0.3683)
						)
						(arc
							(start 0.381 0.3683)
							(mid 0.321484 0.511984)
							(end 0.1778 0.5715)
						)
					)
					(width 0)
					(fill yes)
				)
			)
		)
	)
	(footprint ""
		(layer "F.Cu")
		(at 38.099746 -131.473702 -90)
		(property "Reference" "R291"
			(at 0 0 270)
			(layer "F.SilkS")
			(hide yes)
			(effects
				(font
					(size 1.27 1.27)
				)
			)
		)
		(property "Value" "4K7R2J-2-GP"
			(at 0.064008 -3.993896 270)
			(unlocked yes)
			(layer "F.Fab")
			(hide yes)
			(effects
				(font
					(size 1.016 1.016)
					(thickness 0.1524)
				)
			)
		)
		(property "Device Type" "R402H16"
			(at 0.064008 -5.517896 270)
			(unlocked yes)
			(layer "F.Fab")
			(hide yes)
			(effects
				(font
					(size 1.016 1.016)
					(thickness 0.1524)
				)
			)
		)
		(duplicate_pad_numbers_are_jumpers no)
		(fp_line
			(start -0.508 -0.9398)
			(end -0.508 0.9398)
			(stroke
				(width 0.1524)
				(type default)
			)
			(layer "F.SilkS")
		)
		(fp_line
			(start 0.508 -0.9398)
			(end -0.508 -0.9398)
			(stroke
				(width 0.1524)
				(type default)
			)
			(layer "F.SilkS")
		)
		(fp_rect
			(start -0.508 0.9398)
			(end 0.508 -0.9398)
			(stroke
				(width 0)
				(type default)
			)
			(fill no)
			(layer "F.CrtYd")
		)
		(fp_rect
			(start -0.508 0.9398)
			(end 0.508 -0.9398)
			(stroke
				(width 0)
				(type default)
			)
			(fill no)
			(layer "F.Fab")
		)
		(pad "1" smd custom
			(at 0 -0.4445 270)
			(size 0.1397 0.1397)
			(layers "F.Cu" "F.Mask" "F.Paste")
			(net "P3V3")
			(options
				(clearance outline)
				(anchor circle)
			)
			(primitives
				(gr_poly
					(pts
						(arc
							(start -0.1778 -0.2794)
							(mid -0.249642 -0.249642)
							(end -0.2794 -0.1778)
						)
						(arc
							(start -0.2794 0.1778)
							(mid -0.249642 0.249642)
							(end -0.1778 0.2794)
						)
						(arc
							(start 0.1778 0.2794)
							(mid 0.249642 0.249642)
							(end 0.2794 0.1778)
						)
						(arc
							(start 0.2794 -0.1778)
							(mid 0.249642 -0.249642)
							(end 0.1778 -0.2794)
						)
					)
					(width 0)
					(fill yes)
				)
			)
		)
		(pad "2" smd custom
			(at 0 0.4445 270)
			(size 0.1397 0.1397)
			(layers "F.Cu" "F.Mask" "F.Paste")
			(net "HDD_PRSNT_NET13")
			(options
				(clearance outline)
				(anchor circle)
			)
			(primitives
				(gr_poly
					(pts
						(arc
							(start -0.1778 -0.2794)
							(mid -0.249642 -0.249642)
							(end -0.2794 -0.1778)
						)
						(arc
							(start -0.2794 0.1778)
							(mid -0.249642 0.249642)
							(end -0.1778 0.2794)
						)
						(arc
							(start 0.1778 0.2794)
							(mid 0.249642 0.249642)
							(end 0.2794 0.1778)
						)
						(arc
							(start 0.2794 -0.1778)
							(mid 0.249642 -0.249642)
							(end 0.1778 -0.2794)
						)
					)
					(width 0)
					(fill yes)
				)
			)
		)
	)
	(footprint ""
		(layer "F.Cu")
		(at 71.246746 -87.2617)
		(property "Reference" "R456"
			(at 0 0 0)
			(layer "F.SilkS")
			(hide yes)
			(effects
				(font
					(size 1.27 1.27)
				)
			)
		)
		(property "Value" "4K7R2J-2-GP"
			(at 0.064008 -3.993896 0)
			(unlocked yes)
			(layer "F.Fab")
			(hide yes)
			(effects
				(font
					(size 1.016 1.016)
					(thickness 0.1524)
				)
			)
		)
		(property "Device Type" "R402H16"
			(at 0.064008 -5.517896 0)
			(unlocked yes)
			(layer "F.Fab")
			(hide yes)
			(effects
				(font
					(size 1.016 1.016)
					(thickness 0.1524)
				)
			)
		)
		(duplicate_pad_numbers_are_jumpers no)
		(fp_line
			(start -0.508 -0.9398)
			(end -0.508 0.9398)
			(stroke
				(width 0.1524)
				(type default)
			)
			(layer "F.SilkS")
		)
		(fp_line
			(start 0.508 -0.9398)
			(end -0.508 -0.9398)
			(stroke
				(width 0.1524)
				(type default)
			)
			(layer "F.SilkS")
		)
		(fp_rect
			(start -0.508 0.9398)
			(end 0.508 -0.9398)
			(stroke
				(width 0)
				(type default)
			)
			(fill no)
			(layer "F.CrtYd")
		)
		(fp_rect
			(start -0.508 0.9398)
			(end 0.508 -0.9398)
			(stroke
				(width 0)
				(type default)
			)
			(fill no)
			(layer "F.Fab")
		)
		(pad "1" smd custom
			(at 0 -0.4445)
			(size 0.1397 0.1397)
			(layers "F.Cu" "F.Mask" "F.Paste")
			(net "P3V3")
			(options
				(clearance outline)
				(anchor circle)
			)
			(primitives
				(gr_poly
					(pts
						(arc
							(start -0.1778 -0.2794)
							(mid -0.249642 -0.249642)
							(end -0.2794 -0.1778)
						)
						(arc
							(start -0.2794 0.1778)
							(mid -0.249642 0.249642)
							(end -0.1778 0.2794)
						)
						(arc
							(start 0.1778 0.2794)
							(mid 0.249642 0.249642)
							(end 0.2794 0.1778)
						)
						(arc
							(start 0.2794 -0.1778)
							(mid 0.249642 -0.249642)
							(end 0.1778 -0.2794)
						)
					)
					(width 0)
					(fill yes)
				)
			)
		)
		(pad "2" smd custom
			(at 0 0.4445)
			(size 0.1397 0.1397)
			(layers "F.Cu" "F.Mask" "F.Paste")
			(net "SAS2X28_A_HDD9_FLT")
			(options
				(clearance outline)
				(anchor circle)
			)
			(primitives
				(gr_poly
					(pts
						(arc
							(start -0.1778 -0.2794)
							(mid -0.249642 -0.249642)
							(end -0.2794 -0.1778)
						)
						(arc
							(start -0.2794 0.1778)
							(mid -0.249642 0.249642)
							(end -0.1778 0.2794)
						)
						(arc
							(start 0.1778 0.2794)
							(mid 0.249642 0.249642)
							(end 0.2794 0.1778)
						)
						(arc
							(start 0.2794 -0.1778)
							(mid 0.249642 -0.249642)
							(end 0.1778 -0.2794)
						)
					)
					(width 0)
					(fill yes)
				)
			)
		)
	)
	(footprint ""
		(layer "F.Cu")
		(at 44.246546 -131.7879 180)
		(property "Reference" "R317"
			(at 0 0 180)
			(layer "F.SilkS")
			(hide yes)
			(effects
				(font
					(size 1.27 1.27)
				)
			)
		)
		(property "Value" "4K7R2J-2-GP"
			(at 0.064008 -3.993896 180)
			(unlocked yes)
			(layer "F.Fab")
			(hide yes)
			(effects
				(font
					(size 1.016 1.016)
					(thickness 0.1524)
				)
			)
		)
		(property "Device Type" "R402H16"
			(at 0.064008 -5.517896 180)
			(unlocked yes)
			(layer "F.Fab")
			(hide yes)
			(effects
				(font
					(size 1.016 1.016)
					(thickness 0.1524)
				)
			)
		)
		(duplicate_pad_numbers_are_jumpers no)
		(fp_line
			(start 0.508 -0.9398)
			(end -0.508 -0.9398)
			(stroke
				(width 0.1524)
				(type default)
			)
			(layer "F.SilkS")
		)
		(fp_line
			(start -0.508 -0.9398)
			(end -0.508 0.9398)
			(stroke
				(width 0.1524)
				(type default)
			)
			(layer "F.SilkS")
		)
		(fp_rect
			(start -0.508 0.9398)
			(end 0.508 -0.9398)
			(stroke
				(width 0)
				(type default)
			)
			(fill no)
			(layer "F.CrtYd")
		)
		(fp_rect
			(start -0.508 0.9398)
			(end 0.508 -0.9398)
			(stroke
				(width 0)
				(type default)
			)
			(fill no)
			(layer "F.Fab")
		)
		(pad "1" smd custom
			(at 0 -0.4445 180)
			(size 0.1397 0.1397)
			(layers "F.Cu" "F.Mask" "F.Paste")
			(net "P3V3")
			(options
				(clearance outline)
				(anchor circle)
			)
			(primitives
				(gr_poly
					(pts
						(arc
							(start -0.1778 -0.2794)
							(mid -0.249642 -0.249642)
							(end -0.2794 -0.1778)
						)
						(arc
							(start -0.2794 0.1778)
							(mid -0.249642 0.249642)
							(end -0.1778 0.2794)
						)
						(arc
							(start 0.1778 0.2794)
							(mid 0.249642 0.249642)
							(end 0.2794 0.1778)
						)
						(arc
							(start 0.2794 -0.1778)
							(mid 0.249642 -0.249642)
							(end 0.1778 -0.2794)
						)
					)
					(width 0)
					(fill yes)
				)
			)
		)
		(pad "2" smd custom
			(at 0 0.4445 180)
			(size 0.1397 0.1397)
			(layers "F.Cu" "F.Mask" "F.Paste")
			(net "I2C_B_TMP2_A0")
			(options
				(clearance outline)
				(anchor circle)
			)
			(primitives
				(gr_poly
					(pts
						(arc
							(start -0.1778 -0.2794)
							(mid -0.249642 -0.249642)
							(end -0.2794 -0.1778)
						)
						(arc
							(start -0.2794 0.1778)
							(mid -0.249642 0.249642)
							(end -0.1778 0.2794)
						)
						(arc
							(start 0.1778 0.2794)
							(mid 0.249642 0.249642)
							(end 0.2794 0.1778)
						)
						(arc
							(start 0.2794 -0.1778)
							(mid 0.249642 -0.249642)
							(end 0.1778 -0.2794)
						)
					)
					(width 0)
					(fill yes)
				)
			)
		)
	)
	(footprint ""
		(layer "F.Cu")
		(at 223.4565 -434.136546)
		(property "Reference" "U54"
			(at 0 0 0)
			(layer "F.SilkS")
			(hide yes)
			(effects
				(font
					(size 1.27 1.27)
				)
			)
		)
		(property "Value" "SY8201ABC-GP"
			(at -0.0254 -11.9634 0)
			(unlocked yes)
			(layer "F.Fab")
			(hide yes)
			(effects
				(font
					(size 1.016 1.016)
					(thickness 0.1524)
				)
			)
		)
		(property "Device Type" "SOT-6H56"
			(at -0.0254 -13.5636 0)
			(unlocked yes)
			(layer "F.Fab")
			(hide yes)
			(effects
				(font
					(size 1.016 1.016)
					(thickness 0.1524)
				)
			)
		)
		(duplicate_pad_numbers_are_jumpers no)
		(fp_line
			(start -1.9685 -0.5842)
			(end -1.9685 0.5842)
			(stroke
				(width 0.1524)
				(type default)
			)
			(layer "F.SilkS")
		)
		(fp_line
			(start -1.9685 -0.4064)
			(end -1.5621 0)
			(stroke
				(width 0.1524)
				(type default)
			)
			(layer "F.SilkS")
		)
		(fp_line
			(start -1.9685 0.5842)
			(end -1.9685 2.3622)
			(stroke
				(width 0.508)
				(type default)
			)
			(layer "F.SilkS")
		)
		(fp_line
			(start -1.9685 0.5842)
			(end 1.7145 0.5842)
			(stroke
				(width 0.1524)
				(type default)
			)
			(layer "F.SilkS")
		)
		(fp_line
			(start -1.5621 0)
			(end -1.9685 0.4064)
			(stroke
				(width 0.1524)
				(type default)
			)
			(layer "F.SilkS")
		)
		(fp_line
			(start 1.7145 -0.5842)
			(end -1.9685 -0.5842)
			(stroke
				(width 0.1524)
				(type default)
			)
			(layer "F.SilkS")
		)
		(fp_line
			(start 1.7145 0.5842)
			(end 1.7145 -0.5842)
			(stroke
				(width 0.1524)
				(type default)
			)
			(layer "F.SilkS")
		)
		(fp_poly
			(pts
				(xy -1.27 -0.635) (xy 1.27 -0.635) (xy 1.27 0.635) (xy -1.27 0.635)
			)
			(stroke
				(width 0)
				(type default)
			)
			(fill yes)
			(layer "F.SilkS")
		)
		(fp_rect
			(start -1.9685 2.3622)
			(end 1.9685 -2.3622)
			(stroke
				(width 0)
				(type default)
			)
			(fill no)
			(layer "F.CrtYd")
		)
		(fp_poly
			(pts
				(xy -1.9685 -2.3622) (xy 1.9685 -2.3622) (xy 1.9685 2.3622) (xy -1.9685 2.3622)
			)
			(stroke
				(width 0)
				(type default)
			)
			(fill no)
			(layer "F.Fab")
		)
		(pad "1" smd rect
			(at -0.9525 1.3462)
			(size 0.5842 1.016)
			(layers "F.Cu" "F.Mask" "F.Paste")
			(net "P3V3_BS_NET")
		)
		(pad "2" smd rect
			(at 0 1.3462)
			(size 0.5842 1.016)
			(layers "F.Cu" "F.Mask" "F.Paste")
			(net "GND")
		)
		(pad "3" smd rect
			(at 0.9525 1.3462)
			(size 0.5842 1.016)
			(layers "F.Cu" "F.Mask" "F.Paste")
			(net "P3V3_FB")
		)
		(pad "4" smd rect
			(at 0.9525 -1.3462)
			(size 0.5842 1.016)
			(layers "F.Cu" "F.Mask" "F.Paste")
			(net "P3V3_EN")
		)
		(pad "5" smd rect
			(at 0 -1.3462)
			(size 0.5842 1.016)
			(layers "F.Cu" "F.Mask" "F.Paste")
			(net "P3V3_IN")
		)
		(pad "6" smd rect
			(at -0.9525 -1.3462)
			(size 0.5842 1.016)
			(layers "F.Cu" "F.Mask" "F.Paste")
			(net "P3V3_LX")
		)
	)
	(footprint ""
		(layer "F.Cu")
		(at 57.7342 -384.4036 90)
		(property "Reference" "R190"
			(at 0 0 90)
			(layer "F.SilkS")
			(hide yes)
			(effects
				(font
					(size 1.27 1.27)
				)
			)
		)
		(property "Value" "2R2010J-1-GP"
			(at 0.254 -8.0772 90)
			(unlocked yes)
			(layer "F.Fab")
			(hide yes)
			(effects
				(font
					(size 1.016 1.016)
					(thickness 0.1524)
				)
			)
		)
		(property "Device Type" "R2010H28"
			(at 0.254 -9.6774 90)
			(unlocked yes)
			(layer "F.Fab")
			(hide yes)
			(effects
				(font
					(size 1.016 1.016)
					(thickness 0.1524)
				)
			)
		)
		(duplicate_pad_numbers_are_jumpers no)
		(fp_line
			(start 1.651 -3.302)
			(end -1.651 -3.302)
			(stroke
				(width 0.1524)
				(type default)
			)
			(layer "F.SilkS")
		)
		(fp_line
			(start -1.651 -3.302)
			(end -1.651 3.302)
			(stroke
				(width 0.1524)
				(type default)
			)
			(layer "F.SilkS")
		)
		(fp_line
			(start 1.651 3.302)
			(end 1.651 -3.302)
			(stroke
				(width 0.1524)
				(type default)
			)
			(layer "F.SilkS")
		)
		(fp_line
			(start -1.651 3.302)
			(end 1.651 3.302)
			(stroke
				(width 0.1524)
				(type default)
			)
			(layer "F.SilkS")
		)
		(fp_rect
			(start -1.7272 -3.3782)
			(end 1.7272 3.3782)
			(stroke
				(width 0)
				(type default)
			)
			(fill no)
			(layer "F.CrtYd")
		)
		(fp_poly
			(pts
				(xy 1.7272 3.3782) (xy 1.7272 -3.3782) (xy -1.7272 -3.3782) (xy -1.7272 3.3782)
			)
			(stroke
				(width 0)
				(type default)
			)
			(fill no)
			(layer "F.Fab")
		)
		(pad "1" smd rect
			(at 0 -2.3495 90)
			(size 2.794 1.143)
			(layers "F.Cu" "F.Mask" "F.Paste")
			(net "5V_PRE_6")
		)
		(pad "2" smd rect
			(at 0 2.3495 90)
			(size 2.794 1.143)
			(layers "F.Cu" "F.Mask" "F.Paste")
			(net "P5V_HDD6")
		)
	)
	(footprint ""
		(layer "F.Cu")
		(at 75.692 -187.325 180)
		(property "Reference" "C229"
			(at 0 0 180)
			(layer "F.SilkS")
			(hide yes)
			(effects
				(font
					(size 1.27 1.27)
				)
			)
		)
		(property "Value" "SCD1U10V2KX-5GP"
			(at 1.1811 -2.7051 180)
			(unlocked yes)
			(layer "F.Fab")
			(hide yes)
			(effects
				(font
					(size 1.016 1.016)
					(thickness 0.1524)
				)
			)
		)
		(property "Device Type" "C402H22"
			(at 1.1811 -4.2291 180)
			(unlocked yes)
			(layer "F.Fab")
			(hide yes)
			(effects
				(font
					(size 1.016 1.016)
					(thickness 0.1524)
				)
			)
		)
		(duplicate_pad_numbers_are_jumpers no)
		(fp_rect
			(start -0.4318 0.9525)
			(end 0.4318 -0.9525)
			(stroke
				(width 0)
				(type default)
			)
			(fill no)
			(layer "F.CrtYd")
		)
		(fp_rect
			(start -0.4318 0.9525)
			(end 0.4318 -0.9525)
			(stroke
				(width 0)
				(type default)
			)
			(fill no)
			(layer "F.Fab")
		)
		(pad "1" smd custom
			(at 0 -0.4445 180)
			(size 0.1524 0.1524)
			(layers "F.Cu" "F.Mask" "F.Paste")
			(net "P3V3")
			(options
				(clearance outline)
				(anchor circle)
			)
			(primitives
				(gr_poly
					(pts
						(arc
							(start 0.3048 -0.2032)
							(mid 0.275042 -0.275042)
							(end 0.2032 -0.3048)
						)
						(arc
							(start -0.2032 -0.3048)
							(mid -0.275042 -0.275042)
							(end -0.3048 -0.2032)
						)
						(arc
							(start -0.3048 0.2032)
							(mid -0.275042 0.275042)
							(end -0.2032 0.3048)
						)
						(arc
							(start 0.2032 0.3048)
							(mid 0.275042 0.275042)
							(end 0.3048 0.2032)
						)
					)
					(width 0)
					(fill yes)
				)
			)
		)
		(pad "2" smd custom
			(at 0 0.4445 180)
			(size 0.1524 0.1524)
			(layers "F.Cu" "F.Mask" "F.Paste")
			(net "GND")
			(options
				(clearance outline)
				(anchor circle)
			)
			(primitives
				(gr_poly
					(pts
						(arc
							(start 0.3048 -0.2032)
							(mid 0.275042 -0.275042)
							(end 0.2032 -0.3048)
						)
						(arc
							(start -0.2032 -0.3048)
							(mid -0.275042 -0.275042)
							(end -0.3048 -0.2032)
						)
						(arc
							(start -0.3048 0.2032)
							(mid -0.275042 0.275042)
							(end -0.2032 0.3048)
						)
						(arc
							(start 0.2032 0.3048)
							(mid 0.275042 0.275042)
							(end 0.3048 0.2032)
						)
					)
					(width 0)
					(fill yes)
				)
			)
		)
	)
	(footprint ""
		(layer "F.Cu")
		(at 176.161446 -461.044036 180)
		(property "Reference" "C352"
			(at 0 0 180)
			(layer "F.SilkS")
			(hide yes)
			(effects
				(font
					(size 1.27 1.27)
				)
			)
		)
		(property "Value" "SCD1U16V2KX-3GP"
			(at 1.1811 -2.7051 180)
			(unlocked yes)
			(layer "F.Fab")
			(hide yes)
			(effects
				(font
					(size 1.016 1.016)
					(thickness 0.1524)
				)
			)
		)
		(property "Device Type" "C402H22"
			(at 1.1811 -4.2291 180)
			(unlocked yes)
			(layer "F.Fab")
			(hide yes)
			(effects
				(font
					(size 1.016 1.016)
					(thickness 0.1524)
				)
			)
		)
		(duplicate_pad_numbers_are_jumpers no)
		(fp_rect
			(start -0.4318 0.9525)
			(end 0.4318 -0.9525)
			(stroke
				(width 0)
				(type default)
			)
			(fill no)
			(layer "F.CrtYd")
		)
		(fp_rect
			(start -0.4318 0.9525)
			(end 0.4318 -0.9525)
			(stroke
				(width 0)
				(type default)
			)
			(fill no)
			(layer "F.Fab")
		)
		(pad "1" smd custom
			(at 0 -0.4445 180)
			(size 0.1524 0.1524)
			(layers "F.Cu" "F.Mask" "F.Paste")
			(net "P3V3")
			(options
				(clearance outline)
				(anchor circle)
			)
			(primitives
				(gr_poly
					(pts
						(arc
							(start 0.3048 -0.2032)
							(mid 0.275042 -0.275042)
							(end 0.2032 -0.3048)
						)
						(arc
							(start -0.2032 -0.3048)
							(mid -0.275042 -0.275042)
							(end -0.3048 -0.2032)
						)
						(arc
							(start -0.3048 0.2032)
							(mid -0.275042 0.275042)
							(end -0.2032 0.3048)
						)
						(arc
							(start 0.2032 0.3048)
							(mid 0.275042 0.275042)
							(end 0.3048 0.2032)
						)
					)
					(width 0)
					(fill yes)
				)
			)
		)
		(pad "2" smd custom
			(at 0 0.4445 180)
			(size 0.1524 0.1524)
			(layers "F.Cu" "F.Mask" "F.Paste")
			(net "GND")
			(options
				(clearance outline)
				(anchor circle)
			)
			(primitives
				(gr_poly
					(pts
						(arc
							(start 0.3048 -0.2032)
							(mid 0.275042 -0.275042)
							(end 0.2032 -0.3048)
						)
						(arc
							(start -0.2032 -0.3048)
							(mid -0.275042 -0.275042)
							(end -0.3048 -0.2032)
						)
						(arc
							(start -0.3048 0.2032)
							(mid -0.275042 0.275042)
							(end -0.2032 0.3048)
						)
						(arc
							(start 0.2032 0.3048)
							(mid 0.275042 0.275042)
							(end 0.3048 0.2032)
						)
					)
					(width 0)
					(fill yes)
				)
			)
		)
	)
	(footprint ""
		(layer "F.Cu")
		(at 25.79243 -235.709206 90)
		(property "Reference" "C297"
			(at 0 0 90)
			(layer "F.SilkS")
			(hide yes)
			(effects
				(font
					(size 1.27 1.27)
				)
			)
		)
		(property "Value" "SCD01U50V2KX-1GP"
			(at 1.1811 -2.7051 90)
			(unlocked yes)
			(layer "F.Fab")
			(hide yes)
			(effects
				(font
					(size 1.016 1.016)
					(thickness 0.1524)
				)
			)
		)
		(property "Device Type" "C402H22"
			(at 1.1811 -4.2291 90)
			(unlocked yes)
			(layer "F.Fab")
			(hide yes)
			(effects
				(font
					(size 1.016 1.016)
					(thickness 0.1524)
				)
			)
		)
		(duplicate_pad_numbers_are_jumpers no)
		(fp_rect
			(start -0.4318 0.9525)
			(end 0.4318 -0.9525)
			(stroke
				(width 0)
				(type default)
			)
			(fill no)
			(layer "F.CrtYd")
		)
		(fp_rect
			(start -0.4318 0.9525)
			(end 0.4318 -0.9525)
			(stroke
				(width 0)
				(type default)
			)
			(fill no)
			(layer "F.Fab")
		)
		(pad "1" smd custom
			(at 0 -0.4445 90)
			(size 0.1524 0.1524)
			(layers "F.Cu" "F.Mask" "F.Paste")
			(net "SAS2X28_DRIVE_RX_P_B12")
			(options
				(clearance outline)
				(anchor circle)
			)
			(primitives
				(gr_poly
					(pts
						(arc
							(start 0.3048 -0.2032)
							(mid 0.275042 -0.275042)
							(end 0.2032 -0.3048)
						)
						(arc
							(start -0.2032 -0.3048)
							(mid -0.275042 -0.275042)
							(end -0.3048 -0.2032)
						)
						(arc
							(start -0.3048 0.2032)
							(mid -0.275042 0.275042)
							(end -0.2032 0.3048)
						)
						(arc
							(start 0.2032 0.3048)
							(mid 0.275042 0.275042)
							(end 0.3048 0.2032)
						)
					)
					(width 0)
					(fill yes)
				)
			)
		)
		(pad "2" smd custom
			(at 0 0.4445 90)
			(size 0.1524 0.1524)
			(layers "F.Cu" "F.Mask" "F.Paste")
			(net "SAS2X28_B_HDD12_RX_+")
			(options
				(clearance outline)
				(anchor circle)
			)
			(primitives
				(gr_poly
					(pts
						(arc
							(start 0.3048 -0.2032)
							(mid 0.275042 -0.275042)
							(end 0.2032 -0.3048)
						)
						(arc
							(start -0.2032 -0.3048)
							(mid -0.275042 -0.275042)
							(end -0.3048 -0.2032)
						)
						(arc
							(start -0.3048 0.2032)
							(mid -0.275042 0.275042)
							(end -0.2032 0.3048)
						)
						(arc
							(start 0.2032 0.3048)
							(mid 0.275042 0.275042)
							(end 0.3048 0.2032)
						)
					)
					(width 0)
					(fill yes)
				)
			)
		)
	)
	(footprint ""
		(layer "F.Cu")
		(at 60.2742 -374.8532 -90)
		(property "Reference" "Q58"
			(at 0 0 270)
			(layer "F.SilkS")
			(hide yes)
			(effects
				(font
					(size 1.27 1.27)
				)
			)
		)
		(property "Value" "2N7002DW-7F-GP"
			(at -2.3622 -8.2042 270)
			(unlocked yes)
			(layer "F.Fab")
			(hide yes)
			(effects
				(font
					(size 1.016 1.016)
					(thickness 0.1524)
				)
			)
		)
		(property "Device Type" "SOT-363H44"
			(at -2.3622 -10.1092 270)
			(unlocked yes)
			(layer "F.Fab")
			(hide yes)
			(effects
				(font
					(size 1.016 1.016)
					(thickness 0.1524)
				)
			)
		)
		(duplicate_pad_numbers_are_jumpers no)
		(fp_line
			(start -1.4478 1.7018)
			(end 1.4478 1.7018)
			(stroke
				(width 0.1524)
				(type default)
			)
			(layer "F.SilkS")
		)
		(fp_line
			(start 1.4478 1.7018)
			(end 1.4478 -1.7018)
			(stroke
				(width 0.1524)
				(type default)
			)
			(layer "F.SilkS")
		)
		(fp_line
			(start -1.27 1.524)
			(end -1.27 0.6604)
			(stroke
				(width 0.4826)
				(type default)
			)
			(layer "F.SilkS")
		)
		(fp_line
			(start -1.4478 -1.7018)
			(end -1.4478 1.7018)
			(stroke
				(width 0.1524)
				(type default)
			)
			(layer "F.SilkS")
		)
		(fp_line
			(start 1.4478 -1.7018)
			(end -1.4478 -1.7018)
			(stroke
				(width 0.1524)
				(type default)
			)
			(layer "F.SilkS")
		)
		(fp_poly
			(pts
				(xy -1.524 -1.778) (xy 1.524 -1.778) (xy 1.524 1.778) (xy -1.524 1.778)
			)
			(stroke
				(width 0)
				(type default)
			)
			(fill no)
			(layer "F.CrtYd")
		)
		(fp_poly
			(pts
				(xy -1.524 -1.778) (xy 1.524 -1.778) (xy 1.524 1.778) (xy -1.524 1.778)
			)
			(stroke
				(width 0)
				(type default)
			)
			(fill no)
			(layer "F.Fab")
		)
		(pad "1" smd rect
			(at -0.65024 0.9398 270)
			(size 0.4064 1.016)
			(layers "F.Cu" "F.Mask" "F.Paste")
			(net "P3V3_HDD6_LED")
		)
		(pad "2" smd rect
			(at 0 0.9398 270)
			(size 0.4064 1.016)
			(layers "F.Cu" "F.Mask" "F.Paste")
			(net "HDD6_LED_G")
		)
		(pad "3" smd rect
			(at 0.65024 0.9398 270)
			(size 0.4064 1.016)
			(layers "F.Cu" "F.Mask" "F.Paste")
			(net "P5VB")
		)
		(pad "4" smd rect
			(at 0.65024 -0.9398 270)
			(size 0.4064 1.016)
			(layers "F.Cu" "F.Mask" "F.Paste")
			(net "P5VB_HDD6_LED")
		)
		(pad "5" smd rect
			(at 0 -0.9398 270)
			(size 0.4064 1.016)
			(layers "F.Cu" "F.Mask" "F.Paste")
			(net "HDD6_LED_G")
		)
		(pad "6" smd rect
			(at -0.65024 -0.9398 270)
			(size 0.4064 1.016)
			(layers "F.Cu" "F.Mask" "F.Paste")
			(net "P3V3")
		)
	)
	(footprint ""
		(layer "F.Cu")
		(at 57.3786 -79.4766 180)
		(property "Reference" "C251"
			(at 0 0 180)
			(layer "F.SilkS")
			(hide yes)
			(effects
				(font
					(size 1.27 1.27)
				)
			)
		)
		(property "Value" "SC10U16V6KX-2GP"
			(at -0.0762 -5.1308 180)
			(unlocked yes)
			(layer "F.Fab")
			(hide yes)
			(effects
				(font
					(size 1.016 1.016)
					(thickness 0.1524)
				)
			)
		)
		(property "Device Type" "C1206H71"
			(at -0.127 -6.6548 180)
			(unlocked yes)
			(layer "F.Fab")
			(hide yes)
			(effects
				(font
					(size 1.016 1.016)
					(thickness 0.1524)
				)
			)
		)
		(duplicate_pad_numbers_are_jumpers no)
		(fp_line
			(start 1.016 2.2352)
			(end -1.016 2.2352)
			(stroke
				(width 0.1524)
				(type default)
			)
			(layer "F.SilkS")
		)
		(fp_line
			(start 1.016 0.8382)
			(end 1.016 2.2352)
			(stroke
				(width 0.1524)
				(type default)
			)
			(layer "F.SilkS")
		)
		(fp_line
			(start 1.016 -2.2352)
			(end 1.016 -0.8382)
			(stroke
				(width 0.1524)
				(type default)
			)
			(layer "F.SilkS")
		)
		(fp_line
			(start -1.016 2.2352)
			(end -1.016 0.8382)
			(stroke
				(width 0.1524)
				(type default)
			)
			(layer "F.SilkS")
		)
		(fp_line
			(start -1.016 -0.8382)
			(end -1.016 -2.2352)
			(stroke
				(width 0.1524)
				(type default)
			)
			(layer "F.SilkS")
		)
		(fp_line
			(start -1.016 -2.2352)
			(end 1.016 -2.2352)
			(stroke
				(width 0.1524)
				(type default)
			)
			(layer "F.SilkS")
		)
		(fp_rect
			(start -1.0922 2.3114)
			(end 1.0922 -2.3114)
			(stroke
				(width 0)
				(type default)
			)
			(fill no)
			(layer "F.CrtYd")
		)
		(fp_poly
			(pts
				(xy 1.0922 -2.3114) (xy 1.0922 2.3114) (xy -1.0922 2.3114) (xy -1.0922 -2.3114)
			)
			(stroke
				(width 0)
				(type default)
			)
			(fill no)
			(layer "F.Fab")
		)
		(pad "1" smd rect
			(at 0 -1.397 180)
			(size 1.651 1.27)
			(layers "F.Cu" "F.Mask" "F.Paste")
			(net "P5V_HDD9")
		)
		(pad "2" smd rect
			(at 0 1.397 180)
			(size 1.651 1.27)
			(layers "F.Cu" "F.Mask" "F.Paste")
			(net "GND")
		)
	)
	(footprint ""
		(layer "F.Cu")
		(at 235.838746 -21.7297 90)
		(property "Reference" "PU1"
			(at 0 0 90)
			(layer "F.SilkS")
			(hide yes)
			(effects
				(font
					(size 1.27 1.27)
				)
			)
		)
		(property "Value" "TPS53319DQPR-GP"
			(at 4.7498 -5.6896 90)
			(unlocked yes)
			(layer "F.Fab")
			(hide yes)
			(effects
				(font
					(size 1.016 1.016)
					(thickness 0.1524)
				)
			)
		)
		(property "Device Type" "QFN22G6050-G6133H60"
			(at 4.7498 -7.2136 90)
			(unlocked yes)
			(layer "F.Fab")
			(hide yes)
			(effects
				(font
					(size 1.016 1.016)
					(thickness 0.1524)
				)
			)
		)
		(duplicate_pad_numbers_are_jumpers no)
		(fp_line
			(start -2.286 -3.5179)
			(end -3.556 -3.5179)
			(stroke
				(width 0.1524)
				(type default)
			)
			(layer "F.SilkS")
		)
		(fp_line
			(start -3.556 -3.5179)
			(end -3.556 -2.2479)
			(stroke
				(width 0.1524)
				(type default)
			)
			(layer "F.SilkS")
		)
		(fp_line
			(start 0.500126 -3.262122)
			(end 0.500126 -3.770122)
			(stroke
				(width 0.1524)
				(type default)
			)
			(layer "F.SilkS")
		)
		(fp_line
			(start -1.999996 -3.262122)
			(end -1.999996 -4.024122)
			(stroke
				(width 0.1524)
				(type default)
			)
			(layer "F.SilkS")
		)
		(fp_line
			(start -3.556 2.2479)
			(end -3.556 3.5179)
			(stroke
				(width 0.1524)
				(type default)
			)
			(layer "F.SilkS")
		)
		(fp_line
			(start 1.500124 3.262122)
			(end 1.500124 4.024122)
			(stroke
				(width 0.1524)
				(type default)
			)
			(layer "F.SilkS")
		)
		(fp_line
			(start -0.999998 3.262122)
			(end -0.999998 3.770122)
			(stroke
				(width 0.1524)
				(type default)
			)
			(layer "F.SilkS")
		)
		(fp_line
			(start 3.556 3.5179)
			(end 3.556 2.2479)
			(stroke
				(width 0.1524)
				(type default)
			)
			(layer "F.SilkS")
		)
		(fp_line
			(start 2.286 3.5179)
			(end 3.556 3.5179)
			(stroke
				(width 0.1524)
				(type default)
			)
			(layer "F.SilkS")
		)
		(fp_line
			(start -3.556 3.5179)
			(end -2.286 3.5179)
			(stroke
				(width 0.1524)
				(type default)
			)
			(layer "F.SilkS")
		)
		(fp_poly
			(pts
				(xy 3.556 -3.5179) (xy 2.5273 -3.5179) (xy 3.556 -2.4892)
			)
			(stroke
				(width 0)
				(type default)
			)
			(fill yes)
			(layer "F.SilkS")
		)
		(fp_rect
			(start -2.9972 2.5019)
			(end 2.9972 -2.5019)
			(stroke
				(width 0)
				(type default)
			)
			(fill no)
			(layer "F.CrtYd")
		)
		(fp_poly
			(pts
				(xy 3.556 -2.5019) (xy -2.9972 -2.5019) (xy -2.9972 2.5019) (xy 2.9972 2.5019) (xy 2.9972 -2.4892)
				(xy 3.556 -2.4892) (xy 3.556 3.5179) (xy -3.556 3.5179) (xy -3.556 -3.5179) (xy 3.556 -3.5179)
			)
			(stroke
				(width 0)
				(type default)
			)
			(fill no)
			(layer "F.CrtYd")
		)
		(fp_rect
			(start -3.556 3.5179)
			(end 3.556 -3.5179)
			(stroke
				(width 0)
				(type default)
			)
			(fill no)
			(layer "F.Fab")
		)
		(pad "1" smd rect
			(at 2.500122 -2.449322 90)
			(size 0.3048 1.1176)
			(layers "F.Cu" "F.Mask" "F.Paste")
			(net "P5VA_VFB")
		)
		(pad "2" smd rect
			(at 1.999996 -2.449322 90)
			(size 0.3048 1.1176)
			(layers "F.Cu" "F.Mask" "F.Paste")
			(net "P5VA_EN")
		)
		(pad "3" smd rect
			(at 1.500124 -2.449322 90)
			(size 0.3048 1.1176)
			(layers "F.Cu" "F.Mask" "F.Paste")
			(net "P5VA_PGD")
		)
		(pad "4" smd rect
			(at 0.999998 -2.449322 90)
			(size 0.3048 1.1176)
			(layers "F.Cu" "F.Mask" "F.Paste")
			(net "P5VA_VBST")
		)
		(pad "5" smd rect
			(at 0.500126 -2.449322 90)
			(size 0.3048 1.1176)
			(layers "F.Cu" "F.Mask" "F.Paste")
			(net "P5VA_ROVP")
		)
		(pad "6" smd rect
			(at 0 -2.449322 90)
			(size 0.3048 1.1176)
			(layers "F.Cu" "F.Mask" "F.Paste")
			(net "P5VA_LL")
		)
		(pad "7" smd rect
			(at -0.500126 -2.449322 90)
			(size 0.3048 1.1176)
			(layers "F.Cu" "F.Mask" "F.Paste")
			(net "P5VA_LL")
		)
		(pad "8" smd rect
			(at -0.999998 -2.449322 90)
			(size 0.3048 1.1176)
			(layers "F.Cu" "F.Mask" "F.Paste")
			(net "P5VA_LL")
		)
		(pad "9" smd rect
			(at -1.500124 -2.449322 90)
			(size 0.3048 1.1176)
			(layers "F.Cu" "F.Mask" "F.Paste")
			(net "P5VA_LL")
		)
		(pad "10" smd rect
			(at -1.999996 -2.449322 90)
			(size 0.3048 1.1176)
			(layers "F.Cu" "F.Mask" "F.Paste")
			(net "P5VA_LL")
		)
		(pad "11" smd rect
			(at -2.500122 -2.449322 90)
			(size 0.3048 1.1176)
			(layers "F.Cu" "F.Mask" "F.Paste")
			(net "P5VA_LL")
		)
		(pad "12" smd rect
			(at -2.500122 2.449322 90)
			(size 0.3048 1.1176)
			(layers "F.Cu" "F.Mask" "F.Paste")
			(net "P5VA_12VIN")
		)
		(pad "13" smd rect
			(at -1.999996 2.449322 90)
			(size 0.3048 1.1176)
			(layers "F.Cu" "F.Mask" "F.Paste")
			(net "P5VA_12VIN")
		)
		(pad "14" smd rect
			(at -1.500124 2.449322 90)
			(size 0.3048 1.1176)
			(layers "F.Cu" "F.Mask" "F.Paste")
			(net "P5VA_12VIN")
		)
		(pad "15" smd rect
			(at -0.999998 2.449322 90)
			(size 0.3048 1.1176)
			(layers "F.Cu" "F.Mask" "F.Paste")
			(net "P5VA_12VIN")
		)
		(pad "16" smd rect
			(at -0.500126 2.449322 90)
			(size 0.3048 1.1176)
			(layers "F.Cu" "F.Mask" "F.Paste")
			(net "P5VA_12VIN")
		)
		(pad "17" smd rect
			(at 0 2.449322 90)
			(size 0.3048 1.1176)
			(layers "F.Cu" "F.Mask" "F.Paste")
			(net "P5VA_12VIN")
		)
		(pad "18" smd rect
			(at 0.500126 2.449322 90)
			(size 0.3048 1.1176)
			(layers "F.Cu" "F.Mask" "F.Paste")
			(net "P5VA_VREG")
		)
		(pad "19" smd rect
			(at 0.999998 2.449322 90)
			(size 0.3048 1.1176)
			(layers "F.Cu" "F.Mask" "F.Paste")
			(net "P5VA_VDD")
		)
		(pad "20" smd rect
			(at 1.500124 2.449322 90)
			(size 0.3048 1.1176)
			(layers "F.Cu" "F.Mask" "F.Paste")
			(net "P5VA_MODE")
		)
		(pad "21" smd rect
			(at 1.999996 2.449322 90)
			(size 0.3048 1.1176)
			(layers "F.Cu" "F.Mask" "F.Paste")
			(net "P5VA_TRIP")
		)
		(pad "22" smd rect
			(at 2.500122 2.449322 90)
			(size 0.3048 1.1176)
			(layers "F.Cu" "F.Mask" "F.Paste")
			(net "P5VA_RF")
		)
		(pad "23" smd custom
			(at 0 0 90)
			(size 0.83185 0.83185)
			(layers "F.Cu" "F.Mask" "F.Paste")
			(net "GND")
			(options
				(clearance outline)
				(anchor circle)
			)
			(primitives
				(gr_poly
					(pts
						(xy -2.7813 1.6637) (xy -2.7813 1.2954) (xy -3.048 1.2954) (xy -3.048 0.9525) (xy -2.7813 0.9525)
						(xy -2.7813 -0.9525) (xy -3.048 -0.9525) (xy -3.048 -1.2954) (xy -2.7813 -1.2954) (xy -2.7813 -1.6637)
						(xy 2.7813 -1.6637) (xy 2.7813 -1.2954) (xy 3.048 -1.2954) (xy 3.048 -0.9525) (xy 2.7813 -0.9525)
						(xy 2.7813 0.9525) (xy 3.048 0.9525) (xy 3.048 1.2954) (xy 2.7813 1.2954) (xy 2.7813 1.6637)
					)
					(width 0)
					(fill yes)
				)
			)
		)
	)
	(footprint ""
		(layer "F.Cu")
		(at 26.55443 -242.059206 90)
		(property "Reference" "C295"
			(at 0 0 90)
			(layer "F.SilkS")
			(hide yes)
			(effects
				(font
					(size 1.27 1.27)
				)
			)
		)
		(property "Value" "SCD01U50V2KX-1GP"
			(at 1.1811 -2.7051 90)
			(unlocked yes)
			(layer "F.Fab")
			(hide yes)
			(effects
				(font
					(size 1.016 1.016)
					(thickness 0.1524)
				)
			)
		)
		(property "Device Type" "C402H22"
			(at 1.1811 -4.2291 90)
			(unlocked yes)
			(layer "F.Fab")
			(hide yes)
			(effects
				(font
					(size 1.016 1.016)
					(thickness 0.1524)
				)
			)
		)
		(duplicate_pad_numbers_are_jumpers no)
		(fp_rect
			(start -0.4318 0.9525)
			(end 0.4318 -0.9525)
			(stroke
				(width 0)
				(type default)
			)
			(fill no)
			(layer "F.CrtYd")
		)
		(fp_rect
			(start -0.4318 0.9525)
			(end 0.4318 -0.9525)
			(stroke
				(width 0)
				(type default)
			)
			(fill no)
			(layer "F.Fab")
		)
		(pad "1" smd custom
			(at 0 -0.4445 90)
			(size 0.1524 0.1524)
			(layers "F.Cu" "F.Mask" "F.Paste")
			(net "SAS2X28_DRIVE_RX_P_A12")
			(options
				(clearance outline)
				(anchor circle)
			)
			(primitives
				(gr_poly
					(pts
						(arc
							(start 0.3048 -0.2032)
							(mid 0.275042 -0.275042)
							(end 0.2032 -0.3048)
						)
						(arc
							(start -0.2032 -0.3048)
							(mid -0.275042 -0.275042)
							(end -0.3048 -0.2032)
						)
						(arc
							(start -0.3048 0.2032)
							(mid -0.275042 0.275042)
							(end -0.2032 0.3048)
						)
						(arc
							(start 0.2032 0.3048)
							(mid 0.275042 0.275042)
							(end 0.3048 0.2032)
						)
					)
					(width 0)
					(fill yes)
				)
			)
		)
		(pad "2" smd custom
			(at 0 0.4445 90)
			(size 0.1524 0.1524)
			(layers "F.Cu" "F.Mask" "F.Paste")
			(net "SAS2X28_A_HDD12_RX_+")
			(options
				(clearance outline)
				(anchor circle)
			)
			(primitives
				(gr_poly
					(pts
						(arc
							(start 0.3048 -0.2032)
							(mid 0.275042 -0.275042)
							(end 0.2032 -0.3048)
						)
						(arc
							(start -0.2032 -0.3048)
							(mid -0.275042 -0.275042)
							(end -0.3048 -0.2032)
						)
						(arc
							(start -0.3048 0.2032)
							(mid -0.275042 0.275042)
							(end -0.2032 0.3048)
						)
						(arc
							(start 0.2032 0.3048)
							(mid 0.275042 0.275042)
							(end 0.3048 0.2032)
						)
					)
					(width 0)
					(fill yes)
				)
			)
		)
	)
	(footprint ""
		(layer "F.Cu")
		(at 45.338746 -145.3007 90)
		(property "Reference" "R212"
			(at 0 0 90)
			(layer "F.SilkS")
			(hide yes)
			(effects
				(font
					(size 1.27 1.27)
				)
			)
		)
		(property "Value" "10KR2F-2-GP"
			(at 0.064008 -3.993896 90)
			(unlocked yes)
			(layer "F.Fab")
			(hide yes)
			(effects
				(font
					(size 1.016 1.016)
					(thickness 0.1524)
				)
			)
		)
		(property "Device Type" "R402H16"
			(at 0.064008 -5.517896 90)
			(unlocked yes)
			(layer "F.Fab")
			(hide yes)
			(effects
				(font
					(size 1.016 1.016)
					(thickness 0.1524)
				)
			)
		)
		(duplicate_pad_numbers_are_jumpers no)
		(fp_line
			(start 0.508 -0.9398)
			(end -0.508 -0.9398)
			(stroke
				(width 0.1524)
				(type default)
			)
			(layer "F.SilkS")
		)
		(fp_line
			(start -0.508 -0.9398)
			(end -0.508 0.9398)
			(stroke
				(width 0.1524)
				(type default)
			)
			(layer "F.SilkS")
		)
		(fp_rect
			(start -0.508 0.9398)
			(end 0.508 -0.9398)
			(stroke
				(width 0)
				(type default)
			)
			(fill no)
			(layer "F.CrtYd")
		)
		(fp_rect
			(start -0.508 0.9398)
			(end 0.508 -0.9398)
			(stroke
				(width 0)
				(type default)
			)
			(fill no)
			(layer "F.Fab")
		)
		(pad "1" smd custom
			(at 0 -0.4445 90)
			(size 0.1397 0.1397)
			(layers "F.Cu" "F.Mask" "F.Paste")
			(net "P5VB")
			(options
				(clearance outline)
				(anchor circle)
			)
			(primitives
				(gr_poly
					(pts
						(arc
							(start -0.1778 -0.2794)
							(mid -0.249642 -0.249642)
							(end -0.2794 -0.1778)
						)
						(arc
							(start -0.2794 0.1778)
							(mid -0.249642 0.249642)
							(end -0.1778 0.2794)
						)
						(arc
							(start 0.1778 0.2794)
							(mid 0.249642 0.249642)
							(end 0.2794 0.1778)
						)
						(arc
							(start 0.2794 -0.1778)
							(mid 0.249642 -0.249642)
							(end 0.1778 -0.2794)
						)
					)
					(width 0)
					(fill yes)
				)
			)
		)
		(pad "2" smd custom
			(at 0 0.4445 90)
			(size 0.1397 0.1397)
			(layers "F.Cu" "F.Mask" "F.Paste")
			(net "DRIVE_ACT_8")
			(options
				(clearance outline)
				(anchor circle)
			)
			(primitives
				(gr_poly
					(pts
						(arc
							(start -0.1778 -0.2794)
							(mid -0.249642 -0.249642)
							(end -0.2794 -0.1778)
						)
						(arc
							(start -0.2794 0.1778)
							(mid -0.249642 0.249642)
							(end -0.1778 0.2794)
						)
						(arc
							(start 0.1778 0.2794)
							(mid 0.249642 0.249642)
							(end 0.2794 0.1778)
						)
						(arc
							(start 0.2794 -0.1778)
							(mid 0.249642 -0.249642)
							(end 0.1778 -0.2794)
						)
					)
					(width 0)
					(fill yes)
				)
			)
		)
	)
	(footprint ""
		(layer "F.Cu")
		(at 223.418654 -438.7723 90)
		(property "Reference" "PR52"
			(at 0 0 90)
			(layer "F.SilkS")
			(hide yes)
			(effects
				(font
					(size 1.27 1.27)
				)
			)
		)
		(property "Value" "2MR2F-GP"
			(at 0.064008 -3.993896 90)
			(unlocked yes)
			(layer "F.Fab")
			(hide yes)
			(effects
				(font
					(size 1.016 1.016)
					(thickness 0.1524)
				)
			)
		)
		(property "Device Type" "R402H16"
			(at 0.064008 -5.517896 90)
			(unlocked yes)
			(layer "F.Fab")
			(hide yes)
			(effects
				(font
					(size 1.016 1.016)
					(thickness 0.1524)
				)
			)
		)
		(duplicate_pad_numbers_are_jumpers no)
		(fp_line
			(start 0.508 -0.9398)
			(end -0.508 -0.9398)
			(stroke
				(width 0.1524)
				(type default)
			)
			(layer "F.SilkS")
		)
		(fp_line
			(start -0.508 -0.9398)
			(end -0.508 0.9398)
			(stroke
				(width 0.1524)
				(type default)
			)
			(layer "F.SilkS")
		)
		(fp_rect
			(start -0.508 0.9398)
			(end 0.508 -0.9398)
			(stroke
				(width 0)
				(type default)
			)
			(fill no)
			(layer "F.CrtYd")
		)
		(fp_rect
			(start -0.508 0.9398)
			(end 0.508 -0.9398)
			(stroke
				(width 0)
				(type default)
			)
			(fill no)
			(layer "F.Fab")
		)
		(pad "1" smd custom
			(at 0 -0.4445 90)
			(size 0.1397 0.1397)
			(layers "F.Cu" "F.Mask" "F.Paste")
			(net "P3V3_IN")
			(options
				(clearance outline)
				(anchor circle)
			)
			(primitives
				(gr_poly
					(pts
						(arc
							(start -0.1778 -0.2794)
							(mid -0.249642 -0.249642)
							(end -0.2794 -0.1778)
						)
						(arc
							(start -0.2794 0.1778)
							(mid -0.249642 0.249642)
							(end -0.1778 0.2794)
						)
						(arc
							(start 0.1778 0.2794)
							(mid 0.249642 0.249642)
							(end 0.2794 0.1778)
						)
						(arc
							(start 0.2794 -0.1778)
							(mid 0.249642 -0.249642)
							(end 0.1778 -0.2794)
						)
					)
					(width 0)
					(fill yes)
				)
			)
		)
		(pad "2" smd custom
			(at 0 0.4445 90)
			(size 0.1397 0.1397)
			(layers "F.Cu" "F.Mask" "F.Paste")
			(net "P3V3_EN")
			(options
				(clearance outline)
				(anchor circle)
			)
			(primitives
				(gr_poly
					(pts
						(arc
							(start -0.1778 -0.2794)
							(mid -0.249642 -0.249642)
							(end -0.2794 -0.1778)
						)
						(arc
							(start -0.2794 0.1778)
							(mid -0.249642 0.249642)
							(end -0.1778 0.2794)
						)
						(arc
							(start 0.1778 0.2794)
							(mid 0.249642 0.249642)
							(end 0.2794 0.1778)
						)
						(arc
							(start 0.2794 -0.1778)
							(mid 0.249642 -0.249642)
							(end 0.1778 -0.2794)
						)
					)
					(width 0)
					(fill yes)
				)
			)
		)
	)
	(footprint ""
		(layer "F.Cu")
		(at 34.543746 -107.470702 90)
		(property "Reference" "R472"
			(at 0 0 90)
			(layer "F.SilkS")
			(hide yes)
			(effects
				(font
					(size 1.27 1.27)
				)
			)
		)
		(property "Value" "4K7R2J-2-GP"
			(at 0.064008 -3.993896 90)
			(unlocked yes)
			(layer "F.Fab")
			(hide yes)
			(effects
				(font
					(size 1.016 1.016)
					(thickness 0.1524)
				)
			)
		)
		(property "Device Type" "R402H16"
			(at 0.064008 -5.517896 90)
			(unlocked yes)
			(layer "F.Fab")
			(hide yes)
			(effects
				(font
					(size 1.016 1.016)
					(thickness 0.1524)
				)
			)
		)
		(duplicate_pad_numbers_are_jumpers no)
		(fp_line
			(start 0.508 -0.9398)
			(end -0.508 -0.9398)
			(stroke
				(width 0.1524)
				(type default)
			)
			(layer "F.SilkS")
		)
		(fp_line
			(start -0.508 -0.9398)
			(end -0.508 0.9398)
			(stroke
				(width 0.1524)
				(type default)
			)
			(layer "F.SilkS")
		)
		(fp_rect
			(start -0.508 0.9398)
			(end 0.508 -0.9398)
			(stroke
				(width 0)
				(type default)
			)
			(fill no)
			(layer "F.CrtYd")
		)
		(fp_rect
			(start -0.508 0.9398)
			(end 0.508 -0.9398)
			(stroke
				(width 0)
				(type default)
			)
			(fill no)
			(layer "F.Fab")
		)
		(pad "1" smd custom
			(at 0 -0.4445 90)
			(size 0.1397 0.1397)
			(layers "F.Cu" "F.Mask" "F.Paste")
			(net "P3V3")
			(options
				(clearance outline)
				(anchor circle)
			)
			(primitives
				(gr_poly
					(pts
						(arc
							(start -0.1778 -0.2794)
							(mid -0.249642 -0.249642)
							(end -0.2794 -0.1778)
						)
						(arc
							(start -0.2794 0.1778)
							(mid -0.249642 0.249642)
							(end -0.1778 0.2794)
						)
						(arc
							(start 0.1778 0.2794)
							(mid 0.249642 0.249642)
							(end 0.2794 0.1778)
						)
						(arc
							(start 0.2794 -0.1778)
							(mid 0.249642 -0.249642)
							(end 0.1778 -0.2794)
						)
					)
					(width 0)
					(fill yes)
				)
			)
		)
		(pad "2" smd custom
			(at 0 0.4445 90)
			(size 0.1397 0.1397)
			(layers "F.Cu" "F.Mask" "F.Paste")
			(net "SAS_EXP_A_PWR13")
			(options
				(clearance outline)
				(anchor circle)
			)
			(primitives
				(gr_poly
					(pts
						(arc
							(start -0.1778 -0.2794)
							(mid -0.249642 -0.249642)
							(end -0.2794 -0.1778)
						)
						(arc
							(start -0.2794 0.1778)
							(mid -0.249642 0.249642)
							(end -0.1778 0.2794)
						)
						(arc
							(start 0.1778 0.2794)
							(mid 0.249642 0.249642)
							(end 0.2794 0.1778)
						)
						(arc
							(start 0.2794 -0.1778)
							(mid 0.249642 -0.249642)
							(end 0.1778 -0.2794)
						)
					)
					(width 0)
					(fill yes)
				)
			)
		)
	)
	(footprint ""
		(layer "F.Cu")
		(at 27.888946 -281.7368 90)
		(property "Reference" "Q16"
			(at 0 0 90)
			(layer "F.SilkS")
			(hide yes)
			(effects
				(font
					(size 1.27 1.27)
				)
			)
		)
		(property "Value" "2N7002DW-7F-GP"
			(at -2.3622 -8.2042 90)
			(unlocked yes)
			(layer "F.Fab")
			(hide yes)
			(effects
				(font
					(size 1.016 1.016)
					(thickness 0.1524)
				)
			)
		)
		(property "Device Type" "SOT-363H44"
			(at -2.3622 -10.1092 90)
			(unlocked yes)
			(layer "F.Fab")
			(hide yes)
			(effects
				(font
					(size 1.016 1.016)
					(thickness 0.1524)
				)
			)
		)
		(duplicate_pad_numbers_are_jumpers no)
		(fp_line
			(start 1.4478 -1.7018)
			(end -1.4478 -1.7018)
			(stroke
				(width 0.1524)
				(type default)
			)
			(layer "F.SilkS")
		)
		(fp_line
			(start -1.4478 -1.7018)
			(end -1.4478 1.7018)
			(stroke
				(width 0.1524)
				(type default)
			)
			(layer "F.SilkS")
		)
		(fp_line
			(start -1.27 1.524)
			(end -1.27 0.6604)
			(stroke
				(width 0.4826)
				(type default)
			)
			(layer "F.SilkS")
		)
		(fp_line
			(start 1.4478 1.7018)
			(end 1.4478 -1.7018)
			(stroke
				(width 0.1524)
				(type default)
			)
			(layer "F.SilkS")
		)
		(fp_line
			(start -1.4478 1.7018)
			(end 1.4478 1.7018)
			(stroke
				(width 0.1524)
				(type default)
			)
			(layer "F.SilkS")
		)
		(fp_poly
			(pts
				(xy -1.524 -1.778) (xy 1.524 -1.778) (xy 1.524 1.778) (xy -1.524 1.778)
			)
			(stroke
				(width 0)
				(type default)
			)
			(fill no)
			(layer "F.CrtYd")
		)
		(fp_poly
			(pts
				(xy -1.524 -1.778) (xy 1.524 -1.778) (xy 1.524 1.778) (xy -1.524 1.778)
			)
			(stroke
				(width 0)
				(type default)
			)
			(fill no)
			(layer "F.Fab")
		)
		(pad "1" smd rect
			(at -0.65024 0.9398 90)
			(size 0.4064 1.016)
			(layers "F.Cu" "F.Mask" "F.Paste")
			(net "GND")
		)
		(pad "2" smd rect
			(at 0 0.9398 90)
			(size 0.4064 1.016)
			(layers "F.Cu" "F.Mask" "F.Paste")
			(net "SW_PWR_R_HDD7")
		)
		(pad "3" smd rect
			(at 0.65024 0.9398 90)
			(size 0.4064 1.016)
			(layers "F.Cu" "F.Mask" "F.Paste")
			(net "SW_HDD7_P")
		)
		(pad "4" smd rect
			(at 0.65024 -0.9398 90)
			(size 0.4064 1.016)
			(layers "F.Cu" "F.Mask" "F.Paste")
			(net "GND")
		)
		(pad "5" smd rect
			(at 0 -0.9398 90)
			(size 0.4064 1.016)
			(layers "F.Cu" "F.Mask" "F.Paste")
			(net "SW_HDD7_G")
		)
		(pad "6" smd rect
			(at -0.65024 -0.9398 90)
			(size 0.4064 1.016)
			(layers "F.Cu" "F.Mask" "F.Paste")
			(net "SW_HDD7_R")
		)
	)
	(footprint ""
		(layer "F.Cu")
		(at 80.391 -403.098 -90)
		(property "Reference" "R193"
			(at 0 0 270)
			(layer "F.SilkS")
			(hide yes)
			(effects
				(font
					(size 1.27 1.27)
				)
			)
		)
		(property "Value" "4K7R2J-2-GP"
			(at 0.064008 -3.993896 270)
			(unlocked yes)
			(layer "F.Fab")
			(hide yes)
			(effects
				(font
					(size 1.016 1.016)
					(thickness 0.1524)
				)
			)
		)
		(property "Device Type" "R402H16"
			(at 0.064008 -5.517896 270)
			(unlocked yes)
			(layer "F.Fab")
			(hide yes)
			(effects
				(font
					(size 1.016 1.016)
					(thickness 0.1524)
				)
			)
		)
		(duplicate_pad_numbers_are_jumpers no)
		(fp_line
			(start -0.508 -0.9398)
			(end -0.508 0.9398)
			(stroke
				(width 0.1524)
				(type default)
			)
			(layer "F.SilkS")
		)
		(fp_line
			(start 0.508 -0.9398)
			(end -0.508 -0.9398)
			(stroke
				(width 0.1524)
				(type default)
			)
			(layer "F.SilkS")
		)
		(fp_rect
			(start -0.508 0.9398)
			(end 0.508 -0.9398)
			(stroke
				(width 0)
				(type default)
			)
			(fill no)
			(layer "F.CrtYd")
		)
		(fp_rect
			(start -0.508 0.9398)
			(end 0.508 -0.9398)
			(stroke
				(width 0)
				(type default)
			)
			(fill no)
			(layer "F.Fab")
		)
		(pad "1" smd custom
			(at 0 -0.4445 270)
			(size 0.1397 0.1397)
			(layers "F.Cu" "F.Mask" "F.Paste")
			(net "P12V")
			(options
				(clearance outline)
				(anchor circle)
			)
			(primitives
				(gr_poly
					(pts
						(arc
							(start -0.1778 -0.2794)
							(mid -0.249642 -0.249642)
							(end -0.2794 -0.1778)
						)
						(arc
							(start -0.2794 0.1778)
							(mid -0.249642 0.249642)
							(end -0.1778 0.2794)
						)
						(arc
							(start 0.1778 0.2794)
							(mid 0.249642 0.249642)
							(end 0.2794 0.1778)
						)
						(arc
							(start 0.2794 -0.1778)
							(mid 0.249642 -0.249642)
							(end 0.1778 -0.2794)
						)
					)
					(width 0)
					(fill yes)
				)
			)
		)
		(pad "2" smd custom
			(at 0 0.4445 270)
			(size 0.1397 0.1397)
			(layers "F.Cu" "F.Mask" "F.Paste")
			(net "SW_HDD6_R")
			(options
				(clearance outline)
				(anchor circle)
			)
			(primitives
				(gr_poly
					(pts
						(arc
							(start -0.1778 -0.2794)
							(mid -0.249642 -0.249642)
							(end -0.2794 -0.1778)
						)
						(arc
							(start -0.2794 0.1778)
							(mid -0.249642 0.249642)
							(end -0.1778 0.2794)
						)
						(arc
							(start 0.1778 0.2794)
							(mid 0.249642 0.249642)
							(end 0.2794 0.1778)
						)
						(arc
							(start 0.2794 -0.1778)
							(mid 0.249642 -0.249642)
							(end 0.1778 -0.2794)
						)
					)
					(width 0)
					(fill yes)
				)
			)
		)
	)
	(footprint ""
		(layer "F.Cu")
		(at 19.05 -397.9926)
		(property "Reference" "R481"
			(at 0 0 0)
			(layer "F.SilkS")
			(hide yes)
			(effects
				(font
					(size 1.27 1.27)
				)
			)
		)
		(property "Value" "0R2J-2-GP"
			(at 0.064008 -3.993896 0)
			(unlocked yes)
			(layer "F.Fab")
			(hide yes)
			(effects
				(font
					(size 1.016 1.016)
					(thickness 0.1524)
				)
			)
		)
		(property "Device Type" "R402H16"
			(at 0.064008 -5.517896 0)
			(unlocked yes)
			(layer "F.Fab")
			(hide yes)
			(effects
				(font
					(size 1.016 1.016)
					(thickness 0.1524)
				)
			)
		)
		(duplicate_pad_numbers_are_jumpers no)
		(fp_line
			(start -0.508 -0.9398)
			(end -0.508 0.9398)
			(stroke
				(width 0.1524)
				(type default)
			)
			(layer "F.SilkS")
		)
		(fp_line
			(start 0.508 -0.9398)
			(end -0.508 -0.9398)
			(stroke
				(width 0.1524)
				(type default)
			)
			(layer "F.SilkS")
		)
		(fp_rect
			(start -0.508 0.9398)
			(end 0.508 -0.9398)
			(stroke
				(width 0)
				(type default)
			)
			(fill no)
			(layer "F.CrtYd")
		)
		(fp_rect
			(start -0.508 0.9398)
			(end 0.508 -0.9398)
			(stroke
				(width 0)
				(type default)
			)
			(fill no)
			(layer "F.Fab")
		)
		(pad "1" smd custom
			(at 0 -0.4445)
			(size 0.1397 0.1397)
			(layers "F.Cu" "F.Mask" "F.Paste")
			(net "I2C_C_SCL_DAMP_A")
			(options
				(clearance outline)
				(anchor circle)
			)
			(primitives
				(gr_poly
					(pts
						(arc
							(start -0.1778 -0.2794)
							(mid -0.249642 -0.249642)
							(end -0.2794 -0.1778)
						)
						(arc
							(start -0.2794 0.1778)
							(mid -0.249642 0.249642)
							(end -0.1778 0.2794)
						)
						(arc
							(start 0.1778 0.2794)
							(mid 0.249642 0.249642)
							(end 0.2794 0.1778)
						)
						(arc
							(start 0.2794 -0.1778)
							(mid 0.249642 -0.249642)
							(end 0.1778 -0.2794)
						)
					)
					(width 0)
					(fill yes)
				)
			)
		)
		(pad "2" smd custom
			(at 0 0.4445)
			(size 0.1397 0.1397)
			(layers "F.Cu" "F.Mask" "F.Paste")
			(net "I2C_C_SCL")
			(options
				(clearance outline)
				(anchor circle)
			)
			(primitives
				(gr_poly
					(pts
						(arc
							(start -0.1778 -0.2794)
							(mid -0.249642 -0.249642)
							(end -0.2794 -0.1778)
						)
						(arc
							(start -0.2794 0.1778)
							(mid -0.249642 0.249642)
							(end -0.1778 0.2794)
						)
						(arc
							(start 0.1778 0.2794)
							(mid 0.249642 0.249642)
							(end 0.2794 0.1778)
						)
						(arc
							(start 0.2794 -0.1778)
							(mid 0.249642 -0.249642)
							(end 0.1778 -0.2794)
						)
					)
					(width 0)
					(fill yes)
				)
			)
		)
	)
	(footprint ""
		(layer "F.Cu")
		(at 2.500122 -355.998526 -90)
		(property "Reference" "CN1"
			(at 0 0 270)
			(layer "F.SilkS")
			(hide yes)
			(effects
				(font
					(size 1.27 1.27)
				)
			)
		)
		(property "Value" "PCISLT164-70-GP"
			(at -77.8764 -6.4262 270)
			(unlocked yes)
			(layer "F.Fab")
			(hide yes)
			(effects
				(font
					(size 1.016 1.016)
					(thickness 0.1524)
				)
			)
		)
		(property "Device Type" "G630EAA12048EU"
			(at -77.8764 -7.9502 270)
			(unlocked yes)
			(layer "F.Fab")
			(hide yes)
			(effects
				(font
					(size 1.016 1.016)
					(thickness 0.1524)
				)
			)
		)
		(duplicate_pad_numbers_are_jumpers no)
		(fp_line
			(start -79.6544 2.500122)
			(end -1.450086 2.500122)
			(stroke
				(width 0.1524)
				(type default)
			)
			(layer "F.SilkS")
		)
		(fp_line
			(start -1.450086 2.500122)
			(end -0.94996 1.999996)
			(stroke
				(width 0.1524)
				(type default)
			)
			(layer "F.SilkS")
		)
		(fp_line
			(start 1.450086 2.500122)
			(end 19.6596 2.500122)
			(stroke
				(width 0.1524)
				(type default)
			)
			(layer "F.SilkS")
		)
		(fp_line
			(start 19.6596 2.500122)
			(end 19.6596 -4.064)
			(stroke
				(width 0.1524)
				(type default)
			)
			(layer "F.SilkS")
		)
		(fp_line
			(start -0.94996 1.999996)
			(end -0.94996 -2.55016)
			(stroke
				(width 0.1524)
				(type default)
			)
			(layer "F.SilkS")
		)
		(fp_line
			(start 0.94996 1.999996)
			(end 1.450086 2.500122)
			(stroke
				(width 0.1524)
				(type default)
			)
			(layer "F.SilkS")
		)
		(fp_line
			(start 0.94996 -2.55016)
			(end 0.94996 1.999996)
			(stroke
				(width 0.1524)
				(type default)
			)
			(layer "F.SilkS")
		)
		(fp_line
			(start -72.644 -2.7432)
			(end -72.644 -4.064)
			(stroke
				(width 0.1524)
				(type default)
			)
			(layer "F.SilkS")
		)
		(fp_line
			(start 12.6492 -2.7432)
			(end -72.644 -2.7432)
			(stroke
				(width 0.1524)
				(type default)
			)
			(layer "F.SilkS")
		)
		(fp_line
			(start 11.0617 -2.8321)
			(end 11.9634 -2.8321)
			(stroke
				(width 0.3302)
				(type default)
			)
			(layer "F.SilkS")
		)
		(fp_line
			(start -79.6544 -4.064)
			(end -79.6544 2.500122)
			(stroke
				(width 0.1524)
				(type default)
			)
			(layer "F.SilkS")
		)
		(fp_line
			(start -72.644 -4.064)
			(end -79.6544 -4.064)
			(stroke
				(width 0.1524)
				(type default)
			)
			(layer "F.SilkS")
		)
		(fp_line
			(start 12.6492 -4.064)
			(end 12.6492 -2.7432)
			(stroke
				(width 0.1524)
				(type default)
			)
			(layer "F.SilkS")
		)
		(fp_line
			(start 19.6596 -4.064)
			(end 12.6492 -4.064)
			(stroke
				(width 0.1524)
				(type default)
			)
			(layer "F.SilkS")
		)
		(fp_arc
			(start -0.94996 -2.55016)
			(mid 0 -3.50012)
			(end 0.94996 -2.55016)
			(stroke
				(width 0.1524)
				(type default)
			)
			(layer "F.SilkS")
		)
		(fp_poly
			(pts
				(xy 12.0904 -3.4544) (xy 10.8204 -3.4544) (xy 11.4554 -2.8194)
			)
			(stroke
				(width 0)
				(type default)
			)
			(fill yes)
			(layer "F.SilkS")
		)
		(fp_poly
			(pts
				(xy -74.4982 12.7508) (xy -74.4982 4.8006) (xy -79.4004 4.8006) (xy -79.4004 -3.81) (xy -72.898 -3.81)
				(xy -72.898 -1.6002) (xy 12.9032 -1.6002) (xy 12.9032 -3.81) (xy 19.4056 -3.81) (xy 19.4056 4.8006)
				(xy 14.5034 4.8006) (xy 14.5034 12.7508)
			)
			(stroke
				(width 0)
				(type default)
			)
			(fill no)
			(layer "B.CrtYd")
		)
		(fp_poly
			(pts
				(xy -75.0062 13.2588) (xy -75.0062 5.3086) (xy -79.9084 5.3086) (xy -79.9084 -4.318) (xy -72.39 -4.318)
				(xy -72.39 -2.9972) (xy 12.3952 -2.9972) (xy 12.3952 -4.318) (xy 19.9136 -4.318) (xy 19.9136 -0.00254)
				(xy 19.4056 -0.00254) (xy 19.4056 -3.81) (xy 12.9032 -3.81) (xy 12.9032 -1.6002) (xy -72.898 -1.6002)
				(xy -72.898 -3.81) (xy -79.4004 -3.81) (xy -79.4004 4.8006) (xy -74.4982 4.8006) (xy -74.4982 12.7508)
				(xy 14.5034 12.7508) (xy 14.5034 4.8006) (xy 19.4056 4.8006) (xy 19.4056 0.00254) (xy 19.9136 0.00254)
				(xy 19.9136 5.3086) (xy 15.0114 5.3086) (xy 15.0114 13.2588)
			)
			(stroke
				(width 0)
				(type default)
			)
			(fill no)
			(layer "B.CrtYd")
		)
		(fp_poly
			(pts
				(xy -74.4982 12.7508) (xy -74.4982 4.8006) (xy -79.4004 4.8006) (xy -79.4004 -3.81) (xy -72.898 -3.81)
				(xy -72.898 -1.6002) (xy 12.9032 -1.6002) (xy 12.9032 -3.81) (xy 19.4056 -3.81) (xy 19.4056 4.8006)
				(xy 14.5034 4.8006) (xy 14.5034 12.7508)
			)
			(stroke
				(width 0)
				(type default)
			)
			(fill no)
			(layer "F.CrtYd")
		)
		(fp_poly
			(pts
				(xy -75.0062 13.2588) (xy -75.0062 5.3086) (xy -79.9084 5.3086) (xy -79.9084 -4.318) (xy -72.39 -4.318)
				(xy -72.39 -2.9972) (xy 12.3952 -2.9972) (xy 12.3952 -4.318) (xy 19.9136 -4.318) (xy 19.9136 -0.00254)
				(xy 19.4056 -0.00254) (xy 19.4056 -3.81) (xy 12.9032 -3.81) (xy 12.9032 -1.6002) (xy -72.898 -1.6002)
				(xy -72.898 -3.81) (xy -79.4004 -3.81) (xy -79.4004 4.8006) (xy -74.4982 4.8006) (xy -74.4982 12.7508)
				(xy 14.5034 12.7508) (xy 14.5034 4.8006) (xy 19.4056 4.8006) (xy 19.4056 0.00254) (xy 19.9136 0.00254)
				(xy 19.9136 5.3086) (xy 15.0114 5.3086) (xy 15.0114 13.2588)
			)
			(stroke
				(width 0)
				(type default)
			)
			(fill no)
			(layer "F.CrtYd")
		)
		(fp_poly
			(pts
				(xy -75.0062 13.2588) (xy -75.0062 5.3086) (xy -79.9084 5.3086) (xy -79.9084 -4.318) (xy -72.39 -4.318)
				(xy -72.39 -2.9972) (xy 12.3952 -2.9972) (xy 12.3952 -4.318) (xy 19.9136 -4.318) (xy 19.9136 5.3086)
				(xy 15.0114 5.3086) (xy 15.0114 13.2588)
			)
			(stroke
				(width 0)
				(type default)
			)
			(fill no)
			(layer "B.Fab")
		)
		(fp_poly
			(pts
				(xy -75.0062 13.2588) (xy -75.0062 5.3086) (xy -79.9084 5.3086) (xy -79.9084 -4.318) (xy -72.39 -4.318)
				(xy -72.39 -2.9972) (xy 12.3952 -2.9972) (xy 12.3952 -4.318) (xy 19.9136 -4.318) (xy 19.9136 5.3086)
				(xy 15.0114 5.3086) (xy 15.0114 13.2588)
			)
			(stroke
				(width 0)
				(type default)
			)
			(fill no)
			(layer "F.Fab")
		)
		(fp_text user "Slit"
			(at -25.4 5.17525 270)
			(unlocked yes)
			(layer "F.SilkS")
			(effects
				(font
					(size 0.635 0.635)
					(thickness 0.1524)
				)
				(justify left)
			)
		)
		(fp_text user "02 Do not mirror"
			(at -18.667476 -4.535678 90)
			(unlocked yes)
			(layer "F.Fab")
			(effects
				(font
					(size 1.016 1.016)
					(thickness 0.1524)
				)
				(justify left)
			)
		)
		(pad "" np_thru_hole circle
			(at -76.300076 0 270)
			(size 0.254 0.254)
			(drill 2.3114)
			(layers "*.Cu" "*.Mask")
			(clearance 1.3843)
			(thermal_gap 1.3843)
		)
		(pad "" np_thru_hole circle
			(at 16.299942 0 270)
			(size 0.254 0.254)
			(drill 2.3114)
			(layers "*.Cu" "*.Mask")
			(clearance 1.3843)
			(thermal_gap 1.3843)
		)
		(pad "A1" smd rect
			(at 11.500104 -0.311404 270)
			(size 0.7112 3.6068)
			(drill
				(offset 0 -0.381)
			)
			(layers "F.Cu" "F.Mask" "F.Paste")
			(net "GND")
		)
		(pad "A2" smd rect
			(at 10.500106 -0.311404 270)
			(size 0.7112 3.6068)
			(drill
				(offset 0 -0.381)
			)
			(layers "F.Cu" "F.Mask" "F.Paste")
			(net "SAS2X28_A_HDD11_RX_+")
		)
		(pad "A3" smd rect
			(at 9.500108 -0.311404 270)
			(size 0.7112 3.6068)
			(drill
				(offset 0 -0.381)
			)
			(layers "F.Cu" "F.Mask" "F.Paste")
			(net "SAS2X28_A_HDD11_RX_-")
		)
		(pad "A4" smd rect
			(at 8.50011 -0.311404 270)
			(size 0.7112 3.6068)
			(drill
				(offset 0 -0.381)
			)
			(layers "F.Cu" "F.Mask" "F.Paste")
			(net "GND")
		)
		(pad "A5" smd rect
			(at 7.500112 -0.311404 270)
			(size 0.7112 3.6068)
			(drill
				(offset 0 -0.381)
			)
			(layers "F.Cu" "F.Mask" "F.Paste")
			(net "GND")
		)
		(pad "A6" smd rect
			(at 6.500114 -0.311404 270)
			(size 0.7112 3.6068)
			(drill
				(offset 0 -0.381)
			)
			(layers "F.Cu" "F.Mask" "F.Paste")
			(net "SAS2X28_A_HDD12_RX_+")
		)
		(pad "A7" smd rect
			(at 5.500116 -0.311404 270)
			(size 0.7112 3.6068)
			(drill
				(offset 0 -0.381)
			)
			(layers "F.Cu" "F.Mask" "F.Paste")
			(net "SAS2X28_A_HDD12_RX_-")
		)
		(pad "A8" smd rect
			(at 4.500118 -0.311404 270)
			(size 0.7112 3.6068)
			(drill
				(offset 0 -0.381)
			)
			(layers "F.Cu" "F.Mask" "F.Paste")
			(net "GND")
		)
		(pad "A9" smd rect
			(at 3.50012 -0.311404 270)
			(size 0.7112 3.6068)
			(drill
				(offset 0 -0.381)
			)
			(layers "F.Cu" "F.Mask" "F.Paste")
			(net "GND")
		)
		(pad "A10" smd rect
			(at 2.500122 -0.311404 270)
			(size 0.7112 3.6068)
			(drill
				(offset 0 -0.381)
			)
			(layers "F.Cu" "F.Mask" "F.Paste")
			(net "SAS2X28_A_HDD13_RX_+")
		)
		(pad "A11" smd rect
			(at 1.500124 -0.311404 270)
			(size 0.7112 3.6068)
			(drill
				(offset 0 -0.381)
			)
			(layers "F.Cu" "F.Mask" "F.Paste")
			(net "SAS2X28_A_HDD13_RX_-")
		)
		(pad "A12" smd rect
			(at -1.500124 -0.311404 270)
			(size 0.7112 3.6068)
			(drill
				(offset 0 -0.381)
			)
			(layers "F.Cu" "F.Mask" "F.Paste")
			(net "TRAY_ID")
		)
		(pad "A13" smd rect
			(at -2.500376 -0.311404 270)
			(size 0.7112 3.6068)
			(drill
				(offset 0 -0.381)
			)
			(layers "F.Cu" "F.Mask" "F.Paste")
			(net "GND")
		)
		(pad "A14" smd rect
			(at -3.500374 -0.311404 270)
			(size 0.7112 3.6068)
			(drill
				(offset 0 -0.381)
			)
			(layers "F.Cu" "F.Mask" "F.Paste")
			(net "SAS2X28_A_HDD14_RX_+")
		)
		(pad "A15" smd rect
			(at -4.500372 -0.311404 270)
			(size 0.7112 3.6068)
			(drill
				(offset 0 -0.381)
			)
			(layers "F.Cu" "F.Mask" "F.Paste")
			(net "SAS2X28_A_HDD14_RX_-")
		)
		(pad "A16" smd rect
			(at -5.50037 -0.311404 270)
			(size 0.7112 3.6068)
			(drill
				(offset 0 -0.381)
			)
			(layers "F.Cu" "F.Mask" "F.Paste")
			(net "GND")
		)
		(pad "A17" smd rect
			(at -6.500368 -0.311404 270)
			(size 0.7112 3.6068)
			(drill
				(offset 0 -0.381)
			)
			(layers "F.Cu" "F.Mask" "F.Paste")
			(net "GND")
		)
		(pad "A18" smd rect
			(at -7.500366 -0.311404 270)
			(size 0.7112 3.6068)
			(drill
				(offset 0 -0.381)
			)
			(layers "F.Cu" "F.Mask" "F.Paste")
			(net "SAS2X28_A_HDD9_RX_+")
		)
		(pad "A19" smd rect
			(at -8.500364 -0.311404 270)
			(size 0.7112 3.6068)
			(drill
				(offset 0 -0.381)
			)
			(layers "F.Cu" "F.Mask" "F.Paste")
			(net "SAS2X28_A_HDD9_RX_-")
		)
		(pad "A20" smd rect
			(at -9.500362 -0.311404 270)
			(size 0.7112 3.6068)
			(drill
				(offset 0 -0.381)
			)
			(layers "F.Cu" "F.Mask" "F.Paste")
			(net "GND")
		)
		(pad "A21" smd rect
			(at -10.50036 -0.311404 270)
			(size 0.7112 3.6068)
			(drill
				(offset 0 -0.381)
			)
			(layers "F.Cu" "F.Mask" "F.Paste")
			(net "GND")
		)
		(pad "A22" smd rect
			(at -11.500358 -0.311404 270)
			(size 0.7112 3.6068)
			(drill
				(offset 0 -0.381)
			)
			(layers "F.Cu" "F.Mask" "F.Paste")
			(net "SAS2X28_A_HDD8_RX_+")
		)
		(pad "A23" smd rect
			(at -12.500356 -0.311404 270)
			(size 0.7112 3.6068)
			(drill
				(offset 0 -0.381)
			)
			(layers "F.Cu" "F.Mask" "F.Paste")
			(net "SAS2X28_A_HDD8_RX_-")
		)
		(pad "A24" smd rect
			(at -13.500354 -0.311404 270)
			(size 0.7112 3.6068)
			(drill
				(offset 0 -0.381)
			)
			(layers "F.Cu" "F.Mask" "F.Paste")
			(net "GND")
		)
		(pad "A25" smd rect
			(at -14.500352 -0.311404 270)
			(size 0.7112 3.6068)
			(drill
				(offset 0 -0.381)
			)
			(layers "F.Cu" "F.Mask" "F.Paste")
			(net "GND")
		)
		(pad "A26" smd rect
			(at -15.50035 -0.311404 270)
			(size 0.7112 3.6068)
			(drill
				(offset 0 -0.381)
			)
			(layers "F.Cu" "F.Mask" "F.Paste")
			(net "SAS2X28_A_HDD7_RX_+")
		)
		(pad "A27" smd rect
			(at -16.500348 -0.311404 270)
			(size 0.7112 3.6068)
			(drill
				(offset 0 -0.381)
			)
			(layers "F.Cu" "F.Mask" "F.Paste")
			(net "SAS2X28_A_HDD7_RX_-")
		)
		(pad "A28" smd rect
			(at -17.500346 -0.311404 270)
			(size 0.7112 3.6068)
			(drill
				(offset 0 -0.381)
			)
			(layers "F.Cu" "F.Mask" "F.Paste")
			(net "GND")
		)
		(pad "A29" smd rect
			(at -18.500344 -0.311404 270)
			(size 0.7112 3.6068)
			(drill
				(offset 0 -0.381)
			)
			(layers "F.Cu" "F.Mask" "F.Paste")
			(net "GND")
		)
		(pad "A30" smd rect
			(at -19.500342 -0.311404 270)
			(size 0.7112 3.6068)
			(drill
				(offset 0 -0.381)
			)
			(layers "F.Cu" "F.Mask" "F.Paste")
			(net "SAS2X28_A_HDD4_RX_+")
		)
		(pad "A31" smd rect
			(at -20.50034 -0.311404 270)
			(size 0.7112 3.6068)
			(drill
				(offset 0 -0.381)
			)
			(layers "F.Cu" "F.Mask" "F.Paste")
			(net "SAS2X28_A_HDD4_RX_-")
		)
		(pad "A32" smd rect
			(at -21.500338 -0.311404 270)
			(size 0.7112 3.6068)
			(drill
				(offset 0 -0.381)
			)
			(layers "F.Cu" "F.Mask" "F.Paste")
			(net "GND")
		)
		(pad "A33" smd rect
			(at -22.500336 -0.311404 270)
			(size 0.7112 3.6068)
			(drill
				(offset 0 -0.381)
			)
			(layers "F.Cu" "F.Mask" "F.Paste")
			(net "GND")
		)
		(pad "A34" smd rect
			(at -23.500334 -0.311404 270)
			(size 0.7112 3.6068)
			(drill
				(offset 0 -0.381)
			)
			(layers "F.Cu" "F.Mask" "F.Paste")
			(net "SAS2X28_A_HDD3_RX_+")
		)
		(pad "A35" smd rect
			(at -24.500332 -0.311404 270)
			(size 0.7112 3.6068)
			(drill
				(offset 0 -0.381)
			)
			(layers "F.Cu" "F.Mask" "F.Paste")
			(net "SAS2X28_A_HDD3_RX_-")
		)
		(pad "A36" smd rect
			(at -25.50033 -0.311404 270)
			(size 0.7112 3.6068)
			(drill
				(offset 0 -0.381)
			)
			(layers "F.Cu" "F.Mask" "F.Paste")
			(net "GND")
		)
		(pad "A37" smd rect
			(at -26.500328 -0.311404 270)
			(size 0.7112 3.6068)
			(drill
				(offset 0 -0.381)
			)
			(layers "F.Cu" "F.Mask" "F.Paste")
			(net "GND")
		)
		(pad "A38" smd rect
			(at -27.500326 -0.311404 270)
			(size 0.7112 3.6068)
			(drill
				(offset 0 -0.381)
			)
			(layers "F.Cu" "F.Mask" "F.Paste")
			(net "SAS2X28_A_HDD6_RX_+")
		)
		(pad "A39" smd rect
			(at -28.500324 -0.311404 270)
			(size 0.7112 3.6068)
			(drill
				(offset 0 -0.381)
			)
			(layers "F.Cu" "F.Mask" "F.Paste")
			(net "SAS2X28_A_HDD6_RX_-")
		)
		(pad "A40" smd rect
			(at -29.500322 -0.311404 270)
			(size 0.7112 3.6068)
			(drill
				(offset 0 -0.381)
			)
			(layers "F.Cu" "F.Mask" "F.Paste")
			(net "GND")
		)
		(pad "A41" smd rect
			(at -30.50032 -0.311404 270)
			(size 0.7112 3.6068)
			(drill
				(offset 0 -0.381)
			)
			(layers "F.Cu" "F.Mask" "F.Paste")
			(net "SD_LATCH_RELEASE")
		)
		(pad "A42" smd rect
			(at -31.500318 -0.311404 270)
			(size 0.7112 3.6068)
			(drill
				(offset 0 -0.381)
			)
			(layers "F.Cu" "F.Mask" "F.Paste")
			(net "SAS2X28_A_HDD12_FLT")
		)
		(pad "A43" smd rect
			(at -32.500316 -0.311404 270)
			(size 0.7112 3.6068)
			(drill
				(offset 0 -0.381)
			)
			(layers "F.Cu" "F.Mask" "F.Paste")
			(net "SAS2X28_A_HDD11_FLT")
		)
		(pad "A44" smd rect
			(at -33.500314 -0.311404 270)
			(size 0.7112 3.6068)
			(drill
				(offset 0 -0.381)
			)
			(layers "F.Cu" "F.Mask" "F.Paste")
			(net "SAS2X28_A_HDD13_FLT")
		)
		(pad "A45" smd rect
			(at -34.500312 -0.311404 270)
			(size 0.7112 3.6068)
			(drill
				(offset 0 -0.381)
			)
			(layers "F.Cu" "F.Mask" "F.Paste")
			(net "SAS2X28_A_HDD14_FLT")
		)
		(pad "A46" smd rect
			(at -35.50031 -0.311404 270)
			(size 0.7112 3.6068)
			(drill
				(offset 0 -0.381)
			)
			(layers "F.Cu" "F.Mask" "F.Paste")
			(net "SAS2X28_A_HDD9_FLT")
		)
		(pad "A47" smd rect
			(at -36.500308 -0.311404 270)
			(size 0.7112 3.6068)
			(drill
				(offset 0 -0.381)
			)
			(layers "F.Cu" "F.Mask" "F.Paste")
			(net "SAS2X28_A_HDD8_FLT")
		)
		(pad "A48" smd rect
			(at -37.500306 -0.311404 270)
			(size 0.7112 3.6068)
			(drill
				(offset 0 -0.381)
			)
			(layers "F.Cu" "F.Mask" "F.Paste")
			(net "SAS2X28_A_HDD7_FLT")
		)
		(pad "A49" smd rect
			(at -38.500304 -0.311404 270)
			(size 0.7112 3.6068)
			(drill
				(offset 0 -0.381)
			)
			(layers "F.Cu" "F.Mask" "F.Paste")
			(net "SAS2X28_A_HDD4_FLT")
		)
		(pad "A50" smd rect
			(at -39.500302 -0.311404 270)
			(size 0.7112 3.6068)
			(drill
				(offset 0 -0.381)
			)
			(layers "F.Cu" "F.Mask" "F.Paste")
			(net "SAS2X28_A_HDD3_FLT")
		)
		(pad "A51" smd rect
			(at -40.5003 -0.311404 270)
			(size 0.7112 3.6068)
			(drill
				(offset 0 -0.381)
			)
			(layers "F.Cu" "F.Mask" "F.Paste")
			(net "GND")
		)
		(pad "A52" smd rect
			(at -41.500298 -0.311404 270)
			(size 0.7112 3.6068)
			(drill
				(offset 0 -0.381)
			)
			(layers "F.Cu" "F.Mask" "F.Paste")
			(net "SAS2X28_A_HDD2_RX_+")
		)
		(pad "A53" smd rect
			(at -42.500296 -0.311404 270)
			(size 0.7112 3.6068)
			(drill
				(offset 0 -0.381)
			)
			(layers "F.Cu" "F.Mask" "F.Paste")
			(net "SAS2X28_A_HDD2_RX_-")
		)
		(pad "A54" smd rect
			(at -43.500294 -0.311404 270)
			(size 0.7112 3.6068)
			(drill
				(offset 0 -0.381)
			)
			(layers "F.Cu" "F.Mask" "F.Paste")
			(net "GND")
		)
		(pad "A55" smd rect
			(at -44.500292 -0.311404 270)
			(size 0.7112 3.6068)
			(drill
				(offset 0 -0.381)
			)
			(layers "F.Cu" "F.Mask" "F.Paste")
			(net "I2C_C_SCL_DAMP_A")
		)
		(pad "A56" smd rect
			(at -45.50029 -0.311404 270)
			(size 0.7112 3.6068)
			(drill
				(offset 0 -0.381)
			)
			(layers "F.Cu" "F.Mask" "F.Paste")
			(net "I2C_C_SDA_DAMP_A")
		)
		(pad "A57" smd rect
			(at -46.500288 -0.311404 270)
			(size 0.7112 3.6068)
			(drill
				(offset 0 -0.381)
			)
			(layers "F.Cu" "F.Mask" "F.Paste")
			(net "I2C_D_SCL_DAMP_A")
		)
		(pad "A58" smd rect
			(at -47.500286 -0.311404 270)
			(size 0.7112 3.6068)
			(drill
				(offset 0 -0.381)
			)
			(layers "F.Cu" "F.Mask" "F.Paste")
			(net "I2C_D_SDA_DAMP_A")
		)
		(pad "A59" smd rect
			(at -48.500284 -0.311404 270)
			(size 0.7112 3.6068)
			(drill
				(offset 0 -0.381)
			)
			(layers "F.Cu" "F.Mask" "F.Paste")
			(net "GND")
		)
		(pad "A60" smd rect
			(at -49.500282 -0.311404 270)
			(size 0.7112 3.6068)
			(drill
				(offset 0 -0.381)
			)
			(layers "F.Cu" "F.Mask" "F.Paste")
			(net "SAS2X28_A_HDD1_RX_+")
		)
		(pad "A61" smd rect
			(at -50.50028 -0.311404 270)
			(size 0.7112 3.6068)
			(drill
				(offset 0 -0.381)
			)
			(layers "F.Cu" "F.Mask" "F.Paste")
			(net "SAS2X28_A_HDD1_RX_-")
		)
		(pad "A62" smd rect
			(at -51.500278 -0.311404 270)
			(size 0.7112 3.6068)
			(drill
				(offset 0 -0.381)
			)
			(layers "F.Cu" "F.Mask" "F.Paste")
			(net "GND")
		)
		(pad "A63" smd rect
			(at -52.500276 -0.311404 270)
			(size 0.7112 3.6068)
			(drill
				(offset 0 -0.381)
			)
			(layers "F.Cu" "F.Mask" "F.Paste")
			(net "GND")
		)
		(pad "A64" smd rect
			(at -53.500274 -0.311404 270)
			(size 0.7112 3.6068)
			(drill
				(offset 0 -0.381)
			)
			(layers "F.Cu" "F.Mask" "F.Paste")
			(net "SAS2X28_A_HDD10_RX_+")
		)
		(pad "A65" smd rect
			(at -54.500272 -0.311404 270)
			(size 0.7112 3.6068)
			(drill
				(offset 0 -0.381)
			)
			(layers "F.Cu" "F.Mask" "F.Paste")
			(net "SAS2X28_A_HDD10_RX_-")
		)
		(pad "A66" smd rect
			(at -55.50027 -0.311404 270)
			(size 0.7112 3.6068)
			(drill
				(offset 0 -0.381)
			)
			(layers "F.Cu" "F.Mask" "F.Paste")
			(net "GND")
		)
		(pad "A67" smd rect
			(at -56.500268 -0.311404 270)
			(size 0.7112 3.6068)
			(drill
				(offset 0 -0.381)
			)
			(layers "F.Cu" "F.Mask" "F.Paste")
			(net "GND")
		)
		(pad "A68" smd rect
			(at -57.500266 -0.311404 270)
			(size 0.7112 3.6068)
			(drill
				(offset 0 -0.381)
			)
			(layers "F.Cu" "F.Mask" "F.Paste")
			(net "SAS2X28_A_HDD0_RX_+")
		)
		(pad "A69" smd rect
			(at -58.500264 -0.311404 270)
			(size 0.7112 3.6068)
			(drill
				(offset 0 -0.381)
			)
			(layers "F.Cu" "F.Mask" "F.Paste")
			(net "SAS2X28_A_HDD0_RX_-")
		)
		(pad "A70" smd rect
			(at -59.500262 -0.311404 270)
			(size 0.7112 3.6068)
			(drill
				(offset 0 -0.381)
			)
			(layers "F.Cu" "F.Mask" "F.Paste")
			(net "GND")
		)
		(pad "A71" smd rect
			(at -60.50026 -0.311404 270)
			(size 0.7112 3.6068)
			(drill
				(offset 0 -0.381)
			)
			(layers "F.Cu" "F.Mask" "F.Paste")
			(net "GND")
		)
		(pad "A72" smd rect
			(at -61.500258 -0.311404 270)
			(size 0.7112 3.6068)
			(drill
				(offset 0 -0.381)
			)
			(layers "F.Cu" "F.Mask" "F.Paste")
			(net "SAS2X28_A_HDD5_RX_+")
		)
		(pad "A73" smd rect
			(at -62.500256 -0.311404 270)
			(size 0.7112 3.6068)
			(drill
				(offset 0 -0.381)
			)
			(layers "F.Cu" "F.Mask" "F.Paste")
			(net "SAS2X28_A_HDD5_RX_-")
		)
		(pad "A74" smd rect
			(at -63.500254 -0.311404 270)
			(size 0.7112 3.6068)
			(drill
				(offset 0 -0.381)
			)
			(layers "F.Cu" "F.Mask" "F.Paste")
			(net "GND")
		)
		(pad "A75" smd rect
			(at -64.500252 -0.311404 270)
			(size 0.7112 3.6068)
			(drill
				(offset 0 -0.381)
			)
			(layers "F.Cu" "F.Mask" "F.Paste")
			(net "GND")
		)
		(pad "A76" smd rect
			(at -65.50025 -0.311404 270)
			(size 0.7112 3.6068)
			(drill
				(offset 0 -0.381)
			)
			(layers "F.Cu" "F.Mask" "F.Paste")
			(net "SEB_BA_RX+")
		)
		(pad "A77" smd rect
			(at -66.500248 -0.311404 270)
			(size 0.7112 3.6068)
			(drill
				(offset 0 -0.381)
			)
			(layers "F.Cu" "F.Mask" "F.Paste")
			(net "SEB_BA_RX-")
		)
		(pad "A78" smd rect
			(at -67.500246 -0.311404 270)
			(size 0.7112 3.6068)
			(drill
				(offset 0 -0.381)
			)
			(layers "F.Cu" "F.Mask" "F.Paste")
			(net "GND")
		)
		(pad "A79" smd rect
			(at -68.500244 -0.311404 270)
			(size 0.7112 3.6068)
			(drill
				(offset 0 -0.381)
			)
			(layers "F.Cu" "F.Mask" "F.Paste")
			(net "PEER_1B&2B_HB")
		)
		(pad "A80" smd rect
			(at -69.500242 -0.311404 270)
			(size 0.7112 3.6068)
			(drill
				(offset 0 -0.381)
			)
			(layers "F.Cu" "F.Mask" "F.Paste")
			(net "P12V")
		)
		(pad "A81" smd rect
			(at -70.50024 -0.311404 270)
			(size 0.7112 3.6068)
			(drill
				(offset 0 -0.381)
			)
			(layers "F.Cu" "F.Mask" "F.Paste")
			(net "P12V")
		)
		(pad "A82" smd rect
			(at -71.500238 -0.311404 270)
			(size 0.7112 3.6068)
			(drill
				(offset 0 -0.381)
			)
			(layers "F.Cu" "F.Mask" "F.Paste")
			(net "P12V")
		)
		(pad "B1" smd rect
			(at 11.500104 -0.692404 270)
			(size 0.7112 3.6068)
			(layers "F.Cu" "F.Mask" "F.Paste")
			(net "SAS2X28_A_PRSNT15")
		)
		(pad "B2" smd rect
			(at 10.500106 -0.692404 270)
			(size 0.7112 3.6068)
			(layers "F.Cu" "F.Mask" "F.Paste")
			(net "FCB_HW_REV")
		)
		(pad "B3" smd rect
			(at 9.500108 -0.692404 270)
			(size 0.7112 3.6068)
			(layers "F.Cu" "F.Mask" "F.Paste")
			(net "GND")
		)
		(pad "B4" smd rect
			(at 8.50011 -0.692404 270)
			(size 0.7112 3.6068)
			(layers "F.Cu" "F.Mask" "F.Paste")
			(net "SAS2X28_A_HDD11_TX_+")
		)
		(pad "B5" smd rect
			(at 7.500112 -0.692404 270)
			(size 0.7112 3.6068)
			(layers "F.Cu" "F.Mask" "F.Paste")
			(net "SAS2X28_A_HDD11_TX_-")
		)
		(pad "B6" smd rect
			(at 6.500114 -0.692404 270)
			(size 0.7112 3.6068)
			(layers "F.Cu" "F.Mask" "F.Paste")
			(net "GND")
		)
		(pad "B7" smd rect
			(at 5.500116 -0.692404 270)
			(size 0.7112 3.6068)
			(layers "F.Cu" "F.Mask" "F.Paste")
			(net "GND")
		)
		(pad "B8" smd rect
			(at 4.500118 -0.692404 270)
			(size 0.7112 3.6068)
			(layers "F.Cu" "F.Mask" "F.Paste")
			(net "SAS2X28_A_HDD12_TX_+")
		)
		(pad "B9" smd rect
			(at 3.50012 -0.692404 270)
			(size 0.7112 3.6068)
			(layers "F.Cu" "F.Mask" "F.Paste")
			(net "SAS2X28_A_HDD12_TX_-")
		)
		(pad "B10" smd rect
			(at 2.500122 -0.692404 270)
			(size 0.7112 3.6068)
			(layers "F.Cu" "F.Mask" "F.Paste")
			(net "GND")
		)
		(pad "B11" smd rect
			(at 1.500124 -0.692404 270)
			(size 0.7112 3.6068)
			(layers "F.Cu" "F.Mask" "F.Paste")
			(net "DPB_HW_REV")
		)
		(pad "B12" smd rect
			(at -1.500124 -0.692404 270)
			(size 0.7112 3.6068)
			(layers "F.Cu" "F.Mask" "F.Paste")
			(net "SAS2X28_A_HDD13_TX_+")
		)
		(pad "B13" smd rect
			(at -2.500376 -0.692404 270)
			(size 0.7112 3.6068)
			(layers "F.Cu" "F.Mask" "F.Paste")
			(net "SAS2X28_A_HDD13_TX_-")
		)
		(pad "B14" smd rect
			(at -3.500374 -0.692404 270)
			(size 0.7112 3.6068)
			(layers "F.Cu" "F.Mask" "F.Paste")
			(net "GND")
		)
		(pad "B15" smd rect
			(at -4.500372 -0.692404 270)
			(size 0.7112 3.6068)
			(layers "F.Cu" "F.Mask" "F.Paste")
			(net "GND")
		)
		(pad "B16" smd rect
			(at -5.50037 -0.692404 270)
			(size 0.7112 3.6068)
			(layers "F.Cu" "F.Mask" "F.Paste")
			(net "SAS2X28_A_HDD14_TX_+")
		)
		(pad "B17" smd rect
			(at -6.500368 -0.692404 270)
			(size 0.7112 3.6068)
			(layers "F.Cu" "F.Mask" "F.Paste")
			(net "SAS2X28_A_HDD14_TX_-")
		)
		(pad "B18" smd rect
			(at -7.500366 -0.692404 270)
			(size 0.7112 3.6068)
			(layers "F.Cu" "F.Mask" "F.Paste")
			(net "GND")
		)
		(pad "B19" smd rect
			(at -8.500364 -0.692404 270)
			(size 0.7112 3.6068)
			(layers "F.Cu" "F.Mask" "F.Paste")
			(net "GND")
		)
		(pad "B20" smd rect
			(at -9.500362 -0.692404 270)
			(size 0.7112 3.6068)
			(layers "F.Cu" "F.Mask" "F.Paste")
			(net "SAS2X28_A_HDD9_TX_+")
		)
		(pad "B21" smd rect
			(at -10.50036 -0.692404 270)
			(size 0.7112 3.6068)
			(layers "F.Cu" "F.Mask" "F.Paste")
			(net "SAS2X28_A_HDD9_TX_-")
		)
		(pad "B22" smd rect
			(at -11.500358 -0.692404 270)
			(size 0.7112 3.6068)
			(layers "F.Cu" "F.Mask" "F.Paste")
			(net "GND")
		)
		(pad "B23" smd rect
			(at -12.500356 -0.692404 270)
			(size 0.7112 3.6068)
			(layers "F.Cu" "F.Mask" "F.Paste")
			(net "GND")
		)
		(pad "B24" smd rect
			(at -13.500354 -0.692404 270)
			(size 0.7112 3.6068)
			(layers "F.Cu" "F.Mask" "F.Paste")
			(net "SAS2X28_A_HDD8_TX_+")
		)
		(pad "B25" smd rect
			(at -14.500352 -0.692404 270)
			(size 0.7112 3.6068)
			(layers "F.Cu" "F.Mask" "F.Paste")
			(net "SAS2X28_A_HDD8_TX_-")
		)
		(pad "B26" smd rect
			(at -15.50035 -0.692404 270)
			(size 0.7112 3.6068)
			(layers "F.Cu" "F.Mask" "F.Paste")
			(net "GND")
		)
		(pad "B27" smd rect
			(at -16.500348 -0.692404 270)
			(size 0.7112 3.6068)
			(layers "F.Cu" "F.Mask" "F.Paste")
			(net "GND")
		)
		(pad "B28" smd rect
			(at -17.500346 -0.692404 270)
			(size 0.7112 3.6068)
			(layers "F.Cu" "F.Mask" "F.Paste")
			(net "SAS2X28_A_HDD7_TX_+")
		)
		(pad "B29" smd rect
			(at -18.500344 -0.692404 270)
			(size 0.7112 3.6068)
			(layers "F.Cu" "F.Mask" "F.Paste")
			(net "SAS2X28_A_HDD7_TX_-")
		)
		(pad "B30" smd rect
			(at -19.500342 -0.692404 270)
			(size 0.7112 3.6068)
			(layers "F.Cu" "F.Mask" "F.Paste")
			(net "GND")
		)
		(pad "B31" smd rect
			(at -20.50034 -0.692404 270)
			(size 0.7112 3.6068)
			(layers "F.Cu" "F.Mask" "F.Paste")
			(net "GND")
		)
		(pad "B32" smd rect
			(at -21.500338 -0.692404 270)
			(size 0.7112 3.6068)
			(layers "F.Cu" "F.Mask" "F.Paste")
			(net "SAS2X28_A_HDD4_TX_+")
		)
		(pad "B33" smd rect
			(at -22.500336 -0.692404 270)
			(size 0.7112 3.6068)
			(layers "F.Cu" "F.Mask" "F.Paste")
			(net "SAS2X28_A_HDD4_TX_-")
		)
		(pad "B34" smd rect
			(at -23.500334 -0.692404 270)
			(size 0.7112 3.6068)
			(layers "F.Cu" "F.Mask" "F.Paste")
			(net "GND")
		)
		(pad "B35" smd rect
			(at -24.500332 -0.692404 270)
			(size 0.7112 3.6068)
			(layers "F.Cu" "F.Mask" "F.Paste")
			(net "GND")
		)
		(pad "B36" smd rect
			(at -25.50033 -0.692404 270)
			(size 0.7112 3.6068)
			(layers "F.Cu" "F.Mask" "F.Paste")
			(net "SAS2X28_A_HDD3_TX_+")
		)
		(pad "B37" smd rect
			(at -26.500328 -0.692404 270)
			(size 0.7112 3.6068)
			(layers "F.Cu" "F.Mask" "F.Paste")
			(net "SAS2X28_A_HDD3_TX_-")
		)
		(pad "B38" smd rect
			(at -27.500326 -0.692404 270)
			(size 0.7112 3.6068)
			(layers "F.Cu" "F.Mask" "F.Paste")
			(net "GND")
		)
		(pad "B39" smd rect
			(at -28.500324 -0.692404 270)
			(size 0.7112 3.6068)
			(layers "F.Cu" "F.Mask" "F.Paste")
			(net "GND")
		)
		(pad "B40" smd rect
			(at -29.500322 -0.692404 270)
			(size 0.7112 3.6068)
			(layers "F.Cu" "F.Mask" "F.Paste")
			(net "SAS2X28_A_HDD6_TX_+")
		)
		(pad "B41" smd rect
			(at -30.50032 -0.692404 270)
			(size 0.7112 3.6068)
			(layers "F.Cu" "F.Mask" "F.Paste")
			(net "SAS2X28_A_HDD6_TX_-")
		)
		(pad "B42" smd rect
			(at -31.500318 -0.692404 270)
			(size 0.7112 3.6068)
			(layers "F.Cu" "F.Mask" "F.Paste")
			(net "GND")
		)
		(pad "B43" smd rect
			(at -32.500316 -0.692404 270)
			(size 0.7112 3.6068)
			(layers "F.Cu" "F.Mask" "F.Paste")
			(net "SAS2X28_A_HDD6_FLT")
		)
		(pad "B44" smd rect
			(at -33.500314 -0.692404 270)
			(size 0.7112 3.6068)
			(layers "F.Cu" "F.Mask" "F.Paste")
			(net "SAS2X28_A_HDD2_FLT")
		)
		(pad "B45" smd rect
			(at -34.500312 -0.692404 270)
			(size 0.7112 3.6068)
			(layers "F.Cu" "F.Mask" "F.Paste")
			(net "SAS2X28_A_HDD1_FLT")
		)
		(pad "B46" smd rect
			(at -35.50031 -0.692404 270)
			(size 0.7112 3.6068)
			(layers "F.Cu" "F.Mask" "F.Paste")
			(net "SAS2X28_A_HDD10_FLT")
		)
		(pad "B47" smd rect
			(at -36.500308 -0.692404 270)
			(size 0.7112 3.6068)
			(layers "F.Cu" "F.Mask" "F.Paste")
			(net "SAS2X28_A_HDD0_FLT")
		)
		(pad "B48" smd rect
			(at -37.500306 -0.692404 270)
			(size 0.7112 3.6068)
			(layers "F.Cu" "F.Mask" "F.Paste")
			(net "GND")
		)
		(pad "B49" smd rect
			(at -38.500304 -0.692404 270)
			(size 0.7112 3.6068)
			(layers "F.Cu" "F.Mask" "F.Paste")
			(net "SAS2X28_A_HDD2_TX_+")
		)
		(pad "B50" smd rect
			(at -39.500302 -0.692404 270)
			(size 0.7112 3.6068)
			(layers "F.Cu" "F.Mask" "F.Paste")
			(net "SAS2X28_A_HDD2_TX_-")
		)
		(pad "B51" smd rect
			(at -40.5003 -0.692404 270)
			(size 0.7112 3.6068)
			(layers "F.Cu" "F.Mask" "F.Paste")
			(net "GND")
		)
		(pad "B52" smd rect
			(at -41.500298 -0.692404 270)
			(size 0.7112 3.6068)
			(layers "F.Cu" "F.Mask" "F.Paste")
			(net "SAS2X28_A_HDD5_FLT")
		)
		(pad "B53" smd rect
			(at -42.500296 -0.692404 270)
			(size 0.7112 3.6068)
			(layers "F.Cu" "F.Mask" "F.Paste")
			(net "SAS2X28_A_HDD15_FLT")
		)
		(pad "B54" smd rect
			(at -43.500294 -0.692404 270)
			(size 0.7112 3.6068)
			(layers "F.Cu" "F.Mask" "F.Paste")
			(net "SELF_1A&2A_HB")
		)
		(pad "B55" smd rect
			(at -44.500292 -0.692404 270)
			(size 0.7112 3.6068)
			(layers "F.Cu" "F.Mask" "F.Paste")
			(net "HB_EXP_A_INPUT")
		)
		(pad "B56" smd rect
			(at -45.50029 -0.692404 270)
			(size 0.7112 3.6068)
			(layers "F.Cu" "F.Mask" "F.Paste")
			(net "I2C_B_SCL_DAMP_A")
		)
		(pad "B57" smd rect
			(at -46.500288 -0.692404 270)
			(size 0.7112 3.6068)
			(layers "F.Cu" "F.Mask" "F.Paste")
			(net "I2C_B_SDA_DAMP_A")
		)
		(pad "B58" smd rect
			(at -47.500286 -0.692404 270)
			(size 0.7112 3.6068)
			(layers "F.Cu" "F.Mask" "F.Paste")
			(net "TEMP_SENSOR_A_ADDR0&ID")
		)
		(pad "B59" smd rect
			(at -48.500284 -0.692404 270)
			(size 0.7112 3.6068)
			(layers "F.Cu" "F.Mask" "F.Paste")
			(net "PWM_EXP_A")
		)
		(pad "B60" smd rect
			(at -49.500282 -0.692404 270)
			(size 0.7112 3.6068)
			(layers "F.Cu" "F.Mask" "F.Paste")
			(net "PEER_1A&2A_HB")
		)
		(pad "B61" smd rect
			(at -50.50028 -0.692404 270)
			(size 0.7112 3.6068)
			(layers "F.Cu" "F.Mask" "F.Paste")
			(net "GND")
		)
		(pad "B62" smd rect
			(at -51.500278 -0.692404 270)
			(size 0.7112 3.6068)
			(layers "F.Cu" "F.Mask" "F.Paste")
			(net "SAS2X28_A_HDD1_TX_+")
		)
		(pad "B63" smd rect
			(at -52.500276 -0.692404 270)
			(size 0.7112 3.6068)
			(layers "F.Cu" "F.Mask" "F.Paste")
			(net "SAS2X28_A_HDD1_TX_-")
		)
		(pad "B64" smd rect
			(at -53.500274 -0.692404 270)
			(size 0.7112 3.6068)
			(layers "F.Cu" "F.Mask" "F.Paste")
			(net "GND")
		)
		(pad "B65" smd rect
			(at -54.500272 -0.692404 270)
			(size 0.7112 3.6068)
			(layers "F.Cu" "F.Mask" "F.Paste")
			(net "GND")
		)
		(pad "B66" smd rect
			(at -55.50027 -0.692404 270)
			(size 0.7112 3.6068)
			(layers "F.Cu" "F.Mask" "F.Paste")
			(net "SAS2X28_A_HDD10_TX_+")
		)
		(pad "B67" smd rect
			(at -56.500268 -0.692404 270)
			(size 0.7112 3.6068)
			(layers "F.Cu" "F.Mask" "F.Paste")
			(net "SAS2X28_A_HDD10_TX_-")
		)
		(pad "B68" smd rect
			(at -57.500266 -0.692404 270)
			(size 0.7112 3.6068)
			(layers "F.Cu" "F.Mask" "F.Paste")
			(net "GND")
		)
		(pad "B69" smd rect
			(at -58.500264 -0.692404 270)
			(size 0.7112 3.6068)
			(layers "F.Cu" "F.Mask" "F.Paste")
			(net "GND")
		)
		(pad "B70" smd rect
			(at -59.500262 -0.692404 270)
			(size 0.7112 3.6068)
			(layers "F.Cu" "F.Mask" "F.Paste")
			(net "SAS2X28_A_HDD0_TX_+")
		)
		(pad "B71" smd rect
			(at -60.50026 -0.692404 270)
			(size 0.7112 3.6068)
			(layers "F.Cu" "F.Mask" "F.Paste")
			(net "SAS2X28_A_HDD0_TX_-")
		)
		(pad "B72" smd rect
			(at -61.500258 -0.692404 270)
			(size 0.7112 3.6068)
			(layers "F.Cu" "F.Mask" "F.Paste")
			(net "GND")
		)
		(pad "B73" smd rect
			(at -62.500256 -0.692404 270)
			(size 0.7112 3.6068)
			(layers "F.Cu" "F.Mask" "F.Paste")
			(net "GND")
		)
		(pad "B74" smd rect
			(at -63.500254 -0.692404 270)
			(size 0.7112 3.6068)
			(layers "F.Cu" "F.Mask" "F.Paste")
			(net "SAS2X28_A_HDD5_TX_+")
		)
		(pad "B75" smd rect
			(at -64.500252 -0.692404 270)
			(size 0.7112 3.6068)
			(layers "F.Cu" "F.Mask" "F.Paste")
			(net "SAS2X28_A_HDD5_TX_-")
		)
		(pad "B76" smd rect
			(at -65.50025 -0.692404 270)
			(size 0.7112 3.6068)
			(layers "F.Cu" "F.Mask" "F.Paste")
			(net "GND")
		)
		(pad "B77" smd rect
			(at -66.500248 -0.692404 270)
			(size 0.7112 3.6068)
			(layers "F.Cu" "F.Mask" "F.Paste")
			(net "GND")
		)
		(pad "B78" smd rect
			(at -67.500246 -0.692404 270)
			(size 0.7112 3.6068)
			(layers "F.Cu" "F.Mask" "F.Paste")
			(net "SEB_AB_TX+")
		)
		(pad "B79" smd rect
			(at -68.500244 -0.692404 270)
			(size 0.7112 3.6068)
			(layers "F.Cu" "F.Mask" "F.Paste")
			(net "SEB_AB_TX-")
		)
		(pad "B80" smd rect
			(at -69.500242 -0.692404 270)
			(size 0.7112 3.6068)
			(layers "F.Cu" "F.Mask" "F.Paste")
			(net "GND")
		)
		(pad "B81" smd rect
			(at -70.50024 -0.692404 270)
			(size 0.7112 3.6068)
			(layers "F.Cu" "F.Mask" "F.Paste")
			(net "GND")
		)
		(pad "B82" smd rect
			(at -71.500238 -0.692404 270)
			(size 0.7112 3.6068)
			(layers "F.Cu" "F.Mask" "F.Paste")
			(net "GND")
		)
		(zone
			(layers "F.Cu" "B.Cu" "In1.Cu" "In2.Cu" "In3.Cu" "In4.Cu" "In5.Cu" "In6.Cu")
			(hatch none 0.5)
			(connect_pads
				(clearance 0)
			)
			(min_thickness 0.25)
			(keepout
				(tracks not_allowed)
				(vias allowed)
				(pads allowed)
				(copperpour not_allowed)
				(footprints allowed)
			)
			(placement
				(enabled no)
				(sheetname "")
			)
			(fill
				(thermal_gap 0.5)
				(thermal_bridge_width 0.5)
				(island_removal_mode 0)
			)
			(polygon
				(pts
					(arc
						(start 3.960622 -432.298602)
						(mid 1.039622 -432.298602)
						(end 3.960622 -432.298602)
					)
				)
			)
		)
		(zone
			(layers "F.Cu" "B.Cu" "In1.Cu" "In2.Cu" "In3.Cu" "In4.Cu" "In5.Cu" "In6.Cu")
			(hatch none 0.5)
			(connect_pads
				(clearance 0)
			)
			(min_thickness 0.25)
			(keepout
				(tracks not_allowed)
				(vias allowed)
				(pads allowed)
				(copperpour not_allowed)
				(footprints allowed)
			)
			(placement
				(enabled no)
				(sheetname "")
			)
			(fill
				(thermal_gap 0.5)
				(thermal_bridge_width 0.5)
				(island_removal_mode 0)
			)
			(polygon
				(pts
					(arc
						(start 3.960622 -339.698584)
						(mid 1.039622 -339.698584)
						(end 3.960622 -339.698584)
					)
				)
			)
		)
	)
	(footprint ""
		(layer "F.Cu")
		(at 7.111746 -499.5037 180)
		(property "Reference" "PR46"
			(at 0 0 180)
			(layer "F.SilkS")
			(hide yes)
			(effects
				(font
					(size 1.27 1.27)
				)
			)
		)
		(property "Value" "115KR2F-GP"
			(at 0.064008 -3.993896 180)
			(unlocked yes)
			(layer "F.Fab")
			(hide yes)
			(effects
				(font
					(size 1.016 1.016)
					(thickness 0.1524)
				)
			)
		)
		(property "Device Type" "R402H16"
			(at 0.064008 -5.517896 180)
			(unlocked yes)
			(layer "F.Fab")
			(hide yes)
			(effects
				(font
					(size 1.016 1.016)
					(thickness 0.1524)
				)
			)
		)
		(duplicate_pad_numbers_are_jumpers no)
		(fp_line
			(start 0.508 -0.9398)
			(end -0.508 -0.9398)
			(stroke
				(width 0.1524)
				(type default)
			)
			(layer "F.SilkS")
		)
		(fp_line
			(start -0.508 -0.9398)
			(end -0.508 0.9398)
			(stroke
				(width 0.1524)
				(type default)
			)
			(layer "F.SilkS")
		)
		(fp_rect
			(start -0.508 0.9398)
			(end 0.508 -0.9398)
			(stroke
				(width 0)
				(type default)
			)
			(fill no)
			(layer "F.CrtYd")
		)
		(fp_rect
			(start -0.508 0.9398)
			(end 0.508 -0.9398)
			(stroke
				(width 0)
				(type default)
			)
			(fill no)
			(layer "F.Fab")
		)
		(pad "1" smd custom
			(at 0 -0.4445 180)
			(size 0.1397 0.1397)
			(layers "F.Cu" "F.Mask" "F.Paste")
			(net "P5VC_TRIP")
			(options
				(clearance outline)
				(anchor circle)
			)
			(primitives
				(gr_poly
					(pts
						(arc
							(start -0.1778 -0.2794)
							(mid -0.249642 -0.249642)
							(end -0.2794 -0.1778)
						)
						(arc
							(start -0.2794 0.1778)
							(mid -0.249642 0.249642)
							(end -0.1778 0.2794)
						)
						(arc
							(start 0.1778 0.2794)
							(mid 0.249642 0.249642)
							(end 0.2794 0.1778)
						)
						(arc
							(start 0.2794 -0.1778)
							(mid 0.249642 -0.249642)
							(end 0.1778 -0.2794)
						)
					)
					(width 0)
					(fill yes)
				)
			)
		)
		(pad "2" smd custom
			(at 0 0.4445 180)
			(size 0.1397 0.1397)
			(layers "F.Cu" "F.Mask" "F.Paste")
			(net "P5VC_AGND")
			(options
				(clearance outline)
				(anchor circle)
			)
			(primitives
				(gr_poly
					(pts
						(arc
							(start -0.1778 -0.2794)
							(mid -0.249642 -0.249642)
							(end -0.2794 -0.1778)
						)
						(arc
							(start -0.2794 0.1778)
							(mid -0.249642 0.249642)
							(end -0.1778 0.2794)
						)
						(arc
							(start 0.1778 0.2794)
							(mid 0.249642 0.249642)
							(end 0.2794 0.1778)
						)
						(arc
							(start 0.2794 -0.1778)
							(mid 0.249642 -0.249642)
							(end 0.1778 -0.2794)
						)
					)
					(width 0)
					(fill yes)
				)
			)
		)
	)
	(footprint ""
		(layer "F.Cu")
		(at 195.58 -495.554 180)
		(property "Reference" "R408"
			(at 0 0 180)
			(layer "F.SilkS")
			(hide yes)
			(effects
				(font
					(size 1.27 1.27)
				)
			)
		)
		(property "Value" "0R2J-2-GP"
			(at 0.064008 -3.993896 180)
			(unlocked yes)
			(layer "F.Fab")
			(hide yes)
			(effects
				(font
					(size 1.016 1.016)
					(thickness 0.1524)
				)
			)
		)
		(property "Device Type" "R402H16"
			(at 0.064008 -5.517896 180)
			(unlocked yes)
			(layer "F.Fab")
			(hide yes)
			(effects
				(font
					(size 1.016 1.016)
					(thickness 0.1524)
				)
			)
		)
		(duplicate_pad_numbers_are_jumpers no)
		(fp_line
			(start 0.508 -0.9398)
			(end -0.508 -0.9398)
			(stroke
				(width 0.1524)
				(type default)
			)
			(layer "F.SilkS")
		)
		(fp_line
			(start -0.508 -0.9398)
			(end -0.508 0.9398)
			(stroke
				(width 0.1524)
				(type default)
			)
			(layer "F.SilkS")
		)
		(fp_rect
			(start -0.508 0.9398)
			(end 0.508 -0.9398)
			(stroke
				(width 0)
				(type default)
			)
			(fill no)
			(layer "F.CrtYd")
		)
		(fp_rect
			(start -0.508 0.9398)
			(end 0.508 -0.9398)
			(stroke
				(width 0)
				(type default)
			)
			(fill no)
			(layer "F.Fab")
		)
		(pad "1" smd custom
			(at 0 -0.4445 180)
			(size 0.1397 0.1397)
			(layers "F.Cu" "F.Mask" "F.Paste")
			(net "SW_HDD0_G")
			(options
				(clearance outline)
				(anchor circle)
			)
			(primitives
				(gr_poly
					(pts
						(arc
							(start -0.1778 -0.2794)
							(mid -0.249642 -0.249642)
							(end -0.2794 -0.1778)
						)
						(arc
							(start -0.2794 0.1778)
							(mid -0.249642 0.249642)
							(end -0.1778 0.2794)
						)
						(arc
							(start 0.1778 0.2794)
							(mid 0.249642 0.249642)
							(end 0.2794 0.1778)
						)
						(arc
							(start 0.2794 -0.1778)
							(mid 0.249642 -0.249642)
							(end 0.1778 -0.2794)
						)
					)
					(width 0)
					(fill yes)
				)
			)
		)
		(pad "2" smd custom
			(at 0 0.4445 180)
			(size 0.1397 0.1397)
			(layers "F.Cu" "F.Mask" "F.Paste")
			(net "SW_HDD0_R")
			(options
				(clearance outline)
				(anchor circle)
			)
			(primitives
				(gr_poly
					(pts
						(arc
							(start -0.1778 -0.2794)
							(mid -0.249642 -0.249642)
							(end -0.2794 -0.1778)
						)
						(arc
							(start -0.2794 0.1778)
							(mid -0.249642 0.249642)
							(end -0.1778 0.2794)
						)
						(arc
							(start 0.1778 0.2794)
							(mid 0.249642 0.249642)
							(end 0.2794 0.1778)
						)
						(arc
							(start 0.2794 -0.1778)
							(mid 0.249642 -0.249642)
							(end 0.1778 -0.2794)
						)
					)
					(width 0)
					(fill yes)
				)
			)
		)
	)
	(footprint ""
		(layer "F.Cu")
		(at 6.730746 -491.6297 180)
		(property "Reference" "TP24"
			(at 0 0 180)
			(layer "F.SilkS")
			(hide yes)
			(effects
				(font
					(size 1.27 1.27)
				)
			)
		)
		(property "Value" "TPAD32-GP"
			(at 0 -3.166364 180)
			(unlocked yes)
			(layer "F.Fab")
			(hide yes)
			(effects
				(font
					(size 1.016 1.016)
					(thickness 0.1524)
				)
			)
		)
		(property "Device Type" "TPAD32"
			(at 0 -4.690618 180)
			(unlocked yes)
			(layer "F.Fab")
			(hide yes)
			(effects
				(font
					(size 1.016 1.016)
					(thickness 0.1524)
				)
			)
		)
		(duplicate_pad_numbers_are_jumpers no)
		(fp_poly
			(pts
				(arc
					(start -0.4064 0)
					(mid 0.4064 0)
					(end -0.4064 0)
				)
			)
			(stroke
				(width 0)
				(type default)
			)
			(fill no)
			(layer "F.CrtYd")
		)
		(fp_poly
			(pts
				(arc
					(start -0.7112 0)
					(mid 0.7112 0)
					(end -0.7112 0)
				)
			)
			(stroke
				(width 0)
				(type default)
			)
			(fill no)
			(layer "F.Fab")
		)
		(pad "1" smd circle
			(at 0 0 180)
			(size 0.8128 0.8128)
			(layers "F.Cu" "F.Mask" "F.Paste")
			(net "P5VC_PGD")
		)
	)
	(footprint ""
		(layer "F.Cu")
		(at 32.258 -288.29)
		(property "Reference" "R570"
			(at 0 0 0)
			(layer "F.SilkS")
			(hide yes)
			(effects
				(font
					(size 1.27 1.27)
				)
			)
		)
		(property "Value" "300KR2F-GP"
			(at 0.064008 -3.993896 0)
			(unlocked yes)
			(layer "F.Fab")
			(hide yes)
			(effects
				(font
					(size 1.016 1.016)
					(thickness 0.1524)
				)
			)
		)
		(property "Device Type" "R402H16"
			(at 0.064008 -5.517896 0)
			(unlocked yes)
			(layer "F.Fab")
			(hide yes)
			(effects
				(font
					(size 1.016 1.016)
					(thickness 0.1524)
				)
			)
		)
		(duplicate_pad_numbers_are_jumpers no)
		(fp_line
			(start -0.508 -0.9398)
			(end -0.508 0.9398)
			(stroke
				(width 0.1524)
				(type default)
			)
			(layer "F.SilkS")
		)
		(fp_line
			(start 0.508 -0.9398)
			(end -0.508 -0.9398)
			(stroke
				(width 0.1524)
				(type default)
			)
			(layer "F.SilkS")
		)
		(fp_rect
			(start -0.508 0.9398)
			(end 0.508 -0.9398)
			(stroke
				(width 0)
				(type default)
			)
			(fill no)
			(layer "F.CrtYd")
		)
		(fp_rect
			(start -0.508 0.9398)
			(end 0.508 -0.9398)
			(stroke
				(width 0)
				(type default)
			)
			(fill no)
			(layer "F.Fab")
		)
		(pad "1" smd custom
			(at 0 -0.4445)
			(size 0.1397 0.1397)
			(layers "F.Cu" "F.Mask" "F.Paste")
			(net "SW_HDD7_N")
			(options
				(clearance outline)
				(anchor circle)
			)
			(primitives
				(gr_poly
					(pts
						(arc
							(start -0.1778 -0.2794)
							(mid -0.249642 -0.249642)
							(end -0.2794 -0.1778)
						)
						(arc
							(start -0.2794 0.1778)
							(mid -0.249642 0.249642)
							(end -0.1778 0.2794)
						)
						(arc
							(start 0.1778 0.2794)
							(mid 0.249642 0.249642)
							(end 0.2794 0.1778)
						)
						(arc
							(start 0.2794 -0.1778)
							(mid 0.249642 -0.249642)
							(end 0.1778 -0.2794)
						)
					)
					(width 0)
					(fill yes)
				)
			)
		)
		(pad "2" smd custom
			(at 0 0.4445)
			(size 0.1397 0.1397)
			(layers "F.Cu" "F.Mask" "F.Paste")
			(net "P12V")
			(options
				(clearance outline)
				(anchor circle)
			)
			(primitives
				(gr_poly
					(pts
						(arc
							(start -0.1778 -0.2794)
							(mid -0.249642 -0.249642)
							(end -0.2794 -0.1778)
						)
						(arc
							(start -0.2794 0.1778)
							(mid -0.249642 0.249642)
							(end -0.1778 0.2794)
						)
						(arc
							(start 0.1778 0.2794)
							(mid 0.249642 0.249642)
							(end 0.2794 0.1778)
						)
						(arc
							(start 0.2794 -0.1778)
							(mid 0.249642 -0.249642)
							(end 0.1778 -0.2794)
						)
					)
					(width 0)
					(fill yes)
				)
			)
		)
	)
	(footprint ""
		(layer "F.Cu")
		(at 194.31 -89.916 180)
		(property "Reference" "R567"
			(at 0 0 180)
			(layer "F.SilkS")
			(hide yes)
			(effects
				(font
					(size 1.27 1.27)
				)
			)
		)
		(property "Value" "300KR2F-GP"
			(at 0.064008 -3.993896 180)
			(unlocked yes)
			(layer "F.Fab")
			(hide yes)
			(effects
				(font
					(size 1.016 1.016)
					(thickness 0.1524)
				)
			)
		)
		(property "Device Type" "R402H16"
			(at 0.064008 -5.517896 180)
			(unlocked yes)
			(layer "F.Fab")
			(hide yes)
			(effects
				(font
					(size 1.016 1.016)
					(thickness 0.1524)
				)
			)
		)
		(duplicate_pad_numbers_are_jumpers no)
		(fp_line
			(start 0.508 -0.9398)
			(end -0.508 -0.9398)
			(stroke
				(width 0.1524)
				(type default)
			)
			(layer "F.SilkS")
		)
		(fp_line
			(start -0.508 -0.9398)
			(end -0.508 0.9398)
			(stroke
				(width 0.1524)
				(type default)
			)
			(layer "F.SilkS")
		)
		(fp_rect
			(start -0.508 0.9398)
			(end 0.508 -0.9398)
			(stroke
				(width 0)
				(type default)
			)
			(fill no)
			(layer "F.CrtYd")
		)
		(fp_rect
			(start -0.508 0.9398)
			(end 0.508 -0.9398)
			(stroke
				(width 0)
				(type default)
			)
			(fill no)
			(layer "F.Fab")
		)
		(pad "1" smd custom
			(at 0 -0.4445 180)
			(size 0.1397 0.1397)
			(layers "F.Cu" "F.Mask" "F.Paste")
			(net "SW_HDD4_N")
			(options
				(clearance outline)
				(anchor circle)
			)
			(primitives
				(gr_poly
					(pts
						(arc
							(start -0.1778 -0.2794)
							(mid -0.249642 -0.249642)
							(end -0.2794 -0.1778)
						)
						(arc
							(start -0.2794 0.1778)
							(mid -0.249642 0.249642)
							(end -0.1778 0.2794)
						)
						(arc
							(start 0.1778 0.2794)
							(mid 0.249642 0.249642)
							(end 0.2794 0.1778)
						)
						(arc
							(start 0.2794 -0.1778)
							(mid 0.249642 -0.249642)
							(end 0.1778 -0.2794)
						)
					)
					(width 0)
					(fill yes)
				)
			)
		)
		(pad "2" smd custom
			(at 0 0.4445 180)
			(size 0.1397 0.1397)
			(layers "F.Cu" "F.Mask" "F.Paste")
			(net "P12V")
			(options
				(clearance outline)
				(anchor circle)
			)
			(primitives
				(gr_poly
					(pts
						(arc
							(start -0.1778 -0.2794)
							(mid -0.249642 -0.249642)
							(end -0.2794 -0.1778)
						)
						(arc
							(start -0.2794 0.1778)
							(mid -0.249642 0.249642)
							(end -0.1778 0.2794)
						)
						(arc
							(start 0.1778 0.2794)
							(mid 0.249642 0.249642)
							(end 0.2794 0.1778)
						)
						(arc
							(start 0.2794 -0.1778)
							(mid 0.249642 -0.249642)
							(end 0.1778 -0.2794)
						)
					)
					(width 0)
					(fill yes)
				)
			)
		)
	)
	(footprint ""
		(layer "F.Cu")
		(at 242.569746 -13.9827 90)
		(property "Reference" "PC1"
			(at 0 0 90)
			(layer "F.SilkS")
			(hide yes)
			(effects
				(font
					(size 1.27 1.27)
				)
			)
		)
		(property "Value" "SC22U25V5MX-GP"
			(at -0.0762 -6.1214 90)
			(unlocked yes)
			(layer "F.Fab")
			(hide yes)
			(effects
				(font
					(size 1.016 1.016)
					(thickness 0.1524)
				)
			)
		)
		(property "Device Type" "C805H58"
			(at -0.0762 -8.1534 90)
			(unlocked yes)
			(layer "F.Fab")
			(hide yes)
			(effects
				(font
					(size 1.016 1.016)
					(thickness 0.1524)
				)
			)
		)
		(duplicate_pad_numbers_are_jumpers no)
		(fp_line
			(start 0.635 0)
			(end -0.635 0)
			(stroke
				(width 0.508)
				(type default)
			)
			(layer "F.SilkS")
		)
		(fp_rect
			(start -0.9652 1.778)
			(end 0.9652 -1.778)
			(stroke
				(width 0)
				(type default)
			)
			(fill no)
			(layer "F.CrtYd")
		)
		(fp_poly
			(pts
				(xy -0.9652 -1.778) (xy 0.9652 -1.778) (xy 0.9652 1.778) (xy -0.9652 1.778)
			)
			(stroke
				(width 0)
				(type default)
			)
			(fill no)
			(layer "F.Fab")
		)
		(pad "1" smd rect
			(at 0 -0.9652 90)
			(size 1.397 1.143)
			(layers "F.Cu" "F.Mask" "F.Paste")
			(net "P5VA_12VIN")
		)
		(pad "2" smd rect
			(at 0 0.9652 90)
			(size 1.397 1.143)
			(layers "F.Cu" "F.Mask" "F.Paste")
			(net "GND")
		)
	)
	(footprint ""
		(layer "F.Cu")
		(at 33.043368 -475.171516 -90)
		(property "Reference" "C184"
			(at 0 0 270)
			(layer "F.SilkS")
			(hide yes)
			(effects
				(font
					(size 1.27 1.27)
				)
			)
		)
		(property "Value" "SCD01U50V2KX-1GP"
			(at 1.1811 -2.7051 270)
			(unlocked yes)
			(layer "F.Fab")
			(hide yes)
			(effects
				(font
					(size 1.016 1.016)
					(thickness 0.1524)
				)
			)
		)
		(property "Device Type" "C402H22"
			(at 1.1811 -4.2291 270)
			(unlocked yes)
			(layer "F.Fab")
			(hide yes)
			(effects
				(font
					(size 1.016 1.016)
					(thickness 0.1524)
				)
			)
		)
		(duplicate_pad_numbers_are_jumpers no)
		(fp_rect
			(start -0.4318 0.9525)
			(end 0.4318 -0.9525)
			(stroke
				(width 0)
				(type default)
			)
			(fill no)
			(layer "F.CrtYd")
		)
		(fp_rect
			(start -0.4318 0.9525)
			(end 0.4318 -0.9525)
			(stroke
				(width 0)
				(type default)
			)
			(fill no)
			(layer "F.Fab")
		)
		(pad "1" smd custom
			(at 0 -0.4445 270)
			(size 0.1524 0.1524)
			(layers "F.Cu" "F.Mask" "F.Paste")
			(net "SAS2X28_DRIVE_RX_N_B5")
			(options
				(clearance outline)
				(anchor circle)
			)
			(primitives
				(gr_poly
					(pts
						(arc
							(start 0.3048 -0.2032)
							(mid 0.275042 -0.275042)
							(end 0.2032 -0.3048)
						)
						(arc
							(start -0.2032 -0.3048)
							(mid -0.275042 -0.275042)
							(end -0.3048 -0.2032)
						)
						(arc
							(start -0.3048 0.2032)
							(mid -0.275042 0.275042)
							(end -0.2032 0.3048)
						)
						(arc
							(start 0.2032 0.3048)
							(mid 0.275042 0.275042)
							(end 0.3048 0.2032)
						)
					)
					(width 0)
					(fill yes)
				)
			)
		)
		(pad "2" smd custom
			(at 0 0.4445 270)
			(size 0.1524 0.1524)
			(layers "F.Cu" "F.Mask" "F.Paste")
			(net "SAS2X28_B_HDD5_RX_-")
			(options
				(clearance outline)
				(anchor circle)
			)
			(primitives
				(gr_poly
					(pts
						(arc
							(start 0.3048 -0.2032)
							(mid 0.275042 -0.275042)
							(end 0.2032 -0.3048)
						)
						(arc
							(start -0.2032 -0.3048)
							(mid -0.275042 -0.275042)
							(end -0.3048 -0.2032)
						)
						(arc
							(start -0.3048 0.2032)
							(mid -0.275042 0.275042)
							(end -0.2032 0.3048)
						)
						(arc
							(start 0.2032 0.3048)
							(mid 0.275042 0.275042)
							(end 0.3048 0.2032)
						)
					)
					(width 0)
					(fill yes)
				)
			)
		)
	)
	(footprint ""
		(layer "F.Cu")
		(at 72.681846 -492.6203)
		(property "Reference" "U16"
			(at 0 0 0)
			(layer "F.SilkS")
			(hide yes)
			(effects
				(font
					(size 1.27 1.27)
				)
			)
		)
		(property "Value" "74LVC1G08GW-1-GP"
			(at -2.3368 -8.6868 0)
			(unlocked yes)
			(layer "F.Fab")
			(hide yes)
			(effects
				(font
					(size 1.016 1.016)
					(thickness 0.1524)
				)
			)
		)
		(property "Device Type" "SC70-5H44"
			(at -2.3114 -10.414 0)
			(unlocked yes)
			(layer "F.Fab")
			(hide yes)
			(effects
				(font
					(size 1.016 1.016)
					(thickness 0.1524)
				)
			)
		)
		(duplicate_pad_numbers_are_jumpers no)
		(fp_line
			(start -1.27 -1.7018)
			(end 1.27 -1.7018)
			(stroke
				(width 0.1524)
				(type default)
			)
			(layer "F.SilkS")
		)
		(fp_line
			(start -1.27 1.7018)
			(end -1.27 -1.7018)
			(stroke
				(width 0.1524)
				(type default)
			)
			(layer "F.SilkS")
		)
		(fp_line
			(start 0.6604 -1.8034)
			(end 1.3843 -1.8034)
			(stroke
				(width 0.3302)
				(type default)
			)
			(layer "F.SilkS")
		)
		(fp_line
			(start 1.27 -1.7018)
			(end 1.27 1.7018)
			(stroke
				(width 0.1524)
				(type default)
			)
			(layer "F.SilkS")
		)
		(fp_line
			(start 1.27 1.7018)
			(end -1.27 1.7018)
			(stroke
				(width 0.1524)
				(type default)
			)
			(layer "F.SilkS")
		)
		(fp_line
			(start 1.3843 -1.8034)
			(end 1.3843 -1.1176)
			(stroke
				(width 0.3302)
				(type default)
			)
			(layer "F.SilkS")
		)
		(fp_rect
			(start -1.524 1.9558)
			(end 1.524 -1.9558)
			(stroke
				(width 0)
				(type default)
			)
			(fill no)
			(layer "F.CrtYd")
		)
		(fp_poly
			(pts
				(xy -1.524 -1.9558) (xy 1.524 -1.9558) (xy 1.524 1.9558) (xy -1.524 1.9558)
			)
			(stroke
				(width 0)
				(type default)
			)
			(fill no)
			(layer "F.Fab")
		)
		(pad "1" smd rect
			(at 0.65024 -0.8255)
			(size 0.4064 1.2192)
			(layers "F.Cu" "F.Mask" "F.Paste")
			(net "SAS2X28_B_HDD5_FLT")
		)
		(pad "2" smd rect
			(at 0 -0.8255)
			(size 0.4064 1.2192)
			(layers "F.Cu" "F.Mask" "F.Paste")
			(net "SAS2X28_A_HDD5_FLT")
		)
		(pad "3" smd rect
			(at -0.65024 -0.8255)
			(size 0.4064 1.2192)
			(layers "F.Cu" "F.Mask" "F.Paste")
			(net "GND")
		)
		(pad "4" smd rect
			(at -0.65024 0.8255)
			(size 0.4064 1.2192)
			(layers "F.Cu" "F.Mask" "F.Paste")
			(net "FLT_HDD5_DRIVE")
		)
		(pad "5" smd rect
			(at 0.65024 0.8255)
			(size 0.4064 1.2192)
			(layers "F.Cu" "F.Mask" "F.Paste")
			(net "P3V3")
		)
	)
	(footprint ""
		(layer "F.Cu")
		(at 210.609942 -46.999906 180)
		(property "Reference" "U49"
			(at 0 0 180)
			(layer "F.SilkS")
			(hide yes)
			(effects
				(font
					(size 1.27 1.27)
				)
			)
		)
		(property "Value" "TMP75AIDGKR-GP"
			(at -0.1143 -9.1948 180)
			(unlocked yes)
			(layer "F.Fab")
			(hide yes)
			(effects
				(font
					(size 1.016 1.016)
					(thickness 0.1524)
				)
			)
		)
		(property "Device Type" "MSOP8-1H44"
			(at -0.1143 -10.795 180)
			(unlocked yes)
			(layer "F.Fab")
			(hide yes)
			(effects
				(font
					(size 1.016 1.016)
					(thickness 0.1524)
				)
			)
		)
		(duplicate_pad_numbers_are_jumpers no)
		(fp_line
			(start 1.0795 1.016)
			(end 1.0795 -1.016)
			(stroke
				(width 0.1524)
				(type default)
			)
			(layer "F.SilkS")
		)
		(fp_line
			(start 1.0795 -1.016)
			(end -1.9558 -1.016)
			(stroke
				(width 0.1524)
				(type default)
			)
			(layer "F.SilkS")
		)
		(fp_line
			(start -1.4478 -0.0381)
			(end -1.9558 0.4699)
			(stroke
				(width 0.1524)
				(type default)
			)
			(layer "F.SilkS")
		)
		(fp_line
			(start -1.778 1.0922)
			(end -1.778 3.048)
			(stroke
				(width 0.508)
				(type default)
			)
			(layer "F.SilkS")
		)
		(fp_line
			(start -1.9558 1.016)
			(end 1.0795 1.016)
			(stroke
				(width 0.1524)
				(type default)
			)
			(layer "F.SilkS")
		)
		(fp_line
			(start -1.9558 -0.5461)
			(end -1.4478 -0.0381)
			(stroke
				(width 0.1524)
				(type default)
			)
			(layer "F.SilkS")
		)
		(fp_line
			(start -1.9558 -1.016)
			(end -1.9558 1.016)
			(stroke
				(width 0.1524)
				(type default)
			)
			(layer "F.SilkS")
		)
		(fp_poly
			(pts
				(xy -1.1557 -1.016) (xy -1.1557 1.016) (xy 1.1557 1.016) (xy 1.1557 -1.016)
			)
			(stroke
				(width 0)
				(type default)
			)
			(fill yes)
			(layer "F.SilkS")
		)
		(fp_rect
			(start -1.4986 2.4511)
			(end 1.4986 -2.4511)
			(stroke
				(width 0)
				(type default)
			)
			(fill no)
			(layer "F.CrtYd")
		)
		(fp_poly
			(pts
				(xy -2.032 3.302) (xy -2.032 -3.302) (xy 2.032 -3.302) (xy 2.032 -2.1209) (xy 1.4986 -2.1209) (xy 1.4986 -2.4511)
				(xy -1.4986 -2.4511) (xy -1.4986 2.4511) (xy 1.4986 2.4511) (xy 1.4986 -2.1082) (xy 2.032 -2.1082)
				(xy 2.032 3.302)
			)
			(stroke
				(width 0)
				(type default)
			)
			(fill no)
			(layer "F.CrtYd")
		)
		(fp_rect
			(start -2.032 3.302)
			(end 2.032 -3.302)
			(stroke
				(width 0)
				(type default)
			)
			(fill no)
			(layer "F.Fab")
		)
		(pad "1" smd rect
			(at -0.97536 2.05486 180)
			(size 0.3556 1.524)
			(layers "F.Cu" "F.Mask" "F.Paste")
			(net "TMP4_SDA")
		)
		(pad "2" smd rect
			(at -0.32512 2.05486 180)
			(size 0.3556 1.524)
			(layers "F.Cu" "F.Mask" "F.Paste")
			(net "TMP4_SCL")
		)
		(pad "3" smd rect
			(at 0.32512 2.05486 180)
			(size 0.3556 1.524)
			(layers "F.Cu" "F.Mask" "F.Paste")
			(net "I2C_B_TMP4_ALERT")
		)
		(pad "4" smd rect
			(at 0.97536 2.05486 180)
			(size 0.3556 1.524)
			(layers "F.Cu" "F.Mask" "F.Paste")
			(net "GND")
		)
		(pad "5" smd rect
			(at 0.97536 -2.05486 180)
			(size 0.3556 1.524)
			(layers "F.Cu" "F.Mask" "F.Paste")
			(net "I2C_B_TMP4_A2")
		)
		(pad "6" smd rect
			(at 0.32512 -2.05486 180)
			(size 0.3556 1.524)
			(layers "F.Cu" "F.Mask" "F.Paste")
			(net "I2C_B_TMP4_A1")
		)
		(pad "7" smd rect
			(at -0.32512 -2.05486 180)
			(size 0.3556 1.524)
			(layers "F.Cu" "F.Mask" "F.Paste")
			(net "I2C_B_TMP4_A0")
		)
		(pad "8" smd rect
			(at -0.97536 -2.05486 180)
			(size 0.3556 1.524)
			(layers "F.Cu" "F.Mask" "F.Paste")
			(net "P3V3")
		)
	)
	(footprint ""
		(layer "F.Cu")
		(at 212.5726 -376.6312 180)
		(property "Reference" "Q50"
			(at 0 0 180)
			(layer "F.SilkS")
			(hide yes)
			(effects
				(font
					(size 1.27 1.27)
				)
			)
		)
		(property "Value" "2N7002-11-GP"
			(at 0.127 -8.9662 180)
			(unlocked yes)
			(layer "F.Fab")
			(hide yes)
			(effects
				(font
					(size 1.016 1.016)
					(thickness 0.1524)
				)
			)
		)
		(property "Device Type" "SOT23DGS2D4H44"
			(at 0.127 -10.4902 180)
			(unlocked yes)
			(layer "F.Fab")
			(hide yes)
			(effects
				(font
					(size 1.016 1.016)
					(thickness 0.1524)
				)
			)
		)
		(duplicate_pad_numbers_are_jumpers no)
		(fp_line
			(start 1.651 1.778)
			(end 1.651 -1.778)
			(stroke
				(width 0.1524)
				(type default)
			)
			(layer "F.SilkS")
		)
		(fp_line
			(start 1.651 -1.778)
			(end -1.651 -1.778)
			(stroke
				(width 0.1524)
				(type default)
			)
			(layer "F.SilkS")
		)
		(fp_line
			(start -1.651 1.778)
			(end 1.651 1.778)
			(stroke
				(width 0.1524)
				(type default)
			)
			(layer "F.SilkS")
		)
		(fp_line
			(start -1.651 -1.778)
			(end -1.651 1.778)
			(stroke
				(width 0.1524)
				(type default)
			)
			(layer "F.SilkS")
		)
		(fp_poly
			(pts
				(xy -1.778 1.8796) (xy -1.778 -1.8796) (xy 1.778 -1.8796) (xy 1.778 1.8796)
			)
			(stroke
				(width 0)
				(type default)
			)
			(fill no)
			(layer "F.CrtYd")
		)
		(fp_poly
			(pts
				(xy -1.778 1.8796) (xy -1.778 -1.8796) (xy 1.778 -1.8796) (xy 1.778 1.8796)
			)
			(stroke
				(width 0)
				(type default)
			)
			(fill no)
			(layer "F.Fab")
		)
		(pad "D" smd custom
			(at 0 -0.9525 180)
			(size 0.1905 0.1905)
			(layers "F.Cu" "F.Mask" "F.Paste")
			(net "HDD1_LED_G")
			(options
				(clearance outline)
				(anchor circle)
			)
			(primitives
				(gr_poly
					(pts
						(arc
							(start -0.1778 0.5715)
							(mid -0.321484 0.511984)
							(end -0.381 0.3683)
						)
						(arc
							(start -0.381 -0.3683)
							(mid -0.321484 -0.511984)
							(end -0.1778 -0.5715)
						)
						(arc
							(start 0.1778 -0.5715)
							(mid 0.321484 -0.511984)
							(end 0.381 -0.3683)
						)
						(arc
							(start 0.381 0.3683)
							(mid 0.321484 0.511984)
							(end 0.1778 0.5715)
						)
					)
					(width 0)
					(fill yes)
				)
			)
		)
		(pad "G" smd custom
			(at -0.98425 0.9525 180)
			(size 0.1905 0.1905)
			(layers "F.Cu" "F.Mask" "F.Paste")
			(net "HDD1_LED_B")
			(options
				(clearance outline)
				(anchor circle)
			)
			(primitives
				(gr_poly
					(pts
						(arc
							(start -0.1778 0.5715)
							(mid -0.321484 0.511984)
							(end -0.381 0.3683)
						)
						(arc
							(start -0.381 -0.3683)
							(mid -0.321484 -0.511984)
							(end -0.1778 -0.5715)
						)
						(arc
							(start 0.1778 -0.5715)
							(mid 0.321484 -0.511984)
							(end 0.381 -0.3683)
						)
						(arc
							(start 0.381 0.3683)
							(mid 0.321484 0.511984)
							(end 0.1778 0.5715)
						)
					)
					(width 0)
					(fill yes)
				)
			)
		)
		(pad "S" smd custom
			(at 0.98425 0.9525 180)
			(size 0.1905 0.1905)
			(layers "F.Cu" "F.Mask" "F.Paste")
			(net "GND")
			(options
				(clearance outline)
				(anchor circle)
			)
			(primitives
				(gr_poly
					(pts
						(arc
							(start -0.1778 0.5715)
							(mid -0.321484 0.511984)
							(end -0.381 0.3683)
						)
						(arc
							(start -0.381 -0.3683)
							(mid -0.321484 -0.511984)
							(end -0.1778 -0.5715)
						)
						(arc
							(start 0.1778 -0.5715)
							(mid 0.321484 -0.511984)
							(end 0.381 -0.3683)
						)
						(arc
							(start 0.381 0.3683)
							(mid 0.321484 0.511984)
							(end 0.1778 0.5715)
						)
					)
					(width 0)
					(fill yes)
				)
			)
		)
	)
	(footprint ""
		(layer "F.Cu")
		(at 29.463746 -421.541702 90)
		(property "Reference" "R250"
			(at 0 0 90)
			(layer "F.SilkS")
			(hide yes)
			(effects
				(font
					(size 1.27 1.27)
				)
			)
		)
		(property "Value" "2R2010J-1-GP"
			(at 0.254 -8.0772 90)
			(unlocked yes)
			(layer "F.Fab")
			(hide yes)
			(effects
				(font
					(size 1.016 1.016)
					(thickness 0.1524)
				)
			)
		)
		(property "Device Type" "R2010H28"
			(at 0.254 -9.6774 90)
			(unlocked yes)
			(layer "F.Fab")
			(hide yes)
			(effects
				(font
					(size 1.016 1.016)
					(thickness 0.1524)
				)
			)
		)
		(duplicate_pad_numbers_are_jumpers no)
		(fp_line
			(start 1.651 -3.302)
			(end -1.651 -3.302)
			(stroke
				(width 0.1524)
				(type default)
			)
			(layer "F.SilkS")
		)
		(fp_line
			(start -1.651 -3.302)
			(end -1.651 3.302)
			(stroke
				(width 0.1524)
				(type default)
			)
			(layer "F.SilkS")
		)
		(fp_line
			(start 1.651 3.302)
			(end 1.651 -3.302)
			(stroke
				(width 0.1524)
				(type default)
			)
			(layer "F.SilkS")
		)
		(fp_line
			(start -1.651 3.302)
			(end 1.651 3.302)
			(stroke
				(width 0.1524)
				(type default)
			)
			(layer "F.SilkS")
		)
		(fp_rect
			(start -1.7272 -3.3782)
			(end 1.7272 3.3782)
			(stroke
				(width 0)
				(type default)
			)
			(fill no)
			(layer "F.CrtYd")
		)
		(fp_poly
			(pts
				(xy 1.7272 3.3782) (xy 1.7272 -3.3782) (xy -1.7272 -3.3782) (xy -1.7272 3.3782)
			)
			(stroke
				(width 0)
				(type default)
			)
			(fill no)
			(layer "F.Fab")
		)
		(pad "1" smd rect
			(at 0 -2.3495 90)
			(size 2.794 1.143)
			(layers "F.Cu" "F.Mask" "F.Paste")
			(net "12V_PRE_10")
		)
		(pad "2" smd rect
			(at 0 2.3495 90)
			(size 2.794 1.143)
			(layers "F.Cu" "F.Mask" "F.Paste")
			(net "P12V_HDD10")
		)
	)
	(footprint ""
		(layer "F.Cu")
		(at 30.606746 -314.734702)
		(property "Reference" "C289"
			(at 0 0 0)
			(layer "F.SilkS")
			(hide yes)
			(effects
				(font
					(size 1.27 1.27)
				)
			)
		)
		(property "Value" "SC10U25V6KX-1GP"
			(at -0.0762 -5.1308 0)
			(unlocked yes)
			(layer "F.Fab")
			(hide yes)
			(effects
				(font
					(size 1.016 1.016)
					(thickness 0.1524)
				)
			)
		)
		(property "Device Type" "C1206H71"
			(at -0.127 -6.6548 0)
			(unlocked yes)
			(layer "F.Fab")
			(hide yes)
			(effects
				(font
					(size 1.016 1.016)
					(thickness 0.1524)
				)
			)
		)
		(duplicate_pad_numbers_are_jumpers no)
		(fp_line
			(start -1.016 -2.2352)
			(end 1.016 -2.2352)
			(stroke
				(width 0.1524)
				(type default)
			)
			(layer "F.SilkS")
		)
		(fp_line
			(start -1.016 -0.8382)
			(end -1.016 -2.2352)
			(stroke
				(width 0.1524)
				(type default)
			)
			(layer "F.SilkS")
		)
		(fp_line
			(start -1.016 2.2352)
			(end -1.016 0.8382)
			(stroke
				(width 0.1524)
				(type default)
			)
			(layer "F.SilkS")
		)
		(fp_line
			(start 1.016 -2.2352)
			(end 1.016 -0.8382)
			(stroke
				(width 0.1524)
				(type default)
			)
			(layer "F.SilkS")
		)
		(fp_line
			(start 1.016 0.8382)
			(end 1.016 2.2352)
			(stroke
				(width 0.1524)
				(type default)
			)
			(layer "F.SilkS")
		)
		(fp_line
			(start 1.016 2.2352)
			(end -1.016 2.2352)
			(stroke
				(width 0.1524)
				(type default)
			)
			(layer "F.SilkS")
		)
		(fp_rect
			(start -1.0922 2.3114)
			(end 1.0922 -2.3114)
			(stroke
				(width 0)
				(type default)
			)
			(fill no)
			(layer "F.CrtYd")
		)
		(fp_poly
			(pts
				(xy 1.0922 -2.3114) (xy 1.0922 2.3114) (xy -1.0922 2.3114) (xy -1.0922 -2.3114)
			)
			(stroke
				(width 0)
				(type default)
			)
			(fill no)
			(layer "F.Fab")
		)
		(pad "1" smd rect
			(at 0 -1.397)
			(size 1.651 1.27)
			(layers "F.Cu" "F.Mask" "F.Paste")
			(net "P12V_HDD11")
		)
		(pad "2" smd rect
			(at 0 1.397)
			(size 1.651 1.27)
			(layers "F.Cu" "F.Mask" "F.Paste")
			(net "GND")
		)
	)
	(footprint ""
		(layer "F.Cu")
		(at 218.053412 -70.973696)
		(property "Reference" "C178"
			(at 0 0 0)
			(layer "F.SilkS")
			(hide yes)
			(effects
				(font
					(size 1.27 1.27)
				)
			)
		)
		(property "Value" "SCD01U50V2KX-1GP"
			(at 1.1811 -2.7051 0)
			(unlocked yes)
			(layer "F.Fab")
			(hide yes)
			(effects
				(font
					(size 1.016 1.016)
					(thickness 0.1524)
				)
			)
		)
		(property "Device Type" "C402H22"
			(at 1.1811 -4.2291 0)
			(unlocked yes)
			(layer "F.Fab")
			(hide yes)
			(effects
				(font
					(size 1.016 1.016)
					(thickness 0.1524)
				)
			)
		)
		(duplicate_pad_numbers_are_jumpers no)
		(fp_rect
			(start -0.4318 0.9525)
			(end 0.4318 -0.9525)
			(stroke
				(width 0)
				(type default)
			)
			(fill no)
			(layer "F.CrtYd")
		)
		(fp_rect
			(start -0.4318 0.9525)
			(end 0.4318 -0.9525)
			(stroke
				(width 0)
				(type default)
			)
			(fill no)
			(layer "F.Fab")
		)
		(pad "1" smd custom
			(at 0 -0.4445)
			(size 0.1524 0.1524)
			(layers "F.Cu" "F.Mask" "F.Paste")
			(net "HDD_PRSNT_NET4")
			(options
				(clearance outline)
				(anchor circle)
			)
			(primitives
				(gr_poly
					(pts
						(arc
							(start 0.3048 -0.2032)
							(mid 0.275042 -0.275042)
							(end 0.2032 -0.3048)
						)
						(arc
							(start -0.2032 -0.3048)
							(mid -0.275042 -0.275042)
							(end -0.3048 -0.2032)
						)
						(arc
							(start -0.3048 0.2032)
							(mid -0.275042 0.275042)
							(end -0.2032 0.3048)
						)
						(arc
							(start 0.2032 0.3048)
							(mid 0.275042 0.275042)
							(end 0.3048 0.2032)
						)
					)
					(width 0)
					(fill yes)
				)
			)
		)
		(pad "2" smd custom
			(at 0 0.4445)
			(size 0.1524 0.1524)
			(layers "F.Cu" "F.Mask" "F.Paste")
			(net "GND")
			(options
				(clearance outline)
				(anchor circle)
			)
			(primitives
				(gr_poly
					(pts
						(arc
							(start 0.3048 -0.2032)
							(mid 0.275042 -0.275042)
							(end 0.2032 -0.3048)
						)
						(arc
							(start -0.2032 -0.3048)
							(mid -0.275042 -0.275042)
							(end -0.3048 -0.2032)
						)
						(arc
							(start -0.3048 0.2032)
							(mid -0.275042 0.275042)
							(end -0.2032 0.3048)
						)
						(arc
							(start 0.2032 0.3048)
							(mid 0.275042 0.275042)
							(end 0.3048 0.2032)
						)
					)
					(width 0)
					(fill yes)
				)
			)
		)
	)
	(footprint ""
		(layer "F.Cu")
		(at 57.356756 -489.105702 180)
		(property "Reference" "C189"
			(at 0 0 180)
			(layer "F.SilkS")
			(hide yes)
			(effects
				(font
					(size 1.27 1.27)
				)
			)
		)
		(property "Value" "SC10U16V6KX-2GP"
			(at -0.0762 -5.1308 180)
			(unlocked yes)
			(layer "F.Fab")
			(hide yes)
			(effects
				(font
					(size 1.016 1.016)
					(thickness 0.1524)
				)
			)
		)
		(property "Device Type" "C1206H71"
			(at -0.127 -6.6548 180)
			(unlocked yes)
			(layer "F.Fab")
			(hide yes)
			(effects
				(font
					(size 1.016 1.016)
					(thickness 0.1524)
				)
			)
		)
		(duplicate_pad_numbers_are_jumpers no)
		(fp_line
			(start 1.016 2.2352)
			(end -1.016 2.2352)
			(stroke
				(width 0.1524)
				(type default)
			)
			(layer "F.SilkS")
		)
		(fp_line
			(start 1.016 0.8382)
			(end 1.016 2.2352)
			(stroke
				(width 0.1524)
				(type default)
			)
			(layer "F.SilkS")
		)
		(fp_line
			(start 1.016 -2.2352)
			(end 1.016 -0.8382)
			(stroke
				(width 0.1524)
				(type default)
			)
			(layer "F.SilkS")
		)
		(fp_line
			(start -1.016 2.2352)
			(end -1.016 0.8382)
			(stroke
				(width 0.1524)
				(type default)
			)
			(layer "F.SilkS")
		)
		(fp_line
			(start -1.016 -0.8382)
			(end -1.016 -2.2352)
			(stroke
				(width 0.1524)
				(type default)
			)
			(layer "F.SilkS")
		)
		(fp_line
			(start -1.016 -2.2352)
			(end 1.016 -2.2352)
			(stroke
				(width 0.1524)
				(type default)
			)
			(layer "F.SilkS")
		)
		(fp_rect
			(start -1.0922 2.3114)
			(end 1.0922 -2.3114)
			(stroke
				(width 0)
				(type default)
			)
			(fill no)
			(layer "F.CrtYd")
		)
		(fp_poly
			(pts
				(xy 1.0922 -2.3114) (xy 1.0922 2.3114) (xy -1.0922 2.3114) (xy -1.0922 -2.3114)
			)
			(stroke
				(width 0)
				(type default)
			)
			(fill no)
			(layer "F.Fab")
		)
		(pad "1" smd rect
			(at 0 -1.397 180)
			(size 1.651 1.27)
			(layers "F.Cu" "F.Mask" "F.Paste")
			(net "P5V_HDD5")
		)
		(pad "2" smd rect
			(at 0 1.397 180)
			(size 1.651 1.27)
			(layers "F.Cu" "F.Mask" "F.Paste")
			(net "GND")
		)
	)
	(footprint ""
		(layer "F.Cu")
		(at 43.179746 -29.9847 180)
		(property "Reference" "PC26"
			(at 0 0 180)
			(layer "F.SilkS")
			(hide yes)
			(effects
				(font
					(size 1.27 1.27)
				)
			)
		)
		(property "Value" "SC10U16V6KX-2GP"
			(at -0.0762 -5.1308 180)
			(unlocked yes)
			(layer "F.Fab")
			(hide yes)
			(effects
				(font
					(size 1.016 1.016)
					(thickness 0.1524)
				)
			)
		)
		(property "Device Type" "C1206H71"
			(at -0.127 -6.6548 180)
			(unlocked yes)
			(layer "F.Fab")
			(hide yes)
			(effects
				(font
					(size 1.016 1.016)
					(thickness 0.1524)
				)
			)
		)
		(duplicate_pad_numbers_are_jumpers no)
		(fp_line
			(start 1.016 2.2352)
			(end -1.016 2.2352)
			(stroke
				(width 0.1524)
				(type default)
			)
			(layer "F.SilkS")
		)
		(fp_line
			(start 1.016 0.8382)
			(end 1.016 2.2352)
			(stroke
				(width 0.1524)
				(type default)
			)
			(layer "F.SilkS")
		)
		(fp_line
			(start 1.016 -2.2352)
			(end 1.016 -0.8382)
			(stroke
				(width 0.1524)
				(type default)
			)
			(layer "F.SilkS")
		)
		(fp_line
			(start -1.016 2.2352)
			(end -1.016 0.8382)
			(stroke
				(width 0.1524)
				(type default)
			)
			(layer "F.SilkS")
		)
		(fp_line
			(start -1.016 -0.8382)
			(end -1.016 -2.2352)
			(stroke
				(width 0.1524)
				(type default)
			)
			(layer "F.SilkS")
		)
		(fp_line
			(start -1.016 -2.2352)
			(end 1.016 -2.2352)
			(stroke
				(width 0.1524)
				(type default)
			)
			(layer "F.SilkS")
		)
		(fp_rect
			(start -1.0922 2.3114)
			(end 1.0922 -2.3114)
			(stroke
				(width 0)
				(type default)
			)
			(fill no)
			(layer "F.CrtYd")
		)
		(fp_poly
			(pts
				(xy 1.0922 -2.3114) (xy 1.0922 2.3114) (xy -1.0922 2.3114) (xy -1.0922 -2.3114)
			)
			(stroke
				(width 0)
				(type default)
			)
			(fill no)
			(layer "F.Fab")
		)
		(pad "1" smd rect
			(at 0 -1.397 180)
			(size 1.651 1.27)
			(layers "F.Cu" "F.Mask" "F.Paste")
			(net "P5VB")
		)
		(pad "2" smd rect
			(at 0 1.397 180)
			(size 1.651 1.27)
			(layers "F.Cu" "F.Mask" "F.Paste")
			(net "GND")
		)
	)
	(footprint ""
		(layer "F.Cu")
		(at 45.338746 -245.7577 90)
		(property "Reference" "R202"
			(at 0 0 90)
			(layer "F.SilkS")
			(hide yes)
			(effects
				(font
					(size 1.27 1.27)
				)
			)
		)
		(property "Value" "0R2J-2-GP"
			(at 0.064008 -3.993896 90)
			(unlocked yes)
			(layer "F.Fab")
			(hide yes)
			(effects
				(font
					(size 1.016 1.016)
					(thickness 0.1524)
				)
			)
		)
		(property "Device Type" "R402H16"
			(at 0.064008 -5.517896 90)
			(unlocked yes)
			(layer "F.Fab")
			(hide yes)
			(effects
				(font
					(size 1.016 1.016)
					(thickness 0.1524)
				)
			)
		)
		(duplicate_pad_numbers_are_jumpers no)
		(fp_line
			(start 0.508 -0.9398)
			(end -0.508 -0.9398)
			(stroke
				(width 0.1524)
				(type default)
			)
			(layer "F.SilkS")
		)
		(fp_line
			(start -0.508 -0.9398)
			(end -0.508 0.9398)
			(stroke
				(width 0.1524)
				(type default)
			)
			(layer "F.SilkS")
		)
		(fp_rect
			(start -0.508 0.9398)
			(end 0.508 -0.9398)
			(stroke
				(width 0)
				(type default)
			)
			(fill no)
			(layer "F.CrtYd")
		)
		(fp_rect
			(start -0.508 0.9398)
			(end 0.508 -0.9398)
			(stroke
				(width 0)
				(type default)
			)
			(fill no)
			(layer "F.Fab")
		)
		(pad "1" smd custom
			(at 0 -0.4445 90)
			(size 0.1397 0.1397)
			(layers "F.Cu" "F.Mask" "F.Paste")
			(net "FLT_NET_HDD7")
			(options
				(clearance outline)
				(anchor circle)
			)
			(primitives
				(gr_poly
					(pts
						(arc
							(start -0.1778 -0.2794)
							(mid -0.249642 -0.249642)
							(end -0.2794 -0.1778)
						)
						(arc
							(start -0.2794 0.1778)
							(mid -0.249642 0.249642)
							(end -0.1778 0.2794)
						)
						(arc
							(start 0.1778 0.2794)
							(mid 0.249642 0.249642)
							(end 0.2794 0.1778)
						)
						(arc
							(start 0.2794 -0.1778)
							(mid 0.249642 -0.249642)
							(end 0.1778 -0.2794)
						)
					)
					(width 0)
					(fill yes)
				)
			)
		)
		(pad "2" smd custom
			(at 0 0.4445 90)
			(size 0.1397 0.1397)
			(layers "F.Cu" "F.Mask" "F.Paste")
			(net "FLT_HDD7_DRIVE")
			(options
				(clearance outline)
				(anchor circle)
			)
			(primitives
				(gr_poly
					(pts
						(arc
							(start -0.1778 -0.2794)
							(mid -0.249642 -0.249642)
							(end -0.2794 -0.1778)
						)
						(arc
							(start -0.2794 0.1778)
							(mid -0.249642 0.249642)
							(end -0.1778 0.2794)
						)
						(arc
							(start 0.1778 0.2794)
							(mid 0.249642 0.249642)
							(end 0.2794 0.1778)
						)
						(arc
							(start 0.2794 -0.1778)
							(mid 0.249642 -0.249642)
							(end 0.1778 -0.2794)
						)
					)
					(width 0)
					(fill yes)
				)
			)
		)
	)
	(footprint ""
		(layer "F.Cu")
		(at 45.974 -105.283 90)
		(property "Reference" "D28"
			(at 0 0 90)
			(layer "F.SilkS")
			(hide yes)
			(effects
				(font
					(size 1.27 1.27)
				)
			)
		)
		(property "Value" "RB551V30-1-GP"
			(at 0 -6.7818 90)
			(unlocked yes)
			(layer "F.Fab")
			(hide yes)
			(effects
				(font
					(size 1.016 1.016)
					(thickness 0.1524)
				)
			)
		)
		(property "Device Type" "SOD323AKH44"
			(at 0 -8.6868 90)
			(unlocked yes)
			(layer "F.Fab")
			(hide yes)
			(effects
				(font
					(size 1.016 1.016)
					(thickness 0.1524)
				)
			)
		)
		(duplicate_pad_numbers_are_jumpers no)
		(fp_line
			(start 0.889 -1.9304)
			(end 0.889 2.159)
			(stroke
				(width 0.1524)
				(type default)
			)
			(layer "F.SilkS")
		)
		(fp_line
			(start -0.889 -1.9304)
			(end 0.889 -1.9304)
			(stroke
				(width 0.1524)
				(type default)
			)
			(layer "F.SilkS")
		)
		(fp_line
			(start 0.762 2.0574)
			(end -0.762 2.0574)
			(stroke
				(width 0.508)
				(type default)
			)
			(layer "F.SilkS")
		)
		(fp_line
			(start 0.889 2.159)
			(end -0.889 2.159)
			(stroke
				(width 0.1524)
				(type default)
			)
			(layer "F.SilkS")
		)
		(fp_line
			(start -0.889 2.159)
			(end -0.889 -1.9304)
			(stroke
				(width 0.1524)
				(type default)
			)
			(layer "F.SilkS")
		)
		(fp_rect
			(start -1.016 2.3114)
			(end 1.016 -2.0066)
			(stroke
				(width 0)
				(type default)
			)
			(fill no)
			(layer "F.CrtYd")
		)
		(fp_poly
			(pts
				(xy -1.016 -2.0066) (xy 1.016 -2.0066) (xy 1.016 2.3114) (xy -1.016 2.3114)
			)
			(stroke
				(width 0)
				(type default)
			)
			(fill no)
			(layer "F.Fab")
		)
		(pad "A" smd rect
			(at 0 -1.143 90)
			(size 0.5588 1.016)
			(layers "F.Cu" "F.Mask" "F.Paste")
			(net "SW_HDD13_R")
		)
		(pad "K" smd rect
			(at 0 1.143 90)
			(size 0.5588 1.016)
			(layers "F.Cu" "F.Mask" "F.Paste")
			(net "SW_HDD13_N")
		)
	)
	(footprint ""
		(layer "F.Cu")
		(at 197.230746 -491.5027 -90)
		(property "Reference" "R424"
			(at 0 0 270)
			(layer "F.SilkS")
			(hide yes)
			(effects
				(font
					(size 1.27 1.27)
				)
			)
		)
		(property "Value" "4K7R2J-2-GP"
			(at 0.064008 -3.993896 270)
			(unlocked yes)
			(layer "F.Fab")
			(hide yes)
			(effects
				(font
					(size 1.016 1.016)
					(thickness 0.1524)
				)
			)
		)
		(property "Device Type" "R402H16"
			(at 0.064008 -5.517896 270)
			(unlocked yes)
			(layer "F.Fab")
			(hide yes)
			(effects
				(font
					(size 1.016 1.016)
					(thickness 0.1524)
				)
			)
		)
		(duplicate_pad_numbers_are_jumpers no)
		(fp_line
			(start -0.508 -0.9398)
			(end -0.508 0.9398)
			(stroke
				(width 0.1524)
				(type default)
			)
			(layer "F.SilkS")
		)
		(fp_line
			(start 0.508 -0.9398)
			(end -0.508 -0.9398)
			(stroke
				(width 0.1524)
				(type default)
			)
			(layer "F.SilkS")
		)
		(fp_rect
			(start -0.508 0.9398)
			(end 0.508 -0.9398)
			(stroke
				(width 0)
				(type default)
			)
			(fill no)
			(layer "F.CrtYd")
		)
		(fp_rect
			(start -0.508 0.9398)
			(end 0.508 -0.9398)
			(stroke
				(width 0)
				(type default)
			)
			(fill no)
			(layer "F.Fab")
		)
		(pad "1" smd custom
			(at 0 -0.4445 270)
			(size 0.1397 0.1397)
			(layers "F.Cu" "F.Mask" "F.Paste")
			(net "P3V3")
			(options
				(clearance outline)
				(anchor circle)
			)
			(primitives
				(gr_poly
					(pts
						(arc
							(start -0.1778 -0.2794)
							(mid -0.249642 -0.249642)
							(end -0.2794 -0.1778)
						)
						(arc
							(start -0.2794 0.1778)
							(mid -0.249642 0.249642)
							(end -0.1778 0.2794)
						)
						(arc
							(start 0.1778 0.2794)
							(mid 0.249642 0.249642)
							(end 0.2794 0.1778)
						)
						(arc
							(start 0.2794 -0.1778)
							(mid 0.249642 -0.249642)
							(end 0.1778 -0.2794)
						)
					)
					(width 0)
					(fill yes)
				)
			)
		)
		(pad "2" smd custom
			(at 0 0.4445 270)
			(size 0.1397 0.1397)
			(layers "F.Cu" "F.Mask" "F.Paste")
			(net "SAS_EXP_B_PWR0")
			(options
				(clearance outline)
				(anchor circle)
			)
			(primitives
				(gr_poly
					(pts
						(arc
							(start -0.1778 -0.2794)
							(mid -0.249642 -0.249642)
							(end -0.2794 -0.1778)
						)
						(arc
							(start -0.2794 0.1778)
							(mid -0.249642 0.249642)
							(end -0.1778 0.2794)
						)
						(arc
							(start 0.1778 0.2794)
							(mid 0.249642 0.249642)
							(end 0.2794 0.1778)
						)
						(arc
							(start 0.2794 -0.1778)
							(mid 0.249642 -0.249642)
							(end 0.1778 -0.2794)
						)
					)
					(width 0)
					(fill yes)
				)
			)
		)
	)
	(footprint ""
		(layer "F.Cu")
		(at 16.306546 -468.0204 -90)
		(property "Reference" "Q44"
			(at 0 0 270)
			(layer "F.SilkS")
			(hide yes)
			(effects
				(font
					(size 1.27 1.27)
				)
			)
		)
		(property "Value" "PMBS3904-1-GP"
			(at 0 -9.0932 270)
			(unlocked yes)
			(layer "F.Fab")
			(hide yes)
			(effects
				(font
					(size 1.016 1.016)
					(thickness 0.1524)
				)
			)
		)
		(property "Device Type" "SOT-23-10H44"
			(at 0 -10.6172 270)
			(unlocked yes)
			(layer "F.Fab")
			(hide yes)
			(effects
				(font
					(size 1.016 1.016)
					(thickness 0.1524)
				)
			)
		)
		(duplicate_pad_numbers_are_jumpers no)
		(fp_line
			(start -1.279144 2.15265)
			(end -0.701294 2.15265)
			(stroke
				(width 0.0127)
				(type default)
			)
			(layer "F.SilkS")
		)
		(fp_line
			(start -0.71628 2.15265)
			(end -1.26492 2.15265)
			(stroke
				(width 0.0127)
				(type default)
			)
			(layer "F.SilkS")
		)
		(fp_line
			(start -1.279398 2.152142)
			(end -0.9906 1.86309)
			(stroke
				(width 0.0127)
				(type default)
			)
			(layer "F.SilkS")
		)
		(fp_line
			(start -0.719074 2.145538)
			(end -1.265936 2.14122)
			(stroke
				(width 0.0127)
				(type default)
			)
			(layer "F.SilkS")
		)
		(fp_line
			(start -1.260856 2.1336)
			(end -0.720344 2.1336)
			(stroke
				(width 0.0127)
				(type default)
			)
			(layer "F.SilkS")
		)
		(fp_line
			(start -1.251458 2.124202)
			(end -0.729996 2.124202)
			(stroke
				(width 0.0127)
				(type default)
			)
			(layer "F.SilkS")
		)
		(fp_line
			(start -1.241806 2.11455)
			(end -0.739394 2.11455)
			(stroke
				(width 0.0127)
				(type default)
			)
			(layer "F.SilkS")
		)
		(fp_line
			(start -1.232408 2.105152)
			(end -0.749046 2.105152)
			(stroke
				(width 0.0127)
				(type default)
			)
			(layer "F.SilkS")
		)
		(fp_line
			(start -1.222756 2.0955)
			(end -0.758444 2.0955)
			(stroke
				(width 0.0127)
				(type default)
			)
			(layer "F.SilkS")
		)
		(fp_line
			(start -1.213358 2.086102)
			(end -0.768096 2.086102)
			(stroke
				(width 0.0127)
				(type default)
			)
			(layer "F.SilkS")
		)
		(fp_line
			(start -1.203706 2.07645)
			(end -0.777494 2.07645)
			(stroke
				(width 0.0127)
				(type default)
			)
			(layer "F.SilkS")
		)
		(fp_line
			(start -1.194308 2.067052)
			(end -0.787146 2.067052)
			(stroke
				(width 0.0127)
				(type default)
			)
			(layer "F.SilkS")
		)
		(fp_line
			(start -1.184656 2.0574)
			(end -0.796544 2.0574)
			(stroke
				(width 0.0127)
				(type default)
			)
			(layer "F.SilkS")
		)
		(fp_line
			(start -1.175258 2.048002)
			(end -0.806196 2.048002)
			(stroke
				(width 0.0127)
				(type default)
			)
			(layer "F.SilkS")
		)
		(fp_line
			(start -1.165606 2.03835)
			(end -0.815594 2.03835)
			(stroke
				(width 0.0127)
				(type default)
			)
			(layer "F.SilkS")
		)
		(fp_line
			(start -1.156208 2.028952)
			(end -0.825246 2.028952)
			(stroke
				(width 0.0127)
				(type default)
			)
			(layer "F.SilkS")
		)
		(fp_line
			(start -1.146556 2.0193)
			(end -0.834644 2.0193)
			(stroke
				(width 0.0127)
				(type default)
			)
			(layer "F.SilkS")
		)
		(fp_line
			(start -1.137158 2.009902)
			(end -0.844296 2.009902)
			(stroke
				(width 0.0127)
				(type default)
			)
			(layer "F.SilkS")
		)
		(fp_line
			(start -1.127506 2.00025)
			(end -0.853694 2.00025)
			(stroke
				(width 0.0127)
				(type default)
			)
			(layer "F.SilkS")
		)
		(fp_line
			(start -1.118108 1.990852)
			(end -0.863346 1.990852)
			(stroke
				(width 0.0127)
				(type default)
			)
			(layer "F.SilkS")
		)
		(fp_line
			(start -1.108456 1.9812)
			(end -0.872744 1.9812)
			(stroke
				(width 0.0127)
				(type default)
			)
			(layer "F.SilkS")
		)
		(fp_line
			(start -1.099058 1.971802)
			(end -0.882396 1.971802)
			(stroke
				(width 0.0127)
				(type default)
			)
			(layer "F.SilkS")
		)
		(fp_line
			(start -1.089406 1.96215)
			(end -0.891794 1.96215)
			(stroke
				(width 0.0127)
				(type default)
			)
			(layer "F.SilkS")
		)
		(fp_line
			(start -1.080008 1.952752)
			(end -0.901446 1.952752)
			(stroke
				(width 0.0127)
				(type default)
			)
			(layer "F.SilkS")
		)
		(fp_line
			(start -1.070356 1.9431)
			(end -0.910844 1.9431)
			(stroke
				(width 0.0127)
				(type default)
			)
			(layer "F.SilkS")
		)
		(fp_line
			(start -1.060958 1.933702)
			(end -0.920496 1.933702)
			(stroke
				(width 0.0127)
				(type default)
			)
			(layer "F.SilkS")
		)
		(fp_line
			(start -1.051306 1.92405)
			(end -0.929894 1.92405)
			(stroke
				(width 0.0127)
				(type default)
			)
			(layer "F.SilkS")
		)
		(fp_line
			(start -1.041908 1.914652)
			(end -0.939546 1.914652)
			(stroke
				(width 0.0127)
				(type default)
			)
			(layer "F.SilkS")
		)
		(fp_line
			(start -1.032256 1.905)
			(end -0.948944 1.905)
			(stroke
				(width 0.0127)
				(type default)
			)
			(layer "F.SilkS")
		)
		(fp_line
			(start -1.022858 1.895602)
			(end -0.958596 1.895602)
			(stroke
				(width 0.0127)
				(type default)
			)
			(layer "F.SilkS")
		)
		(fp_line
			(start -1.013206 1.88595)
			(end -0.967994 1.88595)
			(stroke
				(width 0.0127)
				(type default)
			)
			(layer "F.SilkS")
		)
		(fp_line
			(start -1.7526 1.8796)
			(end -1.7526 0.9906)
			(stroke
				(width 0.3302)
				(type default)
			)
			(layer "F.SilkS")
		)
		(fp_line
			(start -0.635 1.8796)
			(end -1.7526 1.8796)
			(stroke
				(width 0.3302)
				(type default)
			)
			(layer "F.SilkS")
		)
		(fp_line
			(start -1.003808 1.876552)
			(end -0.977646 1.876552)
			(stroke
				(width 0.0127)
				(type default)
			)
			(layer "F.SilkS")
		)
		(fp_line
			(start -0.994156 1.8669)
			(end -0.987044 1.8669)
			(stroke
				(width 0.0127)
				(type default)
			)
			(layer "F.SilkS")
		)
		(fp_line
			(start -0.9906 1.86309)
			(end -0.701294 2.15265)
			(stroke
				(width 0.0127)
				(type default)
			)
			(layer "F.SilkS")
		)
		(fp_line
			(start -1.651 1.778)
			(end 1.651 1.778)
			(stroke
				(width 0.1524)
				(type default)
			)
			(layer "F.SilkS")
		)
		(fp_line
			(start 1.651 1.778)
			(end 1.651 -1.778)
			(stroke
				(width 0.1524)
				(type default)
			)
			(layer "F.SilkS")
		)
		(fp_line
			(start -1.651 -1.778)
			(end -1.651 1.778)
			(stroke
				(width 0.1524)
				(type default)
			)
			(layer "F.SilkS")
		)
		(fp_line
			(start 1.651 -1.778)
			(end -1.651 -1.778)
			(stroke
				(width 0.1524)
				(type default)
			)
			(layer "F.SilkS")
		)
		(fp_poly
			(pts
				(xy -1.285748 2.159) (xy -1.285748 1.8796) (xy -1.778 1.8796) (xy -1.778 -1.8796) (xy 1.778 -1.8796)
				(xy 1.778 1.8796) (xy -0.694944 1.8796) (xy -0.694944 2.159)
			)
			(stroke
				(width 0)
				(type default)
			)
			(fill no)
			(layer "F.CrtYd")
		)
		(fp_poly
			(pts
				(xy -1.285748 2.159) (xy -1.285748 1.8796) (xy -1.778 1.8796) (xy -1.778 -1.8796) (xy 1.778 -1.8796)
				(xy 1.778 1.8796) (xy -0.694944 1.8796) (xy -0.694944 2.159)
			)
			(stroke
				(width 0)
				(type default)
			)
			(fill no)
			(layer "F.Fab")
		)
		(pad "1" smd rect
			(at -0.98425 0.9525 270)
			(size 0.762 1.143)
			(layers "F.Cu" "F.Mask" "F.Paste")
			(net "FLT_HDD10_B")
		)
		(pad "2" smd rect
			(at 0.98425 0.9525 270)
			(size 0.762 1.143)
			(layers "F.Cu" "F.Mask" "F.Paste")
			(net "GND")
		)
		(pad "3" smd rect
			(at 0 -0.9525 270)
			(size 0.762 1.143)
			(layers "F.Cu" "F.Mask" "F.Paste")
			(net "DRIVE_ACT_10")
		)
	)
	(footprint ""
		(layer "F.Cu")
		(at 67.055492 -76.863956 -90)
		(property "Reference" "Q19"
			(at 0 0 270)
			(layer "F.SilkS")
			(hide yes)
			(effects
				(font
					(size 1.27 1.27)
				)
			)
		)
		(property "Value" "AO4406AL-GP"
			(at -3.707384 -1.5367 270)
			(unlocked yes)
			(layer "F.Fab")
			(hide yes)
			(effects
				(font
					(size 1.016 1.016)
					(thickness 0.1524)
				)
			)
		)
		(property "Device Type" "SOIC8H69"
			(at -3.707384 -3.0607 270)
			(unlocked yes)
			(layer "F.Fab")
			(hide yes)
			(effects
				(font
					(size 1.016 1.016)
					(thickness 0.1524)
				)
			)
		)
		(duplicate_pad_numbers_are_jumpers no)
		(fp_line
			(start -2.6289 3.4417)
			(end -2.6289 1.4732)
			(stroke
				(width 0.381)
				(type default)
			)
			(layer "F.SilkS")
		)
		(fp_line
			(start -2.7432 1.4224)
			(end -2.6416 1.4224)
			(stroke
				(width 0.1524)
				(type default)
			)
			(layer "F.SilkS")
		)
		(fp_line
			(start -2.7432 1.4224)
			(end 2.1336 1.4224)
			(stroke
				(width 0.1524)
				(type default)
			)
			(layer "F.SilkS")
		)
		(fp_line
			(start 2.1336 1.4224)
			(end 2.1336 -1.4224)
			(stroke
				(width 0.1524)
				(type default)
			)
			(layer "F.SilkS")
		)
		(fp_line
			(start -2.1844 -0.0508)
			(end -2.7178 0.508)
			(stroke
				(width 0.1524)
				(type default)
			)
			(layer "F.SilkS")
		)
		(fp_line
			(start -2.7178 -0.508)
			(end -2.1844 -0.0508)
			(stroke
				(width 0.1524)
				(type default)
			)
			(layer "F.SilkS")
		)
		(fp_line
			(start -2.7432 -1.4224)
			(end -2.7432 1.4224)
			(stroke
				(width 0.1524)
				(type default)
			)
			(layer "F.SilkS")
		)
		(fp_line
			(start 2.1336 -1.4224)
			(end -2.7432 -1.4224)
			(stroke
				(width 0.1524)
				(type default)
			)
			(layer "F.SilkS")
		)
		(fp_poly
			(pts
				(xy -2.2098 -1.4224) (xy -2.2098 1.4224) (xy 2.2098 1.4224) (xy 2.2098 -1.4224)
			)
			(stroke
				(width 0)
				(type default)
			)
			(fill yes)
			(layer "F.SilkS")
		)
		(fp_rect
			(start -2.450084 2.999994)
			(end 2.450084 -2.999994)
			(stroke
				(width 0)
				(type default)
			)
			(fill no)
			(layer "F.CrtYd")
		)
		(fp_poly
			(pts
				(xy -2.8194 3.6322) (xy -2.8194 -3.6322) (xy 2.8194 -3.6322) (xy 2.8194 1.18364) (xy 2.450084 1.18364)
				(xy 2.450084 -2.999994) (xy -2.450084 -2.999994) (xy -2.450084 2.999994) (xy 2.450084 2.999994)
				(xy 2.450084 1.18618) (xy 2.8194 1.18618) (xy 2.8194 3.6322)
			)
			(stroke
				(width 0)
				(type default)
			)
			(fill no)
			(layer "F.CrtYd")
		)
		(fp_rect
			(start -2.8194 3.6322)
			(end 2.8194 -3.6322)
			(stroke
				(width 0)
				(type default)
			)
			(fill no)
			(layer "F.Fab")
		)
		(pad "1" smd rect
			(at -1.905 2.54 270)
			(size 0.635 1.651)
			(layers "F.Cu" "F.Mask" "F.Paste")
			(net "P5V_HDD9")
		)
		(pad "2" smd rect
			(at -0.635 2.54 270)
			(size 0.635 1.651)
			(layers "F.Cu" "F.Mask" "F.Paste")
			(net "P5V_HDD9")
		)
		(pad "3" smd rect
			(at 0.635 2.54 270)
			(size 0.635 1.651)
			(layers "F.Cu" "F.Mask" "F.Paste")
			(net "P5V_HDD9")
		)
		(pad "4" smd rect
			(at 1.905 2.54 270)
			(size 0.635 1.651)
			(layers "F.Cu" "F.Mask" "F.Paste")
			(net "SW_HDD9_P")
		)
		(pad "5" smd rect
			(at 1.905 -2.54 270)
			(size 0.635 1.651)
			(layers "F.Cu" "F.Mask" "F.Paste")
			(net "P5VB")
		)
		(pad "6" smd rect
			(at 0.635 -2.54 270)
			(size 0.635 1.651)
			(layers "F.Cu" "F.Mask" "F.Paste")
			(net "P5VB")
		)
		(pad "7" smd rect
			(at -0.635 -2.54 270)
			(size 0.635 1.651)
			(layers "F.Cu" "F.Mask" "F.Paste")
			(net "P5VB")
		)
		(pad "8" smd rect
			(at -1.905 -2.54 270)
			(size 0.635 1.651)
			(layers "F.Cu" "F.Mask" "F.Paste")
			(net "P5VB")
		)
	)
	(footprint ""
		(layer "F.Cu")
		(at 233.120946 -452.374 90)
		(property "Reference" "Q34"
			(at 0 0 90)
			(layer "F.SilkS")
			(hide yes)
			(effects
				(font
					(size 1.27 1.27)
				)
			)
		)
		(property "Value" "PMBS3904-1-GP"
			(at 0 -9.0932 90)
			(unlocked yes)
			(layer "F.Fab")
			(hide yes)
			(effects
				(font
					(size 1.016 1.016)
					(thickness 0.1524)
				)
			)
		)
		(property "Device Type" "SOT-23-10H44"
			(at 0 -10.6172 90)
			(unlocked yes)
			(layer "F.Fab")
			(hide yes)
			(effects
				(font
					(size 1.016 1.016)
					(thickness 0.1524)
				)
			)
		)
		(duplicate_pad_numbers_are_jumpers no)
		(fp_line
			(start 1.651 -1.778)
			(end -1.651 -1.778)
			(stroke
				(width 0.1524)
				(type default)
			)
			(layer "F.SilkS")
		)
		(fp_line
			(start -1.651 -1.778)
			(end -1.651 1.778)
			(stroke
				(width 0.1524)
				(type default)
			)
			(layer "F.SilkS")
		)
		(fp_line
			(start 1.651 1.778)
			(end 1.651 -1.778)
			(stroke
				(width 0.1524)
				(type default)
			)
			(layer "F.SilkS")
		)
		(fp_line
			(start -1.651 1.778)
			(end 1.651 1.778)
			(stroke
				(width 0.1524)
				(type default)
			)
			(layer "F.SilkS")
		)
		(fp_line
			(start -0.9906 1.86309)
			(end -0.701294 2.15265)
			(stroke
				(width 0.0127)
				(type default)
			)
			(layer "F.SilkS")
		)
		(fp_line
			(start -0.994156 1.8669)
			(end -0.987044 1.8669)
			(stroke
				(width 0.0127)
				(type default)
			)
			(layer "F.SilkS")
		)
		(fp_line
			(start -1.003808 1.876552)
			(end -0.977646 1.876552)
			(stroke
				(width 0.0127)
				(type default)
			)
			(layer "F.SilkS")
		)
		(fp_line
			(start -0.635 1.8796)
			(end -1.7526 1.8796)
			(stroke
				(width 0.3302)
				(type default)
			)
			(layer "F.SilkS")
		)
		(fp_line
			(start -1.7526 1.8796)
			(end -1.7526 0.9906)
			(stroke
				(width 0.3302)
				(type default)
			)
			(layer "F.SilkS")
		)
		(fp_line
			(start -1.013206 1.88595)
			(end -0.967994 1.88595)
			(stroke
				(width 0.0127)
				(type default)
			)
			(layer "F.SilkS")
		)
		(fp_line
			(start -1.022858 1.895602)
			(end -0.958596 1.895602)
			(stroke
				(width 0.0127)
				(type default)
			)
			(layer "F.SilkS")
		)
		(fp_line
			(start -1.032256 1.905)
			(end -0.948944 1.905)
			(stroke
				(width 0.0127)
				(type default)
			)
			(layer "F.SilkS")
		)
		(fp_line
			(start -1.041908 1.914652)
			(end -0.939546 1.914652)
			(stroke
				(width 0.0127)
				(type default)
			)
			(layer "F.SilkS")
		)
		(fp_line
			(start -1.051306 1.92405)
			(end -0.929894 1.92405)
			(stroke
				(width 0.0127)
				(type default)
			)
			(layer "F.SilkS")
		)
		(fp_line
			(start -1.060958 1.933702)
			(end -0.920496 1.933702)
			(stroke
				(width 0.0127)
				(type default)
			)
			(layer "F.SilkS")
		)
		(fp_line
			(start -1.070356 1.9431)
			(end -0.910844 1.9431)
			(stroke
				(width 0.0127)
				(type default)
			)
			(layer "F.SilkS")
		)
		(fp_line
			(start -1.080008 1.952752)
			(end -0.901446 1.952752)
			(stroke
				(width 0.0127)
				(type default)
			)
			(layer "F.SilkS")
		)
		(fp_line
			(start -1.089406 1.96215)
			(end -0.891794 1.96215)
			(stroke
				(width 0.0127)
				(type default)
			)
			(layer "F.SilkS")
		)
		(fp_line
			(start -1.099058 1.971802)
			(end -0.882396 1.971802)
			(stroke
				(width 0.0127)
				(type default)
			)
			(layer "F.SilkS")
		)
		(fp_line
			(start -1.108456 1.9812)
			(end -0.872744 1.9812)
			(stroke
				(width 0.0127)
				(type default)
			)
			(layer "F.SilkS")
		)
		(fp_line
			(start -1.118108 1.990852)
			(end -0.863346 1.990852)
			(stroke
				(width 0.0127)
				(type default)
			)
			(layer "F.SilkS")
		)
		(fp_line
			(start -1.127506 2.00025)
			(end -0.853694 2.00025)
			(stroke
				(width 0.0127)
				(type default)
			)
			(layer "F.SilkS")
		)
		(fp_line
			(start -1.137158 2.009902)
			(end -0.844296 2.009902)
			(stroke
				(width 0.0127)
				(type default)
			)
			(layer "F.SilkS")
		)
		(fp_line
			(start -1.146556 2.0193)
			(end -0.834644 2.0193)
			(stroke
				(width 0.0127)
				(type default)
			)
			(layer "F.SilkS")
		)
		(fp_line
			(start -1.156208 2.028952)
			(end -0.825246 2.028952)
			(stroke
				(width 0.0127)
				(type default)
			)
			(layer "F.SilkS")
		)
		(fp_line
			(start -1.165606 2.03835)
			(end -0.815594 2.03835)
			(stroke
				(width 0.0127)
				(type default)
			)
			(layer "F.SilkS")
		)
		(fp_line
			(start -1.175258 2.048002)
			(end -0.806196 2.048002)
			(stroke
				(width 0.0127)
				(type default)
			)
			(layer "F.SilkS")
		)
		(fp_line
			(start -1.184656 2.0574)
			(end -0.796544 2.0574)
			(stroke
				(width 0.0127)
				(type default)
			)
			(layer "F.SilkS")
		)
		(fp_line
			(start -1.194308 2.067052)
			(end -0.787146 2.067052)
			(stroke
				(width 0.0127)
				(type default)
			)
			(layer "F.SilkS")
		)
		(fp_line
			(start -1.203706 2.07645)
			(end -0.777494 2.07645)
			(stroke
				(width 0.0127)
				(type default)
			)
			(layer "F.SilkS")
		)
		(fp_line
			(start -1.213358 2.086102)
			(end -0.768096 2.086102)
			(stroke
				(width 0.0127)
				(type default)
			)
			(layer "F.SilkS")
		)
		(fp_line
			(start -1.222756 2.0955)
			(end -0.758444 2.0955)
			(stroke
				(width 0.0127)
				(type default)
			)
			(layer "F.SilkS")
		)
		(fp_line
			(start -1.232408 2.105152)
			(end -0.749046 2.105152)
			(stroke
				(width 0.0127)
				(type default)
			)
			(layer "F.SilkS")
		)
		(fp_line
			(start -1.241806 2.11455)
			(end -0.739394 2.11455)
			(stroke
				(width 0.0127)
				(type default)
			)
			(layer "F.SilkS")
		)
		(fp_line
			(start -1.251458 2.124202)
			(end -0.729996 2.124202)
			(stroke
				(width 0.0127)
				(type default)
			)
			(layer "F.SilkS")
		)
		(fp_line
			(start -1.260856 2.1336)
			(end -0.720344 2.1336)
			(stroke
				(width 0.0127)
				(type default)
			)
			(layer "F.SilkS")
		)
		(fp_line
			(start -0.719074 2.145538)
			(end -1.265936 2.14122)
			(stroke
				(width 0.0127)
				(type default)
			)
			(layer "F.SilkS")
		)
		(fp_line
			(start -1.279398 2.152142)
			(end -0.9906 1.86309)
			(stroke
				(width 0.0127)
				(type default)
			)
			(layer "F.SilkS")
		)
		(fp_line
			(start -0.71628 2.15265)
			(end -1.26492 2.15265)
			(stroke
				(width 0.0127)
				(type default)
			)
			(layer "F.SilkS")
		)
		(fp_line
			(start -1.279144 2.15265)
			(end -0.701294 2.15265)
			(stroke
				(width 0.0127)
				(type default)
			)
			(layer "F.SilkS")
		)
		(fp_poly
			(pts
				(xy -1.285748 2.159) (xy -1.285748 1.8796) (xy -1.778 1.8796) (xy -1.778 -1.8796) (xy 1.778 -1.8796)
				(xy 1.778 1.8796) (xy -0.694944 1.8796) (xy -0.694944 2.159)
			)
			(stroke
				(width 0)
				(type default)
			)
			(fill no)
			(layer "F.CrtYd")
		)
		(fp_poly
			(pts
				(xy -1.285748 2.159) (xy -1.285748 1.8796) (xy -1.778 1.8796) (xy -1.778 -1.8796) (xy 1.778 -1.8796)
				(xy 1.778 1.8796) (xy -0.694944 1.8796) (xy -0.694944 2.159)
			)
			(stroke
				(width 0)
				(type default)
			)
			(fill no)
			(layer "F.Fab")
		)
		(pad "1" smd rect
			(at -0.98425 0.9525 90)
			(size 0.762 1.143)
			(layers "F.Cu" "F.Mask" "F.Paste")
			(net "FLT_HDD0_B")
		)
		(pad "2" smd rect
			(at 0.98425 0.9525 90)
			(size 0.762 1.143)
			(layers "F.Cu" "F.Mask" "F.Paste")
			(net "GND")
		)
		(pad "3" smd rect
			(at 0 -0.9525 90)
			(size 0.762 1.143)
			(layers "F.Cu" "F.Mask" "F.Paste")
			(net "DRIVE_ACT_0")
		)
	)
	(footprint ""
		(layer "F.Cu")
		(at 211.3534 -440.563 -90)
		(property "Reference" "PR57"
			(at 0 0 270)
			(layer "F.SilkS")
			(hide yes)
			(effects
				(font
					(size 1.27 1.27)
				)
			)
		)
		(property "Value" "0R0805-PAD-2-GP-U"
			(at 0.0254 -2.8702 270)
			(unlocked yes)
			(layer "F.Fab")
			(hide yes)
			(effects
				(font
					(size 1.016 1.016)
					(thickness 0.1524)
				)
			)
		)
		(property "Device Type" "0R0805-PAD-1-U"
			(at 0.0254 -4.3942 270)
			(unlocked yes)
			(layer "F.Fab")
			(hide yes)
			(effects
				(font
					(size 1.016 1.016)
					(thickness 0.1524)
				)
			)
		)
		(duplicate_pad_numbers_are_jumpers no)
		(fp_line
			(start -0.889 1.7018)
			(end -0.889 -1.7018)
			(stroke
				(width 0.1524)
				(type default)
			)
			(layer "F.SilkS")
		)
		(fp_line
			(start 0.889 1.7018)
			(end -0.889 1.7018)
			(stroke
				(width 0.1524)
				(type default)
			)
			(layer "F.SilkS")
		)
		(fp_line
			(start -0.889 -1.7018)
			(end 0.889 -1.7018)
			(stroke
				(width 0.1524)
				(type default)
			)
			(layer "F.SilkS")
		)
		(fp_line
			(start 0.889 -1.7018)
			(end 0.889 1.7018)
			(stroke
				(width 0.1524)
				(type default)
			)
			(layer "F.SilkS")
		)
		(fp_rect
			(start -0.9652 1.778)
			(end 0.9652 -1.778)
			(stroke
				(width 0)
				(type default)
			)
			(fill no)
			(layer "F.CrtYd")
		)
		(fp_rect
			(start -0.9652 1.778)
			(end 0.9652 -1.778)
			(stroke
				(width 0)
				(type default)
			)
			(fill no)
			(layer "F.Fab")
		)
		(pad "1" smd rect
			(at 0 -0.9652 270)
			(size 1.397 1.5621)
			(drill
				(offset 0 0.20955)
			)
			(layers "F.Cu" "F.Mask" "F.Paste")
			(net "P3V3_LX_COOPER")
		)
		(pad "2" smd rect
			(at 0 0.9652 270)
			(size 1.397 1.568704)
			(drill
				(offset 0 -0.206248)
			)
			(layers "F.Cu" "F.Mask" "F.Paste")
			(net "P3V3")
		)
	)
	(footprint ""
		(layer "F.Cu")
		(at 72.226932 -496.145312)
		(property "Reference" "R442"
			(at 0 0 0)
			(layer "F.SilkS")
			(hide yes)
			(effects
				(font
					(size 1.27 1.27)
				)
			)
		)
		(property "Value" "4K7R2J-2-GP"
			(at 0.064008 -3.993896 0)
			(unlocked yes)
			(layer "F.Fab")
			(hide yes)
			(effects
				(font
					(size 1.016 1.016)
					(thickness 0.1524)
				)
			)
		)
		(property "Device Type" "R402H16"
			(at 0.064008 -5.517896 0)
			(unlocked yes)
			(layer "F.Fab")
			(hide yes)
			(effects
				(font
					(size 1.016 1.016)
					(thickness 0.1524)
				)
			)
		)
		(duplicate_pad_numbers_are_jumpers no)
		(fp_line
			(start -0.508 -0.9398)
			(end -0.508 0.9398)
			(stroke
				(width 0.1524)
				(type default)
			)
			(layer "F.SilkS")
		)
		(fp_line
			(start 0.508 -0.9398)
			(end -0.508 -0.9398)
			(stroke
				(width 0.1524)
				(type default)
			)
			(layer "F.SilkS")
		)
		(fp_rect
			(start -0.508 0.9398)
			(end 0.508 -0.9398)
			(stroke
				(width 0)
				(type default)
			)
			(fill no)
			(layer "F.CrtYd")
		)
		(fp_rect
			(start -0.508 0.9398)
			(end 0.508 -0.9398)
			(stroke
				(width 0)
				(type default)
			)
			(fill no)
			(layer "F.Fab")
		)
		(pad "1" smd custom
			(at 0 -0.4445)
			(size 0.1397 0.1397)
			(layers "F.Cu" "F.Mask" "F.Paste")
			(net "P3V3")
			(options
				(clearance outline)
				(anchor circle)
			)
			(primitives
				(gr_poly
					(pts
						(arc
							(start -0.1778 -0.2794)
							(mid -0.249642 -0.249642)
							(end -0.2794 -0.1778)
						)
						(arc
							(start -0.2794 0.1778)
							(mid -0.249642 0.249642)
							(end -0.1778 0.2794)
						)
						(arc
							(start 0.1778 0.2794)
							(mid 0.249642 0.249642)
							(end 0.2794 0.1778)
						)
						(arc
							(start 0.2794 -0.1778)
							(mid 0.249642 -0.249642)
							(end 0.1778 -0.2794)
						)
					)
					(width 0)
					(fill yes)
				)
			)
		)
		(pad "2" smd custom
			(at 0 0.4445)
			(size 0.1397 0.1397)
			(layers "F.Cu" "F.Mask" "F.Paste")
			(net "SAS2X28_A_HDD5_FLT")
			(options
				(clearance outline)
				(anchor circle)
			)
			(primitives
				(gr_poly
					(pts
						(arc
							(start -0.1778 -0.2794)
							(mid -0.249642 -0.249642)
							(end -0.2794 -0.1778)
						)
						(arc
							(start -0.2794 0.1778)
							(mid -0.249642 0.249642)
							(end -0.1778 0.2794)
						)
						(arc
							(start 0.1778 0.2794)
							(mid 0.249642 0.249642)
							(end 0.2794 0.1778)
						)
						(arc
							(start 0.2794 -0.1778)
							(mid 0.249642 -0.249642)
							(end 0.1778 -0.2794)
						)
					)
					(width 0)
					(fill yes)
				)
			)
		)
	)
	(footprint ""
		(layer "F.Cu")
		(at 226.695 -437.261 90)
		(property "Reference" "PC44"
			(at 0 0 90)
			(layer "F.SilkS")
			(hide yes)
			(effects
				(font
					(size 1.27 1.27)
				)
			)
		)
		(property "Value" "SCD1U25V3KX-GP"
			(at 0 -2.8194 90)
			(unlocked yes)
			(layer "F.Fab")
			(hide yes)
			(effects
				(font
					(size 1.016 1.016)
					(thickness 0.1524)
				)
			)
		)
		(property "Device Type" "C603H36"
			(at 0 -4.3434 90)
			(unlocked yes)
			(layer "F.Fab")
			(hide yes)
			(effects
				(font
					(size 1.016 1.016)
					(thickness 0.1524)
				)
			)
		)
		(duplicate_pad_numbers_are_jumpers no)
		(fp_line
			(start 0.508 0)
			(end -0.508 0)
			(stroke
				(width 0.2032)
				(type default)
			)
			(layer "F.SilkS")
		)
		(fp_rect
			(start -0.5842 1.3335)
			(end 0.5842 -1.3335)
			(stroke
				(width 0)
				(type default)
			)
			(fill no)
			(layer "F.CrtYd")
		)
		(fp_rect
			(start -0.5842 1.3335)
			(end 0.5842 -1.3335)
			(stroke
				(width 0)
				(type default)
			)
			(fill no)
			(layer "F.Fab")
		)
		(pad "1" smd custom
			(at 0 -0.762 90)
			(size 0.2159 0.2159)
			(layers "F.Cu" "F.Mask" "F.Paste")
			(net "P3V3_EN")
			(options
				(clearance outline)
				(anchor circle)
			)
			(primitives
				(gr_poly
					(pts
						(arc
							(start -0.3302 -0.4318)
							(mid -0.402042 -0.402042)
							(end -0.4318 -0.3302)
						)
						(arc
							(start -0.4318 0.3302)
							(mid -0.402042 0.402042)
							(end -0.3302 0.4318)
						)
						(arc
							(start 0.3302 0.4318)
							(mid 0.402042 0.402042)
							(end 0.4318 0.3302)
						)
						(arc
							(start 0.4318 -0.3302)
							(mid 0.402042 -0.402042)
							(end 0.3302 -0.4318)
						)
					)
					(width 0)
					(fill yes)
				)
			)
		)
		(pad "2" smd custom
			(at 0 0.762 90)
			(size 0.2159 0.2159)
			(layers "F.Cu" "F.Mask" "F.Paste")
			(net "GND")
			(options
				(clearance outline)
				(anchor circle)
			)
			(primitives
				(gr_poly
					(pts
						(arc
							(start -0.3302 -0.4318)
							(mid -0.402042 -0.402042)
							(end -0.4318 -0.3302)
						)
						(arc
							(start -0.4318 0.3302)
							(mid -0.402042 0.402042)
							(end -0.3302 0.4318)
						)
						(arc
							(start 0.3302 0.4318)
							(mid 0.402042 0.402042)
							(end 0.4318 0.3302)
						)
						(arc
							(start 0.4318 -0.3302)
							(mid 0.402042 -0.402042)
							(end 0.3302 -0.4318)
						)
					)
					(width 0)
					(fill yes)
				)
			)
		)
	)
	(footprint ""
		(layer "F.Cu")
		(at 32.257746 -308.892702 -90)
		(property "Reference" "Q24"
			(at 0 0 270)
			(layer "F.SilkS")
			(hide yes)
			(effects
				(font
					(size 1.27 1.27)
				)
			)
		)
		(property "Value" "2N7002DW-7F-GP"
			(at -2.3622 -8.2042 270)
			(unlocked yes)
			(layer "F.Fab")
			(hide yes)
			(effects
				(font
					(size 1.016 1.016)
					(thickness 0.1524)
				)
			)
		)
		(property "Device Type" "SOT-363H44"
			(at -2.3622 -10.1092 270)
			(unlocked yes)
			(layer "F.Fab")
			(hide yes)
			(effects
				(font
					(size 1.016 1.016)
					(thickness 0.1524)
				)
			)
		)
		(duplicate_pad_numbers_are_jumpers no)
		(fp_line
			(start -1.4478 1.7018)
			(end 1.4478 1.7018)
			(stroke
				(width 0.1524)
				(type default)
			)
			(layer "F.SilkS")
		)
		(fp_line
			(start 1.4478 1.7018)
			(end 1.4478 -1.7018)
			(stroke
				(width 0.1524)
				(type default)
			)
			(layer "F.SilkS")
		)
		(fp_line
			(start -1.27 1.524)
			(end -1.27 0.6604)
			(stroke
				(width 0.4826)
				(type default)
			)
			(layer "F.SilkS")
		)
		(fp_line
			(start -1.4478 -1.7018)
			(end -1.4478 1.7018)
			(stroke
				(width 0.1524)
				(type default)
			)
			(layer "F.SilkS")
		)
		(fp_line
			(start 1.4478 -1.7018)
			(end -1.4478 -1.7018)
			(stroke
				(width 0.1524)
				(type default)
			)
			(layer "F.SilkS")
		)
		(fp_poly
			(pts
				(xy -1.524 -1.778) (xy 1.524 -1.778) (xy 1.524 1.778) (xy -1.524 1.778)
			)
			(stroke
				(width 0)
				(type default)
			)
			(fill no)
			(layer "F.CrtYd")
		)
		(fp_poly
			(pts
				(xy -1.524 -1.778) (xy 1.524 -1.778) (xy 1.524 1.778) (xy -1.524 1.778)
			)
			(stroke
				(width 0)
				(type default)
			)
			(fill no)
			(layer "F.Fab")
		)
		(pad "1" smd rect
			(at -0.65024 0.9398 270)
			(size 0.4064 1.016)
			(layers "F.Cu" "F.Mask" "F.Paste")
			(net "GND")
		)
		(pad "2" smd rect
			(at 0 0.9398 270)
			(size 0.4064 1.016)
			(layers "F.Cu" "F.Mask" "F.Paste")
			(net "SW_PWR_R_HDD11")
		)
		(pad "3" smd rect
			(at 0.65024 0.9398 270)
			(size 0.4064 1.016)
			(layers "F.Cu" "F.Mask" "F.Paste")
			(net "SW_HDD11_P")
		)
		(pad "4" smd rect
			(at 0.65024 -0.9398 270)
			(size 0.4064 1.016)
			(layers "F.Cu" "F.Mask" "F.Paste")
			(net "GND")
		)
		(pad "5" smd rect
			(at 0 -0.9398 270)
			(size 0.4064 1.016)
			(layers "F.Cu" "F.Mask" "F.Paste")
			(net "SW_HDD11_G")
		)
		(pad "6" smd rect
			(at -0.65024 -0.9398 270)
			(size 0.4064 1.016)
			(layers "F.Cu" "F.Mask" "F.Paste")
			(net "SW_HDD11_R")
		)
	)
	(footprint ""
		(layer "F.Cu")
		(at 53.721 -208.534 180)
		(property "Reference" "R575"
			(at 0 0 180)
			(layer "F.SilkS")
			(hide yes)
			(effects
				(font
					(size 1.27 1.27)
				)
			)
		)
		(property "Value" "300KR2F-GP"
			(at 0.064008 -3.993896 180)
			(unlocked yes)
			(layer "F.Fab")
			(hide yes)
			(effects
				(font
					(size 1.016 1.016)
					(thickness 0.1524)
				)
			)
		)
		(property "Device Type" "R402H16"
			(at 0.064008 -5.517896 180)
			(unlocked yes)
			(layer "F.Fab")
			(hide yes)
			(effects
				(font
					(size 1.016 1.016)
					(thickness 0.1524)
				)
			)
		)
		(duplicate_pad_numbers_are_jumpers no)
		(fp_line
			(start 0.508 -0.9398)
			(end -0.508 -0.9398)
			(stroke
				(width 0.1524)
				(type default)
			)
			(layer "F.SilkS")
		)
		(fp_line
			(start -0.508 -0.9398)
			(end -0.508 0.9398)
			(stroke
				(width 0.1524)
				(type default)
			)
			(layer "F.SilkS")
		)
		(fp_rect
			(start -0.508 0.9398)
			(end 0.508 -0.9398)
			(stroke
				(width 0)
				(type default)
			)
			(fill no)
			(layer "F.CrtYd")
		)
		(fp_rect
			(start -0.508 0.9398)
			(end 0.508 -0.9398)
			(stroke
				(width 0)
				(type default)
			)
			(fill no)
			(layer "F.Fab")
		)
		(pad "1" smd custom
			(at 0 -0.4445 180)
			(size 0.1397 0.1397)
			(layers "F.Cu" "F.Mask" "F.Paste")
			(net "SW_HDD12_N")
			(options
				(clearance outline)
				(anchor circle)
			)
			(primitives
				(gr_poly
					(pts
						(arc
							(start -0.1778 -0.2794)
							(mid -0.249642 -0.249642)
							(end -0.2794 -0.1778)
						)
						(arc
							(start -0.2794 0.1778)
							(mid -0.249642 0.249642)
							(end -0.1778 0.2794)
						)
						(arc
							(start 0.1778 0.2794)
							(mid 0.249642 0.249642)
							(end 0.2794 0.1778)
						)
						(arc
							(start 0.2794 -0.1778)
							(mid 0.249642 -0.249642)
							(end 0.1778 -0.2794)
						)
					)
					(width 0)
					(fill yes)
				)
			)
		)
		(pad "2" smd custom
			(at 0 0.4445 180)
			(size 0.1397 0.1397)
			(layers "F.Cu" "F.Mask" "F.Paste")
			(net "P12V")
			(options
				(clearance outline)
				(anchor circle)
			)
			(primitives
				(gr_poly
					(pts
						(arc
							(start -0.1778 -0.2794)
							(mid -0.249642 -0.249642)
							(end -0.2794 -0.1778)
						)
						(arc
							(start -0.2794 0.1778)
							(mid -0.249642 0.249642)
							(end -0.1778 0.2794)
						)
						(arc
							(start 0.1778 0.2794)
							(mid 0.249642 0.249642)
							(end 0.2794 0.1778)
						)
						(arc
							(start 0.2794 -0.1778)
							(mid 0.249642 -0.249642)
							(end 0.1778 -0.2794)
						)
					)
					(width 0)
					(fill yes)
				)
			)
		)
	)
	(footprint ""
		(layer "F.Cu")
		(at 224.679256 -452.682102 90)
		(property "Reference" "R104"
			(at 0 0 90)
			(layer "F.SilkS")
			(hide yes)
			(effects
				(font
					(size 1.27 1.27)
				)
			)
		)
		(property "Value" "330R2F-GP"
			(at 0.064008 -3.993896 90)
			(unlocked yes)
			(layer "F.Fab")
			(hide yes)
			(effects
				(font
					(size 1.016 1.016)
					(thickness 0.1524)
				)
			)
		)
		(property "Device Type" "R402H16"
			(at 0.064008 -5.517896 90)
			(unlocked yes)
			(layer "F.Fab")
			(hide yes)
			(effects
				(font
					(size 1.016 1.016)
					(thickness 0.1524)
				)
			)
		)
		(duplicate_pad_numbers_are_jumpers no)
		(fp_line
			(start 0.508 -0.9398)
			(end -0.508 -0.9398)
			(stroke
				(width 0.1524)
				(type default)
			)
			(layer "F.SilkS")
		)
		(fp_line
			(start -0.508 -0.9398)
			(end -0.508 0.9398)
			(stroke
				(width 0.1524)
				(type default)
			)
			(layer "F.SilkS")
		)
		(fp_rect
			(start -0.508 0.9398)
			(end 0.508 -0.9398)
			(stroke
				(width 0)
				(type default)
			)
			(fill no)
			(layer "F.CrtYd")
		)
		(fp_rect
			(start -0.508 0.9398)
			(end 0.508 -0.9398)
			(stroke
				(width 0)
				(type default)
			)
			(fill no)
			(layer "F.Fab")
		)
		(pad "1" smd custom
			(at 0 -0.4445 90)
			(size 0.1397 0.1397)
			(layers "F.Cu" "F.Mask" "F.Paste")
			(net "P3V3_HDD0_LED")
			(options
				(clearance outline)
				(anchor circle)
			)
			(primitives
				(gr_poly
					(pts
						(arc
							(start -0.1778 -0.2794)
							(mid -0.249642 -0.249642)
							(end -0.2794 -0.1778)
						)
						(arc
							(start -0.2794 0.1778)
							(mid -0.249642 0.249642)
							(end -0.1778 0.2794)
						)
						(arc
							(start 0.1778 0.2794)
							(mid 0.249642 0.249642)
							(end 0.2794 0.1778)
						)
						(arc
							(start 0.2794 -0.1778)
							(mid 0.249642 -0.249642)
							(end 0.1778 -0.2794)
						)
					)
					(width 0)
					(fill yes)
				)
			)
		)
		(pad "2" smd custom
			(at 0 0.4445 90)
			(size 0.1397 0.1397)
			(layers "F.Cu" "F.Mask" "F.Paste")
			(net "FLT_HDD0")
			(options
				(clearance outline)
				(anchor circle)
			)
			(primitives
				(gr_poly
					(pts
						(arc
							(start -0.1778 -0.2794)
							(mid -0.249642 -0.249642)
							(end -0.2794 -0.1778)
						)
						(arc
							(start -0.2794 0.1778)
							(mid -0.249642 0.249642)
							(end -0.1778 0.2794)
						)
						(arc
							(start 0.1778 0.2794)
							(mid 0.249642 0.249642)
							(end 0.2794 0.1778)
						)
						(arc
							(start 0.2794 -0.1778)
							(mid 0.249642 -0.249642)
							(end 0.1778 -0.2794)
						)
					)
					(width 0)
					(fill yes)
				)
			)
		)
	)
	(footprint ""
		(layer "F.Cu")
		(at 30.352746 -281.4447 180)
		(property "Reference" "R210"
			(at 0 0 180)
			(layer "F.SilkS")
			(hide yes)
			(effects
				(font
					(size 1.27 1.27)
				)
			)
		)
		(property "Value" "0R2J-2-GP"
			(at 0.064008 -3.993896 180)
			(unlocked yes)
			(layer "F.Fab")
			(hide yes)
			(effects
				(font
					(size 1.016 1.016)
					(thickness 0.1524)
				)
			)
		)
		(property "Device Type" "R402H16"
			(at 0.064008 -5.517896 180)
			(unlocked yes)
			(layer "F.Fab")
			(hide yes)
			(effects
				(font
					(size 1.016 1.016)
					(thickness 0.1524)
				)
			)
		)
		(duplicate_pad_numbers_are_jumpers no)
		(fp_line
			(start 0.508 -0.9398)
			(end -0.508 -0.9398)
			(stroke
				(width 0.1524)
				(type default)
			)
			(layer "F.SilkS")
		)
		(fp_line
			(start -0.508 -0.9398)
			(end -0.508 0.9398)
			(stroke
				(width 0.1524)
				(type default)
			)
			(layer "F.SilkS")
		)
		(fp_rect
			(start -0.508 0.9398)
			(end 0.508 -0.9398)
			(stroke
				(width 0)
				(type default)
			)
			(fill no)
			(layer "F.CrtYd")
		)
		(fp_rect
			(start -0.508 0.9398)
			(end 0.508 -0.9398)
			(stroke
				(width 0)
				(type default)
			)
			(fill no)
			(layer "F.Fab")
		)
		(pad "1" smd custom
			(at 0 -0.4445 180)
			(size 0.1397 0.1397)
			(layers "F.Cu" "F.Mask" "F.Paste")
			(net "SW_PWR_HDD7")
			(options
				(clearance outline)
				(anchor circle)
			)
			(primitives
				(gr_poly
					(pts
						(arc
							(start -0.1778 -0.2794)
							(mid -0.249642 -0.249642)
							(end -0.2794 -0.1778)
						)
						(arc
							(start -0.2794 0.1778)
							(mid -0.249642 0.249642)
							(end -0.1778 0.2794)
						)
						(arc
							(start 0.1778 0.2794)
							(mid 0.249642 0.249642)
							(end 0.2794 0.1778)
						)
						(arc
							(start 0.2794 -0.1778)
							(mid 0.249642 -0.249642)
							(end 0.1778 -0.2794)
						)
					)
					(width 0)
					(fill yes)
				)
			)
		)
		(pad "2" smd custom
			(at 0 0.4445 180)
			(size 0.1397 0.1397)
			(layers "F.Cu" "F.Mask" "F.Paste")
			(net "SW_PWR_R_HDD7")
			(options
				(clearance outline)
				(anchor circle)
			)
			(primitives
				(gr_poly
					(pts
						(arc
							(start -0.1778 -0.2794)
							(mid -0.249642 -0.249642)
							(end -0.2794 -0.1778)
						)
						(arc
							(start -0.2794 0.1778)
							(mid -0.249642 0.249642)
							(end -0.1778 0.2794)
						)
						(arc
							(start 0.1778 0.2794)
							(mid 0.249642 0.249642)
							(end 0.2794 0.1778)
						)
						(arc
							(start 0.2794 -0.1778)
							(mid 0.249642 -0.249642)
							(end 0.1778 -0.2794)
						)
					)
					(width 0)
					(fill yes)
				)
			)
		)
	)
	(footprint ""
		(layer "F.Cu")
		(at 77.469746 -396.8877 90)
		(property "Reference" "R196"
			(at 0 0 90)
			(layer "F.SilkS")
			(hide yes)
			(effects
				(font
					(size 1.27 1.27)
				)
			)
		)
		(property "Value" "0R2J-2-GP"
			(at 0.064008 -3.993896 90)
			(unlocked yes)
			(layer "F.Fab")
			(hide yes)
			(effects
				(font
					(size 1.016 1.016)
					(thickness 0.1524)
				)
			)
		)
		(property "Device Type" "R402H16"
			(at 0.064008 -5.517896 90)
			(unlocked yes)
			(layer "F.Fab")
			(hide yes)
			(effects
				(font
					(size 1.016 1.016)
					(thickness 0.1524)
				)
			)
		)
		(duplicate_pad_numbers_are_jumpers no)
		(fp_line
			(start 0.508 -0.9398)
			(end -0.508 -0.9398)
			(stroke
				(width 0.1524)
				(type default)
			)
			(layer "F.SilkS")
		)
		(fp_line
			(start -0.508 -0.9398)
			(end -0.508 0.9398)
			(stroke
				(width 0.1524)
				(type default)
			)
			(layer "F.SilkS")
		)
		(fp_rect
			(start -0.508 0.9398)
			(end 0.508 -0.9398)
			(stroke
				(width 0)
				(type default)
			)
			(fill no)
			(layer "F.CrtYd")
		)
		(fp_rect
			(start -0.508 0.9398)
			(end 0.508 -0.9398)
			(stroke
				(width 0)
				(type default)
			)
			(fill no)
			(layer "F.Fab")
		)
		(pad "1" smd custom
			(at 0 -0.4445 90)
			(size 0.1397 0.1397)
			(layers "F.Cu" "F.Mask" "F.Paste")
			(net "SW_PWR_HDD6")
			(options
				(clearance outline)
				(anchor circle)
			)
			(primitives
				(gr_poly
					(pts
						(arc
							(start -0.1778 -0.2794)
							(mid -0.249642 -0.249642)
							(end -0.2794 -0.1778)
						)
						(arc
							(start -0.2794 0.1778)
							(mid -0.249642 0.249642)
							(end -0.1778 0.2794)
						)
						(arc
							(start 0.1778 0.2794)
							(mid 0.249642 0.249642)
							(end 0.2794 0.1778)
						)
						(arc
							(start 0.2794 -0.1778)
							(mid 0.249642 -0.249642)
							(end 0.1778 -0.2794)
						)
					)
					(width 0)
					(fill yes)
				)
			)
		)
		(pad "2" smd custom
			(at 0 0.4445 90)
			(size 0.1397 0.1397)
			(layers "F.Cu" "F.Mask" "F.Paste")
			(net "SW_PWR_R_HDD6")
			(options
				(clearance outline)
				(anchor circle)
			)
			(primitives
				(gr_poly
					(pts
						(arc
							(start -0.1778 -0.2794)
							(mid -0.249642 -0.249642)
							(end -0.2794 -0.1778)
						)
						(arc
							(start -0.2794 0.1778)
							(mid -0.249642 0.249642)
							(end -0.1778 0.2794)
						)
						(arc
							(start 0.1778 0.2794)
							(mid 0.249642 0.249642)
							(end 0.2794 0.1778)
						)
						(arc
							(start 0.2794 -0.1778)
							(mid 0.249642 -0.249642)
							(end 0.1778 -0.2794)
						)
					)
					(width 0)
					(fill yes)
				)
			)
		)
	)
	(footprint ""
		(layer "F.Cu")
		(at 35.940746 -321.8307)
		(property "Reference" "TP36"
			(at 0 0 0)
			(layer "F.SilkS")
			(hide yes)
			(effects
				(font
					(size 1.27 1.27)
				)
			)
		)
		(property "Value" "TPAD32-GP"
			(at 0 -3.166364 0)
			(unlocked yes)
			(layer "F.Fab")
			(hide yes)
			(effects
				(font
					(size 1.016 1.016)
					(thickness 0.1524)
				)
			)
		)
		(property "Device Type" "TPAD32"
			(at 0 -4.690618 0)
			(unlocked yes)
			(layer "F.Fab")
			(hide yes)
			(effects
				(font
					(size 1.016 1.016)
					(thickness 0.1524)
				)
			)
		)
		(duplicate_pad_numbers_are_jumpers no)
		(fp_poly
			(pts
				(arc
					(start 0.4064 0)
					(mid -0.4064 0)
					(end 0.4064 0)
				)
			)
			(stroke
				(width 0)
				(type default)
			)
			(fill no)
			(layer "F.CrtYd")
		)
		(fp_poly
			(pts
				(arc
					(start 0.7112 0)
					(mid -0.7112 0)
					(end 0.7112 0)
				)
			)
			(stroke
				(width 0)
				(type default)
			)
			(fill no)
			(layer "F.Fab")
		)
		(pad "1" smd circle
			(at 0 0)
			(size 0.8128 0.8128)
			(layers "F.Cu" "F.Mask" "F.Paste")
			(net "ACT_HDD11")
		)
	)
	(footprint ""
		(layer "F.Cu")
		(at 229.742746 -21.9837)
		(property "Reference" "PC7"
			(at 0 0 0)
			(layer "F.SilkS")
			(hide yes)
			(effects
				(font
					(size 1.27 1.27)
				)
			)
		)
		(property "Value" "SCD1U25V2KX-GP"
			(at 1.1811 -2.7051 0)
			(unlocked yes)
			(layer "F.Fab")
			(hide yes)
			(effects
				(font
					(size 1.016 1.016)
					(thickness 0.1524)
				)
			)
		)
		(property "Device Type" "C402H22"
			(at 1.1811 -4.2291 0)
			(unlocked yes)
			(layer "F.Fab")
			(hide yes)
			(effects
				(font
					(size 1.016 1.016)
					(thickness 0.1524)
				)
			)
		)
		(duplicate_pad_numbers_are_jumpers no)
		(fp_rect
			(start -0.4318 0.9525)
			(end 0.4318 -0.9525)
			(stroke
				(width 0)
				(type default)
			)
			(fill no)
			(layer "F.CrtYd")
		)
		(fp_rect
			(start -0.4318 0.9525)
			(end 0.4318 -0.9525)
			(stroke
				(width 0)
				(type default)
			)
			(fill no)
			(layer "F.Fab")
		)
		(pad "1" smd custom
			(at 0 -0.4445)
			(size 0.1524 0.1524)
			(layers "F.Cu" "F.Mask" "F.Paste")
			(net "P5VA_VBST_NET")
			(options
				(clearance outline)
				(anchor circle)
			)
			(primitives
				(gr_poly
					(pts
						(arc
							(start 0.3048 -0.2032)
							(mid 0.275042 -0.275042)
							(end 0.2032 -0.3048)
						)
						(arc
							(start -0.2032 -0.3048)
							(mid -0.275042 -0.275042)
							(end -0.3048 -0.2032)
						)
						(arc
							(start -0.3048 0.2032)
							(mid -0.275042 0.275042)
							(end -0.2032 0.3048)
						)
						(arc
							(start 0.2032 0.3048)
							(mid 0.275042 0.275042)
							(end 0.3048 0.2032)
						)
					)
					(width 0)
					(fill yes)
				)
			)
		)
		(pad "2" smd custom
			(at 0 0.4445)
			(size 0.1524 0.1524)
			(layers "F.Cu" "F.Mask" "F.Paste")
			(net "P5VA_LL")
			(options
				(clearance outline)
				(anchor circle)
			)
			(primitives
				(gr_poly
					(pts
						(arc
							(start 0.3048 -0.2032)
							(mid 0.275042 -0.275042)
							(end 0.2032 -0.3048)
						)
						(arc
							(start -0.2032 -0.3048)
							(mid -0.275042 -0.275042)
							(end -0.3048 -0.2032)
						)
						(arc
							(start -0.3048 0.2032)
							(mid -0.275042 0.275042)
							(end -0.2032 0.3048)
						)
						(arc
							(start 0.2032 0.3048)
							(mid 0.275042 0.275042)
							(end 0.3048 0.2032)
						)
					)
					(width 0)
					(fill yes)
				)
			)
		)
	)
	(footprint ""
		(layer "F.Cu")
		(at 190.754 -395.097)
		(property "Reference" "R122"
			(at 0 0 0)
			(layer "F.SilkS")
			(hide yes)
			(effects
				(font
					(size 1.27 1.27)
				)
			)
		)
		(property "Value" "200KR2F-L-GP"
			(at 0.064008 -3.993896 0)
			(unlocked yes)
			(layer "F.Fab")
			(hide yes)
			(effects
				(font
					(size 1.016 1.016)
					(thickness 0.1524)
				)
			)
		)
		(property "Device Type" "R402H16"
			(at 0.064008 -5.517896 0)
			(unlocked yes)
			(layer "F.Fab")
			(hide yes)
			(effects
				(font
					(size 1.016 1.016)
					(thickness 0.1524)
				)
			)
		)
		(duplicate_pad_numbers_are_jumpers no)
		(fp_line
			(start -0.508 -0.9398)
			(end -0.508 0.9398)
			(stroke
				(width 0.1524)
				(type default)
			)
			(layer "F.SilkS")
		)
		(fp_line
			(start 0.508 -0.9398)
			(end -0.508 -0.9398)
			(stroke
				(width 0.1524)
				(type default)
			)
			(layer "F.SilkS")
		)
		(fp_rect
			(start -0.508 0.9398)
			(end 0.508 -0.9398)
			(stroke
				(width 0)
				(type default)
			)
			(fill no)
			(layer "F.CrtYd")
		)
		(fp_rect
			(start -0.508 0.9398)
			(end 0.508 -0.9398)
			(stroke
				(width 0)
				(type default)
			)
			(fill no)
			(layer "F.Fab")
		)
		(pad "1" smd custom
			(at 0 -0.4445)
			(size 0.1397 0.1397)
			(layers "F.Cu" "F.Mask" "F.Paste")
			(net "P12V")
			(options
				(clearance outline)
				(anchor circle)
			)
			(primitives
				(gr_poly
					(pts
						(arc
							(start -0.1778 -0.2794)
							(mid -0.249642 -0.249642)
							(end -0.2794 -0.1778)
						)
						(arc
							(start -0.2794 0.1778)
							(mid -0.249642 0.249642)
							(end -0.1778 0.2794)
						)
						(arc
							(start 0.1778 0.2794)
							(mid 0.249642 0.249642)
							(end 0.2794 0.1778)
						)
						(arc
							(start 0.2794 -0.1778)
							(mid 0.249642 -0.249642)
							(end 0.1778 -0.2794)
						)
					)
					(width 0)
					(fill yes)
				)
			)
		)
		(pad "2" smd custom
			(at 0 0.4445)
			(size 0.1397 0.1397)
			(layers "F.Cu" "F.Mask" "F.Paste")
			(net "SW_HDD1_P")
			(options
				(clearance outline)
				(anchor circle)
			)
			(primitives
				(gr_poly
					(pts
						(arc
							(start -0.1778 -0.2794)
							(mid -0.249642 -0.249642)
							(end -0.2794 -0.1778)
						)
						(arc
							(start -0.2794 0.1778)
							(mid -0.249642 0.249642)
							(end -0.1778 0.2794)
						)
						(arc
							(start 0.1778 0.2794)
							(mid 0.249642 0.249642)
							(end 0.2794 0.1778)
						)
						(arc
							(start 0.2794 -0.1778)
							(mid 0.249642 -0.249642)
							(end 0.1778 -0.2794)
						)
					)
					(width 0)
					(fill yes)
				)
			)
		)
	)
	(footprint ""
		(layer "F.Cu")
		(at 239.902746 -27.9527 180)
		(property "Reference" "PR13"
			(at 0 0 180)
			(layer "F.SilkS")
			(hide yes)
			(effects
				(font
					(size 1.27 1.27)
				)
			)
		)
		(property "Value" "115KR2F-GP"
			(at 0.064008 -3.993896 180)
			(unlocked yes)
			(layer "F.Fab")
			(hide yes)
			(effects
				(font
					(size 1.016 1.016)
					(thickness 0.1524)
				)
			)
		)
		(property "Device Type" "R402H16"
			(at 0.064008 -5.517896 180)
			(unlocked yes)
			(layer "F.Fab")
			(hide yes)
			(effects
				(font
					(size 1.016 1.016)
					(thickness 0.1524)
				)
			)
		)
		(duplicate_pad_numbers_are_jumpers no)
		(fp_line
			(start 0.508 -0.9398)
			(end -0.508 -0.9398)
			(stroke
				(width 0.1524)
				(type default)
			)
			(layer "F.SilkS")
		)
		(fp_line
			(start -0.508 -0.9398)
			(end -0.508 0.9398)
			(stroke
				(width 0.1524)
				(type default)
			)
			(layer "F.SilkS")
		)
		(fp_rect
			(start -0.508 0.9398)
			(end 0.508 -0.9398)
			(stroke
				(width 0)
				(type default)
			)
			(fill no)
			(layer "F.CrtYd")
		)
		(fp_rect
			(start -0.508 0.9398)
			(end 0.508 -0.9398)
			(stroke
				(width 0)
				(type default)
			)
			(fill no)
			(layer "F.Fab")
		)
		(pad "1" smd custom
			(at 0 -0.4445 180)
			(size 0.1397 0.1397)
			(layers "F.Cu" "F.Mask" "F.Paste")
			(net "P5VA_TRIP")
			(options
				(clearance outline)
				(anchor circle)
			)
			(primitives
				(gr_poly
					(pts
						(arc
							(start -0.1778 -0.2794)
							(mid -0.249642 -0.249642)
							(end -0.2794 -0.1778)
						)
						(arc
							(start -0.2794 0.1778)
							(mid -0.249642 0.249642)
							(end -0.1778 0.2794)
						)
						(arc
							(start 0.1778 0.2794)
							(mid 0.249642 0.249642)
							(end 0.2794 0.1778)
						)
						(arc
							(start 0.2794 -0.1778)
							(mid 0.249642 -0.249642)
							(end 0.1778 -0.2794)
						)
					)
					(width 0)
					(fill yes)
				)
			)
		)
		(pad "2" smd custom
			(at 0 0.4445 180)
			(size 0.1397 0.1397)
			(layers "F.Cu" "F.Mask" "F.Paste")
			(net "P5VA_AGND")
			(options
				(clearance outline)
				(anchor circle)
			)
			(primitives
				(gr_poly
					(pts
						(arc
							(start -0.1778 -0.2794)
							(mid -0.249642 -0.249642)
							(end -0.2794 -0.1778)
						)
						(arc
							(start -0.2794 0.1778)
							(mid -0.249642 0.249642)
							(end -0.1778 0.2794)
						)
						(arc
							(start 0.1778 0.2794)
							(mid 0.249642 0.249642)
							(end 0.2794 0.1778)
						)
						(arc
							(start 0.2794 -0.1778)
							(mid 0.249642 -0.249642)
							(end 0.1778 -0.2794)
						)
					)
					(width 0)
					(fill yes)
				)
			)
		)
	)
	(footprint ""
		(layer "F.Cu")
		(at 33.273746 -270.1417 -90)
		(property "Reference" "C217"
			(at 0 0 270)
			(layer "F.SilkS")
			(hide yes)
			(effects
				(font
					(size 1.27 1.27)
				)
			)
		)
		(property "Value" "SCD01U50V2KX-1GP"
			(at 1.1811 -2.7051 270)
			(unlocked yes)
			(layer "F.Fab")
			(hide yes)
			(effects
				(font
					(size 1.016 1.016)
					(thickness 0.1524)
				)
			)
		)
		(property "Device Type" "C402H22"
			(at 1.1811 -4.2291 270)
			(unlocked yes)
			(layer "F.Fab")
			(hide yes)
			(effects
				(font
					(size 1.016 1.016)
					(thickness 0.1524)
				)
			)
		)
		(duplicate_pad_numbers_are_jumpers no)
		(fp_rect
			(start -0.4318 0.9525)
			(end 0.4318 -0.9525)
			(stroke
				(width 0)
				(type default)
			)
			(fill no)
			(layer "F.CrtYd")
		)
		(fp_rect
			(start -0.4318 0.9525)
			(end 0.4318 -0.9525)
			(stroke
				(width 0)
				(type default)
			)
			(fill no)
			(layer "F.Fab")
		)
		(pad "1" smd custom
			(at 0 -0.4445 270)
			(size 0.1524 0.1524)
			(layers "F.Cu" "F.Mask" "F.Paste")
			(net "SAS2X28_DRIVE_RX_P_B7")
			(options
				(clearance outline)
				(anchor circle)
			)
			(primitives
				(gr_poly
					(pts
						(arc
							(start 0.3048 -0.2032)
							(mid 0.275042 -0.275042)
							(end 0.2032 -0.3048)
						)
						(arc
							(start -0.2032 -0.3048)
							(mid -0.275042 -0.275042)
							(end -0.3048 -0.2032)
						)
						(arc
							(start -0.3048 0.2032)
							(mid -0.275042 0.275042)
							(end -0.2032 0.3048)
						)
						(arc
							(start 0.2032 0.3048)
							(mid 0.275042 0.275042)
							(end 0.3048 0.2032)
						)
					)
					(width 0)
					(fill yes)
				)
			)
		)
		(pad "2" smd custom
			(at 0 0.4445 270)
			(size 0.1524 0.1524)
			(layers "F.Cu" "F.Mask" "F.Paste")
			(net "SAS2X28_B_HDD7_RX_+")
			(options
				(clearance outline)
				(anchor circle)
			)
			(primitives
				(gr_poly
					(pts
						(arc
							(start 0.3048 -0.2032)
							(mid 0.275042 -0.275042)
							(end 0.2032 -0.3048)
						)
						(arc
							(start -0.2032 -0.3048)
							(mid -0.275042 -0.275042)
							(end -0.3048 -0.2032)
						)
						(arc
							(start -0.3048 0.2032)
							(mid -0.275042 0.275042)
							(end -0.2032 0.3048)
						)
						(arc
							(start 0.2032 0.3048)
							(mid 0.275042 0.275042)
							(end 0.3048 0.2032)
						)
					)
					(width 0)
					(fill yes)
				)
			)
		)
	)
	(footprint ""
		(layer "F.Cu")
		(at 34.1122 -116.2812)
		(property "Reference" "C322"
			(at 0 0 0)
			(layer "F.SilkS")
			(hide yes)
			(effects
				(font
					(size 1.27 1.27)
				)
			)
		)
		(property "Value" "SC1U25V3KX-1-GP"
			(at 0 -2.8194 0)
			(unlocked yes)
			(layer "F.Fab")
			(hide yes)
			(effects
				(font
					(size 1.016 1.016)
					(thickness 0.1524)
				)
			)
		)
		(property "Device Type" "C603H36"
			(at 0 -4.3434 0)
			(unlocked yes)
			(layer "F.Fab")
			(hide yes)
			(effects
				(font
					(size 1.016 1.016)
					(thickness 0.1524)
				)
			)
		)
		(duplicate_pad_numbers_are_jumpers no)
		(fp_line
			(start 0.508 0)
			(end -0.508 0)
			(stroke
				(width 0.2032)
				(type default)
			)
			(layer "F.SilkS")
		)
		(fp_rect
			(start -0.5842 1.3335)
			(end 0.5842 -1.3335)
			(stroke
				(width 0)
				(type default)
			)
			(fill no)
			(layer "F.CrtYd")
		)
		(fp_rect
			(start -0.5842 1.3335)
			(end 0.5842 -1.3335)
			(stroke
				(width 0)
				(type default)
			)
			(fill no)
			(layer "F.Fab")
		)
		(pad "1" smd custom
			(at 0 -0.762)
			(size 0.2159 0.2159)
			(layers "F.Cu" "F.Mask" "F.Paste")
			(net "P12V_HDD13")
			(options
				(clearance outline)
				(anchor circle)
			)
			(primitives
				(gr_poly
					(pts
						(arc
							(start -0.3302 -0.4318)
							(mid -0.402042 -0.402042)
							(end -0.4318 -0.3302)
						)
						(arc
							(start -0.4318 0.3302)
							(mid -0.402042 0.402042)
							(end -0.3302 0.4318)
						)
						(arc
							(start 0.3302 0.4318)
							(mid 0.402042 0.402042)
							(end 0.4318 0.3302)
						)
						(arc
							(start 0.4318 -0.3302)
							(mid 0.402042 -0.402042)
							(end 0.3302 -0.4318)
						)
					)
					(width 0)
					(fill yes)
				)
			)
		)
		(pad "2" smd custom
			(at 0 0.762)
			(size 0.2159 0.2159)
			(layers "F.Cu" "F.Mask" "F.Paste")
			(net "GND")
			(options
				(clearance outline)
				(anchor circle)
			)
			(primitives
				(gr_poly
					(pts
						(arc
							(start -0.3302 -0.4318)
							(mid -0.402042 -0.402042)
							(end -0.4318 -0.3302)
						)
						(arc
							(start -0.4318 0.3302)
							(mid -0.402042 0.402042)
							(end -0.3302 0.4318)
						)
						(arc
							(start 0.3302 0.4318)
							(mid 0.402042 0.402042)
							(end 0.4318 0.3302)
						)
						(arc
							(start 0.4318 -0.3302)
							(mid 0.402042 -0.402042)
							(end 0.3302 -0.4318)
						)
					)
					(width 0)
					(fill yes)
				)
			)
		)
	)
	(footprint ""
		(layer "F.Cu")
		(at 33.781746 -332.387702 180)
		(property "Reference" "C277"
			(at 0 0 180)
			(layer "F.SilkS")
			(hide yes)
			(effects
				(font
					(size 1.27 1.27)
				)
			)
		)
		(property "Value" "SCD1U10V2KX-5GP"
			(at 1.1811 -2.7051 180)
			(unlocked yes)
			(layer "F.Fab")
			(hide yes)
			(effects
				(font
					(size 1.016 1.016)
					(thickness 0.1524)
				)
			)
		)
		(property "Device Type" "C402H22"
			(at 1.1811 -4.2291 180)
			(unlocked yes)
			(layer "F.Fab")
			(hide yes)
			(effects
				(font
					(size 1.016 1.016)
					(thickness 0.1524)
				)
			)
		)
		(duplicate_pad_numbers_are_jumpers no)
		(fp_rect
			(start -0.4318 0.9525)
			(end 0.4318 -0.9525)
			(stroke
				(width 0)
				(type default)
			)
			(fill no)
			(layer "F.CrtYd")
		)
		(fp_rect
			(start -0.4318 0.9525)
			(end 0.4318 -0.9525)
			(stroke
				(width 0)
				(type default)
			)
			(fill no)
			(layer "F.Fab")
		)
		(pad "1" smd custom
			(at 0 -0.4445 180)
			(size 0.1524 0.1524)
			(layers "F.Cu" "F.Mask" "F.Paste")
			(net "P3V3")
			(options
				(clearance outline)
				(anchor circle)
			)
			(primitives
				(gr_poly
					(pts
						(arc
							(start 0.3048 -0.2032)
							(mid 0.275042 -0.275042)
							(end 0.2032 -0.3048)
						)
						(arc
							(start -0.2032 -0.3048)
							(mid -0.275042 -0.275042)
							(end -0.3048 -0.2032)
						)
						(arc
							(start -0.3048 0.2032)
							(mid -0.275042 0.275042)
							(end -0.2032 0.3048)
						)
						(arc
							(start 0.2032 0.3048)
							(mid 0.275042 0.275042)
							(end 0.3048 0.2032)
						)
					)
					(width 0)
					(fill yes)
				)
			)
		)
		(pad "2" smd custom
			(at 0 0.4445 180)
			(size 0.1524 0.1524)
			(layers "F.Cu" "F.Mask" "F.Paste")
			(net "GND")
			(options
				(clearance outline)
				(anchor circle)
			)
			(primitives
				(gr_poly
					(pts
						(arc
							(start 0.3048 -0.2032)
							(mid 0.275042 -0.275042)
							(end 0.2032 -0.3048)
						)
						(arc
							(start -0.2032 -0.3048)
							(mid -0.275042 -0.275042)
							(end -0.3048 -0.2032)
						)
						(arc
							(start -0.3048 0.2032)
							(mid -0.275042 0.275042)
							(end -0.2032 0.3048)
						)
						(arc
							(start 0.2032 0.3048)
							(mid 0.275042 0.275042)
							(end 0.3048 0.2032)
						)
					)
					(width 0)
					(fill yes)
				)
			)
		)
	)
	(footprint ""
		(layer "F.Cu")
		(at 47.243746 -214.404702)
		(property "Reference" "R275"
			(at 0 0 0)
			(layer "F.SilkS")
			(hide yes)
			(effects
				(font
					(size 1.27 1.27)
				)
			)
		)
		(property "Value" "200KR2F-L-GP"
			(at 0.064008 -3.993896 0)
			(unlocked yes)
			(layer "F.Fab")
			(hide yes)
			(effects
				(font
					(size 1.016 1.016)
					(thickness 0.1524)
				)
			)
		)
		(property "Device Type" "R402H16"
			(at 0.064008 -5.517896 0)
			(unlocked yes)
			(layer "F.Fab")
			(hide yes)
			(effects
				(font
					(size 1.016 1.016)
					(thickness 0.1524)
				)
			)
		)
		(duplicate_pad_numbers_are_jumpers no)
		(fp_line
			(start -0.508 -0.9398)
			(end -0.508 0.9398)
			(stroke
				(width 0.1524)
				(type default)
			)
			(layer "F.SilkS")
		)
		(fp_line
			(start 0.508 -0.9398)
			(end -0.508 -0.9398)
			(stroke
				(width 0.1524)
				(type default)
			)
			(layer "F.SilkS")
		)
		(fp_rect
			(start -0.508 0.9398)
			(end 0.508 -0.9398)
			(stroke
				(width 0)
				(type default)
			)
			(fill no)
			(layer "F.CrtYd")
		)
		(fp_rect
			(start -0.508 0.9398)
			(end 0.508 -0.9398)
			(stroke
				(width 0)
				(type default)
			)
			(fill no)
			(layer "F.Fab")
		)
		(pad "1" smd custom
			(at 0 -0.4445)
			(size 0.1397 0.1397)
			(layers "F.Cu" "F.Mask" "F.Paste")
			(net "P12V")
			(options
				(clearance outline)
				(anchor circle)
			)
			(primitives
				(gr_poly
					(pts
						(arc
							(start -0.1778 -0.2794)
							(mid -0.249642 -0.249642)
							(end -0.2794 -0.1778)
						)
						(arc
							(start -0.2794 0.1778)
							(mid -0.249642 0.249642)
							(end -0.1778 0.2794)
						)
						(arc
							(start 0.1778 0.2794)
							(mid 0.249642 0.249642)
							(end 0.2794 0.1778)
						)
						(arc
							(start 0.2794 -0.1778)
							(mid 0.249642 -0.249642)
							(end 0.1778 -0.2794)
						)
					)
					(width 0)
					(fill yes)
				)
			)
		)
		(pad "2" smd custom
			(at 0 0.4445)
			(size 0.1397 0.1397)
			(layers "F.Cu" "F.Mask" "F.Paste")
			(net "SW_HDD12_P")
			(options
				(clearance outline)
				(anchor circle)
			)
			(primitives
				(gr_poly
					(pts
						(arc
							(start -0.1778 -0.2794)
							(mid -0.249642 -0.249642)
							(end -0.2794 -0.1778)
						)
						(arc
							(start -0.2794 0.1778)
							(mid -0.249642 0.249642)
							(end -0.1778 0.2794)
						)
						(arc
							(start 0.1778 0.2794)
							(mid 0.249642 0.249642)
							(end 0.2794 0.1778)
						)
						(arc
							(start 0.2794 -0.1778)
							(mid 0.249642 -0.249642)
							(end 0.1778 -0.2794)
						)
					)
					(width 0)
					(fill yes)
				)
			)
		)
	)
	(footprint ""
		(layer "F.Cu")
		(at 56.133746 -381.1397)
		(property "Reference" "R191"
			(at 0 0 0)
			(layer "F.SilkS")
			(hide yes)
			(effects
				(font
					(size 1.27 1.27)
				)
			)
		)
		(property "Value" "220R3F-1-GP"
			(at -0.0254 -2.5146 0)
			(unlocked yes)
			(layer "F.Fab")
			(hide yes)
			(effects
				(font
					(size 1.016 1.016)
					(thickness 0.1524)
				)
			)
		)
		(property "Device Type" "R603H22"
			(at -0.0254 -4.0386 0)
			(unlocked yes)
			(layer "F.Fab")
			(hide yes)
			(effects
				(font
					(size 1.016 1.016)
					(thickness 0.1524)
				)
			)
		)
		(duplicate_pad_numbers_are_jumpers no)
		(fp_line
			(start -0.4826 0)
			(end -0.2032 0)
			(stroke
				(width 0.2032)
				(type default)
			)
			(layer "F.SilkS")
		)
		(fp_line
			(start 0.2032 0)
			(end 0.4826 0)
			(stroke
				(width 0.2032)
				(type default)
			)
			(layer "F.SilkS")
		)
		(fp_rect
			(start -0.5842 1.3335)
			(end 0.5842 -1.3335)
			(stroke
				(width 0)
				(type default)
			)
			(fill no)
			(layer "F.CrtYd")
		)
		(fp_rect
			(start -0.5842 1.3335)
			(end 0.5842 -1.3335)
			(stroke
				(width 0)
				(type default)
			)
			(fill no)
			(layer "F.Fab")
		)
		(pad "1" smd custom
			(at 0 -0.762)
			(size 0.2159 0.2159)
			(layers "F.Cu" "F.Mask" "F.Paste")
			(net "HDD_PRSNT_NET6")
			(options
				(clearance outline)
				(anchor circle)
			)
			(primitives
				(gr_poly
					(pts
						(arc
							(start -0.3302 -0.4318)
							(mid -0.402042 -0.402042)
							(end -0.4318 -0.3302)
						)
						(arc
							(start -0.4318 0.3302)
							(mid -0.402042 0.402042)
							(end -0.3302 0.4318)
						)
						(arc
							(start 0.3302 0.4318)
							(mid 0.402042 0.402042)
							(end 0.4318 0.3302)
						)
						(arc
							(start 0.4318 -0.3302)
							(mid 0.402042 -0.402042)
							(end 0.3302 -0.4318)
						)
					)
					(width 0)
					(fill yes)
				)
			)
		)
		(pad "2" smd custom
			(at 0 0.762)
			(size 0.2159 0.2159)
			(layers "F.Cu" "F.Mask" "F.Paste")
			(net "HDD_PRSNT6")
			(options
				(clearance outline)
				(anchor circle)
			)
			(primitives
				(gr_poly
					(pts
						(arc
							(start -0.3302 -0.4318)
							(mid -0.402042 -0.402042)
							(end -0.4318 -0.3302)
						)
						(arc
							(start -0.4318 0.3302)
							(mid -0.402042 0.402042)
							(end -0.3302 0.4318)
						)
						(arc
							(start 0.3302 0.4318)
							(mid 0.402042 0.402042)
							(end 0.4318 0.3302)
						)
						(arc
							(start 0.4318 -0.3302)
							(mid 0.402042 -0.402042)
							(end 0.3302 -0.4318)
						)
					)
					(width 0)
					(fill yes)
				)
			)
		)
	)
	(footprint ""
		(layer "F.Cu")
		(at 205.104746 -276.7457)
		(property "Reference" "TP27"
			(at 0 0 0)
			(layer "F.SilkS")
			(hide yes)
			(effects
				(font
					(size 1.27 1.27)
				)
			)
		)
		(property "Value" "TPAD32-GP"
			(at 0 -3.166364 0)
			(unlocked yes)
			(layer "F.Fab")
			(hide yes)
			(effects
				(font
					(size 1.016 1.016)
					(thickness 0.1524)
				)
			)
		)
		(property "Device Type" "TPAD32"
			(at 0 -4.690618 0)
			(unlocked yes)
			(layer "F.Fab")
			(hide yes)
			(effects
				(font
					(size 1.016 1.016)
					(thickness 0.1524)
				)
			)
		)
		(duplicate_pad_numbers_are_jumpers no)
		(fp_poly
			(pts
				(arc
					(start 0.4064 0)
					(mid -0.4064 0)
					(end 0.4064 0)
				)
			)
			(stroke
				(width 0)
				(type default)
			)
			(fill no)
			(layer "F.CrtYd")
		)
		(fp_poly
			(pts
				(arc
					(start 0.7112 0)
					(mid -0.7112 0)
					(end 0.7112 0)
				)
			)
			(stroke
				(width 0)
				(type default)
			)
			(fill no)
			(layer "F.Fab")
		)
		(pad "1" smd circle
			(at 0 0)
			(size 0.8128 0.8128)
			(layers "F.Cu" "F.Mask" "F.Paste")
			(net "ACT_HDD2")
		)
	)
	(footprint ""
		(layer "F.Cu")
		(at 29.590746 -336.070702)
		(property "Reference" "R464"
			(at 0 0 0)
			(layer "F.SilkS")
			(hide yes)
			(effects
				(font
					(size 1.27 1.27)
				)
			)
		)
		(property "Value" "4K7R2J-2-GP"
			(at 0.064008 -3.993896 0)
			(unlocked yes)
			(layer "F.Fab")
			(hide yes)
			(effects
				(font
					(size 1.016 1.016)
					(thickness 0.1524)
				)
			)
		)
		(property "Device Type" "R402H16"
			(at 0.064008 -5.517896 0)
			(unlocked yes)
			(layer "F.Fab")
			(hide yes)
			(effects
				(font
					(size 1.016 1.016)
					(thickness 0.1524)
				)
			)
		)
		(duplicate_pad_numbers_are_jumpers no)
		(fp_line
			(start -0.508 -0.9398)
			(end -0.508 0.9398)
			(stroke
				(width 0.1524)
				(type default)
			)
			(layer "F.SilkS")
		)
		(fp_line
			(start 0.508 -0.9398)
			(end -0.508 -0.9398)
			(stroke
				(width 0.1524)
				(type default)
			)
			(layer "F.SilkS")
		)
		(fp_rect
			(start -0.508 0.9398)
			(end 0.508 -0.9398)
			(stroke
				(width 0)
				(type default)
			)
			(fill no)
			(layer "F.CrtYd")
		)
		(fp_rect
			(start -0.508 0.9398)
			(end 0.508 -0.9398)
			(stroke
				(width 0)
				(type default)
			)
			(fill no)
			(layer "F.Fab")
		)
		(pad "1" smd custom
			(at 0 -0.4445)
			(size 0.1397 0.1397)
			(layers "F.Cu" "F.Mask" "F.Paste")
			(net "P3V3")
			(options
				(clearance outline)
				(anchor circle)
			)
			(primitives
				(gr_poly
					(pts
						(arc
							(start -0.1778 -0.2794)
							(mid -0.249642 -0.249642)
							(end -0.2794 -0.1778)
						)
						(arc
							(start -0.2794 0.1778)
							(mid -0.249642 0.249642)
							(end -0.1778 0.2794)
						)
						(arc
							(start 0.1778 0.2794)
							(mid 0.249642 0.249642)
							(end 0.2794 0.1778)
						)
						(arc
							(start 0.2794 -0.1778)
							(mid 0.249642 -0.249642)
							(end 0.1778 -0.2794)
						)
					)
					(width 0)
					(fill yes)
				)
			)
		)
		(pad "2" smd custom
			(at 0 0.4445)
			(size 0.1397 0.1397)
			(layers "F.Cu" "F.Mask" "F.Paste")
			(net "SAS2X28_A_HDD11_FLT")
			(options
				(clearance outline)
				(anchor circle)
			)
			(primitives
				(gr_poly
					(pts
						(arc
							(start -0.1778 -0.2794)
							(mid -0.249642 -0.249642)
							(end -0.2794 -0.1778)
						)
						(arc
							(start -0.2794 0.1778)
							(mid -0.249642 0.249642)
							(end -0.1778 0.2794)
						)
						(arc
							(start 0.1778 0.2794)
							(mid 0.249642 0.249642)
							(end 0.2794 0.1778)
						)
						(arc
							(start 0.2794 -0.1778)
							(mid 0.249642 -0.249642)
							(end 0.1778 -0.2794)
						)
					)
					(width 0)
					(fill yes)
				)
			)
		)
	)
	(footprint ""
		(layer "F.Cu")
		(at 199.820784 -190.470028 -90)
		(property "Reference" "U11"
			(at 0 0 270)
			(layer "F.SilkS")
			(hide yes)
			(effects
				(font
					(size 1.27 1.27)
				)
			)
		)
		(property "Value" "P2003EVG-GP"
			(at 0 -11.1252 270)
			(unlocked yes)
			(layer "F.Fab")
			(hide yes)
			(effects
				(font
					(size 1.016 1.016)
					(thickness 0.1524)
				)
			)
		)
		(property "Device Type" "SOIC8H79"
			(at 0 -12.6492 270)
			(unlocked yes)
			(layer "F.Fab")
			(hide yes)
			(effects
				(font
					(size 1.016 1.016)
					(thickness 0.1524)
				)
			)
		)
		(duplicate_pad_numbers_are_jumpers no)
		(fp_line
			(start -2.6162 3.429)
			(end -2.6162 1.4732)
			(stroke
				(width 0.4064)
				(type default)
			)
			(layer "F.SilkS")
		)
		(fp_line
			(start -2.7432 1.4224)
			(end 2.1336 1.4224)
			(stroke
				(width 0.1524)
				(type default)
			)
			(layer "F.SilkS")
		)
		(fp_line
			(start 2.1336 1.4224)
			(end 2.1336 -1.4224)
			(stroke
				(width 0.1524)
				(type default)
			)
			(layer "F.SilkS")
		)
		(fp_line
			(start -2.2352 0)
			(end -2.7432 0.508)
			(stroke
				(width 0.1524)
				(type default)
			)
			(layer "F.SilkS")
		)
		(fp_line
			(start -2.7432 -0.508)
			(end -2.2352 0)
			(stroke
				(width 0.1524)
				(type default)
			)
			(layer "F.SilkS")
		)
		(fp_line
			(start -2.7432 -1.4224)
			(end -2.7432 1.4224)
			(stroke
				(width 0.1524)
				(type default)
			)
			(layer "F.SilkS")
		)
		(fp_line
			(start 2.1336 -1.4224)
			(end -2.7432 -1.4224)
			(stroke
				(width 0.1524)
				(type default)
			)
			(layer "F.SilkS")
		)
		(fp_poly
			(pts
				(xy 2.2098 -1.4224) (xy 2.2098 1.4224) (xy -2.2225 1.4224) (xy -2.2225 -1.4224)
			)
			(stroke
				(width 0)
				(type default)
			)
			(fill yes)
			(layer "F.SilkS")
		)
		(fp_rect
			(start -2.4511 2.9972)
			(end 2.4511 -2.9972)
			(stroke
				(width 0)
				(type default)
			)
			(fill no)
			(layer "F.CrtYd")
		)
		(fp_poly
			(pts
				(xy -2.8194 3.6322) (xy -2.8194 -3.6322) (xy 2.8194 -3.6322) (xy 2.8194 -2.2987) (xy 2.4511 -2.2987)
				(xy 2.4511 -2.9972) (xy -2.4511 -2.9972) (xy -2.4511 2.9972) (xy 2.4511 2.9972) (xy 2.4511 -2.286)
				(xy 2.8194 -2.286) (xy 2.8194 3.6322)
			)
			(stroke
				(width 0)
				(type default)
			)
			(fill no)
			(layer "F.CrtYd")
		)
		(fp_rect
			(start -2.8194 3.6322)
			(end 2.8194 -3.6322)
			(stroke
				(width 0)
				(type default)
			)
			(fill no)
			(layer "F.Fab")
		)
		(pad "1" smd rect
			(at -1.905 2.54 270)
			(size 0.635 1.651)
			(layers "F.Cu" "F.Mask" "F.Paste")
			(net "P12V")
		)
		(pad "2" smd rect
			(at -0.635 2.54 270)
			(size 0.635 1.651)
			(layers "F.Cu" "F.Mask" "F.Paste")
			(net "P12V")
		)
		(pad "3" smd rect
			(at 0.635 2.54 270)
			(size 0.635 1.651)
			(layers "F.Cu" "F.Mask" "F.Paste")
			(net "P12V")
		)
		(pad "4" smd rect
			(at 1.905 2.54 270)
			(size 0.635 1.651)
			(layers "F.Cu" "F.Mask" "F.Paste")
			(net "SW_HDD3_N")
		)
		(pad "5" smd rect
			(at 1.905 -2.54 270)
			(size 0.635 1.651)
			(layers "F.Cu" "F.Mask" "F.Paste")
			(net "P12V_HDD3")
		)
		(pad "6" smd rect
			(at 0.635 -2.54 270)
			(size 0.635 1.651)
			(layers "F.Cu" "F.Mask" "F.Paste")
			(net "P12V_HDD3")
		)
		(pad "7" smd rect
			(at -0.635 -2.54 270)
			(size 0.635 1.651)
			(layers "F.Cu" "F.Mask" "F.Paste")
			(net "P12V_HDD3")
		)
		(pad "8" smd rect
			(at -1.905 -2.54 270)
			(size 0.635 1.651)
			(layers "F.Cu" "F.Mask" "F.Paste")
			(net "P12V_HDD3")
		)
	)
	(footprint ""
		(layer "F.Cu")
		(at 217.8812 -497.713 180)
		(property "Reference" "C114"
			(at 0 0 180)
			(layer "F.SilkS")
			(hide yes)
			(effects
				(font
					(size 1.27 1.27)
				)
			)
		)
		(property "Value" "SC10U25V6KX-1GP"
			(at -0.0762 -5.1308 180)
			(unlocked yes)
			(layer "F.Fab")
			(hide yes)
			(effects
				(font
					(size 1.016 1.016)
					(thickness 0.1524)
				)
			)
		)
		(property "Device Type" "C1206H71"
			(at -0.127 -6.6548 180)
			(unlocked yes)
			(layer "F.Fab")
			(hide yes)
			(effects
				(font
					(size 1.016 1.016)
					(thickness 0.1524)
				)
			)
		)
		(duplicate_pad_numbers_are_jumpers no)
		(fp_line
			(start 1.016 2.2352)
			(end -1.016 2.2352)
			(stroke
				(width 0.1524)
				(type default)
			)
			(layer "F.SilkS")
		)
		(fp_line
			(start 1.016 0.8382)
			(end 1.016 2.2352)
			(stroke
				(width 0.1524)
				(type default)
			)
			(layer "F.SilkS")
		)
		(fp_line
			(start 1.016 -2.2352)
			(end 1.016 -0.8382)
			(stroke
				(width 0.1524)
				(type default)
			)
			(layer "F.SilkS")
		)
		(fp_line
			(start -1.016 2.2352)
			(end -1.016 0.8382)
			(stroke
				(width 0.1524)
				(type default)
			)
			(layer "F.SilkS")
		)
		(fp_line
			(start -1.016 -0.8382)
			(end -1.016 -2.2352)
			(stroke
				(width 0.1524)
				(type default)
			)
			(layer "F.SilkS")
		)
		(fp_line
			(start -1.016 -2.2352)
			(end 1.016 -2.2352)
			(stroke
				(width 0.1524)
				(type default)
			)
			(layer "F.SilkS")
		)
		(fp_rect
			(start -1.0922 2.3114)
			(end 1.0922 -2.3114)
			(stroke
				(width 0)
				(type default)
			)
			(fill no)
			(layer "F.CrtYd")
		)
		(fp_poly
			(pts
				(xy 1.0922 -2.3114) (xy 1.0922 2.3114) (xy -1.0922 2.3114) (xy -1.0922 -2.3114)
			)
			(stroke
				(width 0)
				(type default)
			)
			(fill no)
			(layer "F.Fab")
		)
		(pad "1" smd rect
			(at 0 -1.397 180)
			(size 1.651 1.27)
			(layers "F.Cu" "F.Mask" "F.Paste")
			(net "P12V_HDD0")
		)
		(pad "2" smd rect
			(at 0 1.397 180)
			(size 1.651 1.27)
			(layers "F.Cu" "F.Mask" "F.Paste")
			(net "GND")
		)
	)
	(footprint ""
		(layer "F.Cu")
		(at 191.092582 -286.103568 -90)
		(property "Reference" "R135"
			(at 0 0 270)
			(layer "F.SilkS")
			(hide yes)
			(effects
				(font
					(size 1.27 1.27)
				)
			)
		)
		(property "Value" "1KR2F-3-GP"
			(at 0.064008 -3.993896 270)
			(unlocked yes)
			(layer "F.Fab")
			(hide yes)
			(effects
				(font
					(size 1.016 1.016)
					(thickness 0.1524)
				)
			)
		)
		(property "Device Type" "R402H16"
			(at 0.064008 -5.517896 270)
			(unlocked yes)
			(layer "F.Fab")
			(hide yes)
			(effects
				(font
					(size 1.016 1.016)
					(thickness 0.1524)
				)
			)
		)
		(duplicate_pad_numbers_are_jumpers no)
		(fp_line
			(start -0.508 -0.9398)
			(end -0.508 0.9398)
			(stroke
				(width 0.1524)
				(type default)
			)
			(layer "F.SilkS")
		)
		(fp_line
			(start 0.508 -0.9398)
			(end -0.508 -0.9398)
			(stroke
				(width 0.1524)
				(type default)
			)
			(layer "F.SilkS")
		)
		(fp_rect
			(start -0.508 0.9398)
			(end 0.508 -0.9398)
			(stroke
				(width 0)
				(type default)
			)
			(fill no)
			(layer "F.CrtYd")
		)
		(fp_rect
			(start -0.508 0.9398)
			(end 0.508 -0.9398)
			(stroke
				(width 0)
				(type default)
			)
			(fill no)
			(layer "F.Fab")
		)
		(pad "1" smd custom
			(at 0 -0.4445 270)
			(size 0.1397 0.1397)
			(layers "F.Cu" "F.Mask" "F.Paste")
			(net "P3V3")
			(options
				(clearance outline)
				(anchor circle)
			)
			(primitives
				(gr_poly
					(pts
						(arc
							(start -0.1778 -0.2794)
							(mid -0.249642 -0.249642)
							(end -0.2794 -0.1778)
						)
						(arc
							(start -0.2794 0.1778)
							(mid -0.249642 0.249642)
							(end -0.1778 0.2794)
						)
						(arc
							(start 0.1778 0.2794)
							(mid 0.249642 0.249642)
							(end 0.2794 0.1778)
						)
						(arc
							(start 0.2794 -0.1778)
							(mid 0.249642 -0.249642)
							(end 0.1778 -0.2794)
						)
					)
					(width 0)
					(fill yes)
				)
			)
		)
		(pad "2" smd custom
			(at 0 0.4445 270)
			(size 0.1397 0.1397)
			(layers "F.Cu" "F.Mask" "F.Paste")
			(net "SW_PWR_HDD2")
			(options
				(clearance outline)
				(anchor circle)
			)
			(primitives
				(gr_poly
					(pts
						(arc
							(start -0.1778 -0.2794)
							(mid -0.249642 -0.249642)
							(end -0.2794 -0.1778)
						)
						(arc
							(start -0.2794 0.1778)
							(mid -0.249642 0.249642)
							(end -0.1778 0.2794)
						)
						(arc
							(start 0.1778 0.2794)
							(mid 0.249642 0.249642)
							(end 0.2794 0.1778)
						)
						(arc
							(start 0.2794 -0.1778)
							(mid 0.249642 -0.249642)
							(end 0.1778 -0.2794)
						)
					)
					(width 0)
					(fill yes)
				)
			)
		)
	)
	(footprint ""
		(layer "F.Cu")
		(at 78.358746 -91.4527 90)
		(property "Reference" "R232"
			(at 0 0 90)
			(layer "F.SilkS")
			(hide yes)
			(effects
				(font
					(size 1.27 1.27)
				)
			)
		)
		(property "Value" "4K7R2J-2-GP"
			(at 0.064008 -3.993896 90)
			(unlocked yes)
			(layer "F.Fab")
			(hide yes)
			(effects
				(font
					(size 1.016 1.016)
					(thickness 0.1524)
				)
			)
		)
		(property "Device Type" "R402H16"
			(at 0.064008 -5.517896 90)
			(unlocked yes)
			(layer "F.Fab")
			(hide yes)
			(effects
				(font
					(size 1.016 1.016)
					(thickness 0.1524)
				)
			)
		)
		(duplicate_pad_numbers_are_jumpers no)
		(fp_line
			(start 0.508 -0.9398)
			(end -0.508 -0.9398)
			(stroke
				(width 0.1524)
				(type default)
			)
			(layer "F.SilkS")
		)
		(fp_line
			(start -0.508 -0.9398)
			(end -0.508 0.9398)
			(stroke
				(width 0.1524)
				(type default)
			)
			(layer "F.SilkS")
		)
		(fp_rect
			(start -0.508 0.9398)
			(end 0.508 -0.9398)
			(stroke
				(width 0)
				(type default)
			)
			(fill no)
			(layer "F.CrtYd")
		)
		(fp_rect
			(start -0.508 0.9398)
			(end 0.508 -0.9398)
			(stroke
				(width 0)
				(type default)
			)
			(fill no)
			(layer "F.Fab")
		)
		(pad "1" smd custom
			(at 0 -0.4445 90)
			(size 0.1397 0.1397)
			(layers "F.Cu" "F.Mask" "F.Paste")
			(net "P12V")
			(options
				(clearance outline)
				(anchor circle)
			)
			(primitives
				(gr_poly
					(pts
						(arc
							(start -0.1778 -0.2794)
							(mid -0.249642 -0.249642)
							(end -0.2794 -0.1778)
						)
						(arc
							(start -0.2794 0.1778)
							(mid -0.249642 0.249642)
							(end -0.1778 0.2794)
						)
						(arc
							(start 0.1778 0.2794)
							(mid 0.249642 0.249642)
							(end 0.2794 0.1778)
						)
						(arc
							(start 0.2794 -0.1778)
							(mid 0.249642 -0.249642)
							(end 0.1778 -0.2794)
						)
					)
					(width 0)
					(fill yes)
				)
			)
		)
		(pad "2" smd custom
			(at 0 0.4445 90)
			(size 0.1397 0.1397)
			(layers "F.Cu" "F.Mask" "F.Paste")
			(net "SW_HDD9_R")
			(options
				(clearance outline)
				(anchor circle)
			)
			(primitives
				(gr_poly
					(pts
						(arc
							(start -0.1778 -0.2794)
							(mid -0.249642 -0.249642)
							(end -0.2794 -0.1778)
						)
						(arc
							(start -0.2794 0.1778)
							(mid -0.249642 0.249642)
							(end -0.1778 0.2794)
						)
						(arc
							(start 0.1778 0.2794)
							(mid 0.249642 0.249642)
							(end 0.2794 0.1778)
						)
						(arc
							(start 0.2794 -0.1778)
							(mid 0.249642 -0.249642)
							(end 0.1778 -0.2794)
						)
					)
					(width 0)
					(fill yes)
				)
			)
		)
	)
	(footprint ""
		(layer "F.Cu")
		(at 232.409746 -26.1747)
		(property "Reference" "TP22"
			(at 0 0 0)
			(layer "F.SilkS")
			(hide yes)
			(effects
				(font
					(size 1.27 1.27)
				)
			)
		)
		(property "Value" "TPAD32-GP"
			(at 0 -3.166364 0)
			(unlocked yes)
			(layer "F.Fab")
			(hide yes)
			(effects
				(font
					(size 1.016 1.016)
					(thickness 0.1524)
				)
			)
		)
		(property "Device Type" "TPAD32"
			(at 0 -4.690618 0)
			(unlocked yes)
			(layer "F.Fab")
			(hide yes)
			(effects
				(font
					(size 1.016 1.016)
					(thickness 0.1524)
				)
			)
		)
		(duplicate_pad_numbers_are_jumpers no)
		(fp_poly
			(pts
				(arc
					(start 0.4064 0)
					(mid -0.4064 0)
					(end 0.4064 0)
				)
			)
			(stroke
				(width 0)
				(type default)
			)
			(fill no)
			(layer "F.CrtYd")
		)
		(fp_poly
			(pts
				(arc
					(start 0.7112 0)
					(mid -0.7112 0)
					(end 0.7112 0)
				)
			)
			(stroke
				(width 0)
				(type default)
			)
			(fill no)
			(layer "F.Fab")
		)
		(pad "1" smd circle
			(at 0 0)
			(size 0.8128 0.8128)
			(layers "F.Cu" "F.Mask" "F.Paste")
			(net "P5VA_PGD")
		)
	)
	(footprint ""
		(layer "F.Cu")
		(at 195.961 -86.233 180)
		(property "Reference" "R412"
			(at 0 0 180)
			(layer "F.SilkS")
			(hide yes)
			(effects
				(font
					(size 1.27 1.27)
				)
			)
		)
		(property "Value" "0R2J-2-GP"
			(at 0.064008 -3.993896 180)
			(unlocked yes)
			(layer "F.Fab")
			(hide yes)
			(effects
				(font
					(size 1.016 1.016)
					(thickness 0.1524)
				)
			)
		)
		(property "Device Type" "R402H16"
			(at 0.064008 -5.517896 180)
			(unlocked yes)
			(layer "F.Fab")
			(hide yes)
			(effects
				(font
					(size 1.016 1.016)
					(thickness 0.1524)
				)
			)
		)
		(duplicate_pad_numbers_are_jumpers no)
		(fp_line
			(start 0.508 -0.9398)
			(end -0.508 -0.9398)
			(stroke
				(width 0.1524)
				(type default)
			)
			(layer "F.SilkS")
		)
		(fp_line
			(start -0.508 -0.9398)
			(end -0.508 0.9398)
			(stroke
				(width 0.1524)
				(type default)
			)
			(layer "F.SilkS")
		)
		(fp_rect
			(start -0.508 0.9398)
			(end 0.508 -0.9398)
			(stroke
				(width 0)
				(type default)
			)
			(fill no)
			(layer "F.CrtYd")
		)
		(fp_rect
			(start -0.508 0.9398)
			(end 0.508 -0.9398)
			(stroke
				(width 0)
				(type default)
			)
			(fill no)
			(layer "F.Fab")
		)
		(pad "1" smd custom
			(at 0 -0.4445 180)
			(size 0.1397 0.1397)
			(layers "F.Cu" "F.Mask" "F.Paste")
			(net "SW_HDD4_G")
			(options
				(clearance outline)
				(anchor circle)
			)
			(primitives
				(gr_poly
					(pts
						(arc
							(start -0.1778 -0.2794)
							(mid -0.249642 -0.249642)
							(end -0.2794 -0.1778)
						)
						(arc
							(start -0.2794 0.1778)
							(mid -0.249642 0.249642)
							(end -0.1778 0.2794)
						)
						(arc
							(start 0.1778 0.2794)
							(mid 0.249642 0.249642)
							(end 0.2794 0.1778)
						)
						(arc
							(start 0.2794 -0.1778)
							(mid 0.249642 -0.249642)
							(end 0.1778 -0.2794)
						)
					)
					(width 0)
					(fill yes)
				)
			)
		)
		(pad "2" smd custom
			(at 0 0.4445 180)
			(size 0.1397 0.1397)
			(layers "F.Cu" "F.Mask" "F.Paste")
			(net "SW_HDD4_R")
			(options
				(clearance outline)
				(anchor circle)
			)
			(primitives
				(gr_poly
					(pts
						(arc
							(start -0.1778 -0.2794)
							(mid -0.249642 -0.249642)
							(end -0.2794 -0.1778)
						)
						(arc
							(start -0.2794 0.1778)
							(mid -0.249642 0.249642)
							(end -0.1778 0.2794)
						)
						(arc
							(start 0.1778 0.2794)
							(mid 0.249642 0.249642)
							(end 0.2794 0.1778)
						)
						(arc
							(start 0.2794 -0.1778)
							(mid 0.249642 -0.249642)
							(end 0.1778 -0.2794)
						)
					)
					(width 0)
					(fill yes)
				)
			)
		)
	)
	(footprint ""
		(layer "F.Cu")
		(at 42.500042 -144.159986 180)
		(property "Reference" "LED9"
			(at 0 0 180)
			(layer "F.SilkS")
			(hide yes)
			(effects
				(font
					(size 1.27 1.27)
				)
			)
		)
		(property "Value" "LED-RB-4-GP"
			(at 5.88899 1.80848 180)
			(unlocked yes)
			(layer "F.Fab")
			(hide yes)
			(effects
				(font
					(size 1.016 1.016)
					(thickness 0.1524)
				)
			)
		)
		(property "Device Type" "LED1613-4PH20"
			(at 5.88899 0.28448 180)
			(unlocked yes)
			(layer "F.Fab")
			(hide yes)
			(effects
				(font
					(size 1.016 1.016)
					(thickness 0.1524)
				)
			)
		)
		(duplicate_pad_numbers_are_jumpers no)
		(fp_line
			(start 1.4478 0.9652)
			(end -1.4478 0.9652)
			(stroke
				(width 0.1524)
				(type default)
			)
			(layer "F.SilkS")
		)
		(fp_line
			(start 1.4478 -0.9652)
			(end 1.4478 0.9652)
			(stroke
				(width 0.1524)
				(type default)
			)
			(layer "F.SilkS")
		)
		(fp_line
			(start -1.4478 0.9652)
			(end -1.4478 -0.9652)
			(stroke
				(width 0.1524)
				(type default)
			)
			(layer "F.SilkS")
		)
		(fp_line
			(start -1.4478 0.9652)
			(end -1.4478 -0.9652)
			(stroke
				(width 0.508)
				(type default)
			)
			(layer "F.SilkS")
		)
		(fp_line
			(start -1.4478 -0.9652)
			(end 1.4478 -0.9652)
			(stroke
				(width 0.1524)
				(type default)
			)
			(layer "F.SilkS")
		)
		(fp_rect
			(start -0.8001 0.6477)
			(end 0.8001 -0.6477)
			(stroke
				(width 0)
				(type default)
			)
			(fill no)
			(layer "F.CrtYd")
		)
		(fp_poly
			(pts
				(xy -1.7018 1.2192) (xy -1.7018 -0.06223) (xy -0.8001 -0.06223) (xy -0.8001 0.6477) (xy 0.8001 0.6477)
				(xy 0.8001 -0.6477) (xy -0.8001 -0.6477) (xy -0.8001 -0.0635) (xy -1.7018 -0.0635) (xy -1.7018 -1.2192)
				(xy 1.7018 -1.2192) (xy 1.7018 1.2192)
			)
			(stroke
				(width 0)
				(type default)
			)
			(fill no)
			(layer "F.CrtYd")
		)
		(fp_rect
			(start -1.7018 1.2192)
			(end 1.7018 -1.2192)
			(stroke
				(width 0)
				(type default)
			)
			(fill no)
			(layer "F.Fab")
		)
		(pad "1" smd rect
			(at -0.73025 0.4064 180)
			(size 0.9144 0.6096)
			(layers "F.Cu" "F.Mask" "F.Paste")
			(net "DRV_ACT_NET8")
		)
		(pad "2" smd rect
			(at -0.73025 -0.4064 180)
			(size 0.9144 0.6096)
			(layers "F.Cu" "F.Mask" "F.Paste")
			(net "FLT_NET_HDD8")
		)
		(pad "3" smd rect
			(at 0.73025 -0.4064 180)
			(size 0.9144 0.6096)
			(layers "F.Cu" "F.Mask" "F.Paste")
			(net "FLT_HDD8")
		)
		(pad "4" smd rect
			(at 0.73025 0.4064 180)
			(size 0.9144 0.6096)
			(layers "F.Cu" "F.Mask" "F.Paste")
			(net "DRV_ACT_8")
		)
	)
	(footprint ""
		(layer "F.Cu")
		(at 217.762582 -269.466568 -90)
		(property "Reference" "C136"
			(at 0 0 270)
			(layer "F.SilkS")
			(hide yes)
			(effects
				(font
					(size 1.27 1.27)
				)
			)
		)
		(property "Value" "SCD01U50V2KX-1GP"
			(at 1.1811 -2.7051 270)
			(unlocked yes)
			(layer "F.Fab")
			(hide yes)
			(effects
				(font
					(size 1.016 1.016)
					(thickness 0.1524)
				)
			)
		)
		(property "Device Type" "C402H22"
			(at 1.1811 -4.2291 270)
			(unlocked yes)
			(layer "F.Fab")
			(hide yes)
			(effects
				(font
					(size 1.016 1.016)
					(thickness 0.1524)
				)
			)
		)
		(duplicate_pad_numbers_are_jumpers no)
		(fp_rect
			(start -0.4318 0.9525)
			(end 0.4318 -0.9525)
			(stroke
				(width 0)
				(type default)
			)
			(fill no)
			(layer "F.CrtYd")
		)
		(fp_rect
			(start -0.4318 0.9525)
			(end 0.4318 -0.9525)
			(stroke
				(width 0)
				(type default)
			)
			(fill no)
			(layer "F.Fab")
		)
		(pad "1" smd custom
			(at 0 -0.4445 270)
			(size 0.1524 0.1524)
			(layers "F.Cu" "F.Mask" "F.Paste")
			(net "SAS2X28_DRIVE_RX_N_B2")
			(options
				(clearance outline)
				(anchor circle)
			)
			(primitives
				(gr_poly
					(pts
						(arc
							(start 0.3048 -0.2032)
							(mid 0.275042 -0.275042)
							(end 0.2032 -0.3048)
						)
						(arc
							(start -0.2032 -0.3048)
							(mid -0.275042 -0.275042)
							(end -0.3048 -0.2032)
						)
						(arc
							(start -0.3048 0.2032)
							(mid -0.275042 0.275042)
							(end -0.2032 0.3048)
						)
						(arc
							(start 0.2032 0.3048)
							(mid 0.275042 0.275042)
							(end 0.3048 0.2032)
						)
					)
					(width 0)
					(fill yes)
				)
			)
		)
		(pad "2" smd custom
			(at 0 0.4445 270)
			(size 0.1524 0.1524)
			(layers "F.Cu" "F.Mask" "F.Paste")
			(net "SAS2X28_B_HDD2_RX_-")
			(options
				(clearance outline)
				(anchor circle)
			)
			(primitives
				(gr_poly
					(pts
						(arc
							(start 0.3048 -0.2032)
							(mid 0.275042 -0.275042)
							(end 0.2032 -0.3048)
						)
						(arc
							(start -0.2032 -0.3048)
							(mid -0.275042 -0.275042)
							(end -0.3048 -0.2032)
						)
						(arc
							(start -0.3048 0.2032)
							(mid -0.275042 0.275042)
							(end -0.2032 0.3048)
						)
						(arc
							(start 0.2032 0.3048)
							(mid 0.275042 0.275042)
							(end 0.3048 0.2032)
						)
					)
					(width 0)
					(fill yes)
				)
			)
		)
	)
	(footprint ""
		(layer "F.Cu")
		(at 37.210746 -124.996702)
		(property "Reference" "C317"
			(at 0 0 0)
			(layer "F.SilkS")
			(hide yes)
			(effects
				(font
					(size 1.27 1.27)
				)
			)
		)
		(property "Value" "SC10U16V6KX-2GP"
			(at -0.0762 -5.1308 0)
			(unlocked yes)
			(layer "F.Fab")
			(hide yes)
			(effects
				(font
					(size 1.016 1.016)
					(thickness 0.1524)
				)
			)
		)
		(property "Device Type" "C1206H71"
			(at -0.127 -6.6548 0)
			(unlocked yes)
			(layer "F.Fab")
			(hide yes)
			(effects
				(font
					(size 1.016 1.016)
					(thickness 0.1524)
				)
			)
		)
		(duplicate_pad_numbers_are_jumpers no)
		(fp_line
			(start -1.016 -2.2352)
			(end 1.016 -2.2352)
			(stroke
				(width 0.1524)
				(type default)
			)
			(layer "F.SilkS")
		)
		(fp_line
			(start -1.016 -0.8382)
			(end -1.016 -2.2352)
			(stroke
				(width 0.1524)
				(type default)
			)
			(layer "F.SilkS")
		)
		(fp_line
			(start -1.016 2.2352)
			(end -1.016 0.8382)
			(stroke
				(width 0.1524)
				(type default)
			)
			(layer "F.SilkS")
		)
		(fp_line
			(start 1.016 -2.2352)
			(end 1.016 -0.8382)
			(stroke
				(width 0.1524)
				(type default)
			)
			(layer "F.SilkS")
		)
		(fp_line
			(start 1.016 0.8382)
			(end 1.016 2.2352)
			(stroke
				(width 0.1524)
				(type default)
			)
			(layer "F.SilkS")
		)
		(fp_line
			(start 1.016 2.2352)
			(end -1.016 2.2352)
			(stroke
				(width 0.1524)
				(type default)
			)
			(layer "F.SilkS")
		)
		(fp_rect
			(start -1.0922 2.3114)
			(end 1.0922 -2.3114)
			(stroke
				(width 0)
				(type default)
			)
			(fill no)
			(layer "F.CrtYd")
		)
		(fp_poly
			(pts
				(xy 1.0922 -2.3114) (xy 1.0922 2.3114) (xy -1.0922 2.3114) (xy -1.0922 -2.3114)
			)
			(stroke
				(width 0)
				(type default)
			)
			(fill no)
			(layer "F.Fab")
		)
		(pad "1" smd rect
			(at 0 -1.397)
			(size 1.651 1.27)
			(layers "F.Cu" "F.Mask" "F.Paste")
			(net "P5V_HDD13")
		)
		(pad "2" smd rect
			(at 0 1.397)
			(size 1.651 1.27)
			(layers "F.Cu" "F.Mask" "F.Paste")
			(net "GND")
		)
	)
	(footprint ""
		(layer "F.Cu")
		(at 39.750746 -247.7897 90)
		(property "Reference" "R199"
			(at 0 0 90)
			(layer "F.SilkS")
			(hide yes)
			(effects
				(font
					(size 1.27 1.27)
				)
			)
		)
		(property "Value" "402R2F-GP"
			(at 0.064008 -3.993896 90)
			(unlocked yes)
			(layer "F.Fab")
			(hide yes)
			(effects
				(font
					(size 1.016 1.016)
					(thickness 0.1524)
				)
			)
		)
		(property "Device Type" "R402H16"
			(at 0.064008 -5.517896 90)
			(unlocked yes)
			(layer "F.Fab")
			(hide yes)
			(effects
				(font
					(size 1.016 1.016)
					(thickness 0.1524)
				)
			)
		)
		(duplicate_pad_numbers_are_jumpers no)
		(fp_line
			(start 0.508 -0.9398)
			(end -0.508 -0.9398)
			(stroke
				(width 0.1524)
				(type default)
			)
			(layer "F.SilkS")
		)
		(fp_line
			(start -0.508 -0.9398)
			(end -0.508 0.9398)
			(stroke
				(width 0.1524)
				(type default)
			)
			(layer "F.SilkS")
		)
		(fp_rect
			(start -0.508 0.9398)
			(end 0.508 -0.9398)
			(stroke
				(width 0)
				(type default)
			)
			(fill no)
			(layer "F.CrtYd")
		)
		(fp_rect
			(start -0.508 0.9398)
			(end 0.508 -0.9398)
			(stroke
				(width 0)
				(type default)
			)
			(fill no)
			(layer "F.Fab")
		)
		(pad "1" smd custom
			(at 0 -0.4445 90)
			(size 0.1397 0.1397)
			(layers "F.Cu" "F.Mask" "F.Paste")
			(net "P5VB_HDD7_LED")
			(options
				(clearance outline)
				(anchor circle)
			)
			(primitives
				(gr_poly
					(pts
						(arc
							(start -0.1778 -0.2794)
							(mid -0.249642 -0.249642)
							(end -0.2794 -0.1778)
						)
						(arc
							(start -0.2794 0.1778)
							(mid -0.249642 0.249642)
							(end -0.1778 0.2794)
						)
						(arc
							(start 0.1778 0.2794)
							(mid 0.249642 0.249642)
							(end 0.2794 0.1778)
						)
						(arc
							(start 0.2794 -0.1778)
							(mid 0.249642 -0.249642)
							(end 0.1778 -0.2794)
						)
					)
					(width 0)
					(fill yes)
				)
			)
		)
		(pad "2" smd custom
			(at 0 0.4445 90)
			(size 0.1397 0.1397)
			(layers "F.Cu" "F.Mask" "F.Paste")
			(net "DRV_ACT_7")
			(options
				(clearance outline)
				(anchor circle)
			)
			(primitives
				(gr_poly
					(pts
						(arc
							(start -0.1778 -0.2794)
							(mid -0.249642 -0.249642)
							(end -0.2794 -0.1778)
						)
						(arc
							(start -0.2794 0.1778)
							(mid -0.249642 0.249642)
							(end -0.1778 0.2794)
						)
						(arc
							(start 0.1778 0.2794)
							(mid 0.249642 0.249642)
							(end 0.2794 0.1778)
						)
						(arc
							(start 0.2794 -0.1778)
							(mid 0.249642 -0.249642)
							(end 0.1778 -0.2794)
						)
					)
					(width 0)
					(fill yes)
				)
			)
		)
	)
	(footprint ""
		(layer "F.Cu")
		(at 193.04 -191.77 90)
		(property "Reference" "R552"
			(at 0 0 90)
			(layer "F.SilkS")
			(hide yes)
			(effects
				(font
					(size 1.27 1.27)
				)
			)
		)
		(property "Value" "200KR2F-L-GP"
			(at 0.064008 -3.993896 90)
			(unlocked yes)
			(layer "F.Fab")
			(hide yes)
			(effects
				(font
					(size 1.016 1.016)
					(thickness 0.1524)
				)
			)
		)
		(property "Device Type" "R402H16"
			(at 0.064008 -5.517896 90)
			(unlocked yes)
			(layer "F.Fab")
			(hide yes)
			(effects
				(font
					(size 1.016 1.016)
					(thickness 0.1524)
				)
			)
		)
		(duplicate_pad_numbers_are_jumpers no)
		(fp_line
			(start 0.508 -0.9398)
			(end -0.508 -0.9398)
			(stroke
				(width 0.1524)
				(type default)
			)
			(layer "F.SilkS")
		)
		(fp_line
			(start -0.508 -0.9398)
			(end -0.508 0.9398)
			(stroke
				(width 0.1524)
				(type default)
			)
			(layer "F.SilkS")
		)
		(fp_rect
			(start -0.508 0.9398)
			(end 0.508 -0.9398)
			(stroke
				(width 0)
				(type default)
			)
			(fill no)
			(layer "F.CrtYd")
		)
		(fp_rect
			(start -0.508 0.9398)
			(end 0.508 -0.9398)
			(stroke
				(width 0)
				(type default)
			)
			(fill no)
			(layer "F.Fab")
		)
		(pad "1" smd custom
			(at 0 -0.4445 90)
			(size 0.1397 0.1397)
			(layers "F.Cu" "F.Mask" "F.Paste")
			(net "SW_HDD3_R")
			(options
				(clearance outline)
				(anchor circle)
			)
			(primitives
				(gr_poly
					(pts
						(arc
							(start -0.1778 -0.2794)
							(mid -0.249642 -0.249642)
							(end -0.2794 -0.1778)
						)
						(arc
							(start -0.2794 0.1778)
							(mid -0.249642 0.249642)
							(end -0.1778 0.2794)
						)
						(arc
							(start 0.1778 0.2794)
							(mid 0.249642 0.249642)
							(end 0.2794 0.1778)
						)
						(arc
							(start 0.2794 -0.1778)
							(mid 0.249642 -0.249642)
							(end 0.1778 -0.2794)
						)
					)
					(width 0)
					(fill yes)
				)
			)
		)
		(pad "2" smd custom
			(at 0 0.4445 90)
			(size 0.1397 0.1397)
			(layers "F.Cu" "F.Mask" "F.Paste")
			(net "SW_HDD3_N")
			(options
				(clearance outline)
				(anchor circle)
			)
			(primitives
				(gr_poly
					(pts
						(arc
							(start -0.1778 -0.2794)
							(mid -0.249642 -0.249642)
							(end -0.2794 -0.1778)
						)
						(arc
							(start -0.2794 0.1778)
							(mid -0.249642 0.249642)
							(end -0.1778 0.2794)
						)
						(arc
							(start 0.1778 0.2794)
							(mid 0.249642 0.249642)
							(end 0.2794 0.1778)
						)
						(arc
							(start 0.2794 -0.1778)
							(mid 0.249642 -0.249642)
							(end 0.1778 -0.2794)
						)
					)
					(width 0)
					(fill yes)
				)
			)
		)
	)
	(footprint ""
		(layer "F.Cu")
		(at 79.756 -197.866 -90)
		(property "Reference" "R557"
			(at 0 0 270)
			(layer "F.SilkS")
			(hide yes)
			(effects
				(font
					(size 1.27 1.27)
				)
			)
		)
		(property "Value" "200KR2F-L-GP"
			(at 0.064008 -3.993896 270)
			(unlocked yes)
			(layer "F.Fab")
			(hide yes)
			(effects
				(font
					(size 1.016 1.016)
					(thickness 0.1524)
				)
			)
		)
		(property "Device Type" "R402H16"
			(at 0.064008 -5.517896 270)
			(unlocked yes)
			(layer "F.Fab")
			(hide yes)
			(effects
				(font
					(size 1.016 1.016)
					(thickness 0.1524)
				)
			)
		)
		(duplicate_pad_numbers_are_jumpers no)
		(fp_line
			(start -0.508 -0.9398)
			(end -0.508 0.9398)
			(stroke
				(width 0.1524)
				(type default)
			)
			(layer "F.SilkS")
		)
		(fp_line
			(start 0.508 -0.9398)
			(end -0.508 -0.9398)
			(stroke
				(width 0.1524)
				(type default)
			)
			(layer "F.SilkS")
		)
		(fp_rect
			(start -0.508 0.9398)
			(end 0.508 -0.9398)
			(stroke
				(width 0)
				(type default)
			)
			(fill no)
			(layer "F.CrtYd")
		)
		(fp_rect
			(start -0.508 0.9398)
			(end 0.508 -0.9398)
			(stroke
				(width 0)
				(type default)
			)
			(fill no)
			(layer "F.Fab")
		)
		(pad "1" smd custom
			(at 0 -0.4445 270)
			(size 0.1397 0.1397)
			(layers "F.Cu" "F.Mask" "F.Paste")
			(net "SW_HDD8_R")
			(options
				(clearance outline)
				(anchor circle)
			)
			(primitives
				(gr_poly
					(pts
						(arc
							(start -0.1778 -0.2794)
							(mid -0.249642 -0.249642)
							(end -0.2794 -0.1778)
						)
						(arc
							(start -0.2794 0.1778)
							(mid -0.249642 0.249642)
							(end -0.1778 0.2794)
						)
						(arc
							(start 0.1778 0.2794)
							(mid 0.249642 0.249642)
							(end 0.2794 0.1778)
						)
						(arc
							(start 0.2794 -0.1778)
							(mid 0.249642 -0.249642)
							(end 0.1778 -0.2794)
						)
					)
					(width 0)
					(fill yes)
				)
			)
		)
		(pad "2" smd custom
			(at 0 0.4445 270)
			(size 0.1397 0.1397)
			(layers "F.Cu" "F.Mask" "F.Paste")
			(net "SW_HDD8_N")
			(options
				(clearance outline)
				(anchor circle)
			)
			(primitives
				(gr_poly
					(pts
						(arc
							(start -0.1778 -0.2794)
							(mid -0.249642 -0.249642)
							(end -0.2794 -0.1778)
						)
						(arc
							(start -0.2794 0.1778)
							(mid -0.249642 0.249642)
							(end -0.1778 0.2794)
						)
						(arc
							(start 0.1778 0.2794)
							(mid 0.249642 0.249642)
							(end 0.2794 0.1778)
						)
						(arc
							(start 0.2794 -0.1778)
							(mid 0.249642 -0.249642)
							(end 0.1778 -0.2794)
						)
					)
					(width 0)
					(fill yes)
				)
			)
		)
	)
	(footprint ""
		(layer "F.Cu")
		(at 25.9334 -416.941)
		(property "Reference" "C272"
			(at 0 0 0)
			(layer "F.SilkS")
			(hide yes)
			(effects
				(font
					(size 1.27 1.27)
				)
			)
		)
		(property "Value" "SC1U25V3KX-1-GP"
			(at 0 -2.8194 0)
			(unlocked yes)
			(layer "F.Fab")
			(hide yes)
			(effects
				(font
					(size 1.016 1.016)
					(thickness 0.1524)
				)
			)
		)
		(property "Device Type" "C603H36"
			(at 0 -4.3434 0)
			(unlocked yes)
			(layer "F.Fab")
			(hide yes)
			(effects
				(font
					(size 1.016 1.016)
					(thickness 0.1524)
				)
			)
		)
		(duplicate_pad_numbers_are_jumpers no)
		(fp_line
			(start 0.508 0)
			(end -0.508 0)
			(stroke
				(width 0.2032)
				(type default)
			)
			(layer "F.SilkS")
		)
		(fp_rect
			(start -0.5842 1.3335)
			(end 0.5842 -1.3335)
			(stroke
				(width 0)
				(type default)
			)
			(fill no)
			(layer "F.CrtYd")
		)
		(fp_rect
			(start -0.5842 1.3335)
			(end 0.5842 -1.3335)
			(stroke
				(width 0)
				(type default)
			)
			(fill no)
			(layer "F.Fab")
		)
		(pad "1" smd custom
			(at 0 -0.762)
			(size 0.2159 0.2159)
			(layers "F.Cu" "F.Mask" "F.Paste")
			(net "P12V_HDD10")
			(options
				(clearance outline)
				(anchor circle)
			)
			(primitives
				(gr_poly
					(pts
						(arc
							(start -0.3302 -0.4318)
							(mid -0.402042 -0.402042)
							(end -0.4318 -0.3302)
						)
						(arc
							(start -0.4318 0.3302)
							(mid -0.402042 0.402042)
							(end -0.3302 0.4318)
						)
						(arc
							(start 0.3302 0.4318)
							(mid 0.402042 0.402042)
							(end 0.4318 0.3302)
						)
						(arc
							(start 0.4318 -0.3302)
							(mid 0.402042 -0.402042)
							(end 0.3302 -0.4318)
						)
					)
					(width 0)
					(fill yes)
				)
			)
		)
		(pad "2" smd custom
			(at 0 0.762)
			(size 0.2159 0.2159)
			(layers "F.Cu" "F.Mask" "F.Paste")
			(net "GND")
			(options
				(clearance outline)
				(anchor circle)
			)
			(primitives
				(gr_poly
					(pts
						(arc
							(start -0.3302 -0.4318)
							(mid -0.402042 -0.402042)
							(end -0.4318 -0.3302)
						)
						(arc
							(start -0.4318 0.3302)
							(mid -0.402042 0.402042)
							(end -0.3302 0.4318)
						)
						(arc
							(start 0.3302 0.4318)
							(mid 0.402042 0.402042)
							(end 0.4318 0.3302)
						)
						(arc
							(start 0.4318 -0.3302)
							(mid 0.402042 -0.402042)
							(end 0.3302 -0.4318)
						)
					)
					(width 0)
					(fill yes)
				)
			)
		)
	)
	(footprint ""
		(layer "F.Cu")
		(at 9.4234 -154.260804 90)
		(property "Reference" "R549"
			(at 0 0 90)
			(layer "F.SilkS")
			(hide yes)
			(effects
				(font
					(size 1.27 1.27)
				)
			)
		)
		(property "Value" "0R2J-2-GP"
			(at 0.064008 -3.993896 90)
			(unlocked yes)
			(layer "F.Fab")
			(hide yes)
			(effects
				(font
					(size 1.016 1.016)
					(thickness 0.1524)
				)
			)
		)
		(property "Device Type" "R402H16"
			(at 0.064008 -5.517896 90)
			(unlocked yes)
			(layer "F.Fab")
			(hide yes)
			(effects
				(font
					(size 1.016 1.016)
					(thickness 0.1524)
				)
			)
		)
		(duplicate_pad_numbers_are_jumpers no)
		(fp_line
			(start 0.508 -0.9398)
			(end -0.508 -0.9398)
			(stroke
				(width 0.1524)
				(type default)
			)
			(layer "F.SilkS")
		)
		(fp_line
			(start -0.508 -0.9398)
			(end -0.508 0.9398)
			(stroke
				(width 0.1524)
				(type default)
			)
			(layer "F.SilkS")
		)
		(fp_rect
			(start -0.508 0.9398)
			(end 0.508 -0.9398)
			(stroke
				(width 0)
				(type default)
			)
			(fill no)
			(layer "F.CrtYd")
		)
		(fp_rect
			(start -0.508 0.9398)
			(end 0.508 -0.9398)
			(stroke
				(width 0)
				(type default)
			)
			(fill no)
			(layer "F.Fab")
		)
		(pad "1" smd custom
			(at 0 -0.4445 90)
			(size 0.1397 0.1397)
			(layers "F.Cu" "F.Mask" "F.Paste")
			(net "I2C_D_SDA_DAMP_B")
			(options
				(clearance outline)
				(anchor circle)
			)
			(primitives
				(gr_poly
					(pts
						(arc
							(start -0.1778 -0.2794)
							(mid -0.249642 -0.249642)
							(end -0.2794 -0.1778)
						)
						(arc
							(start -0.2794 0.1778)
							(mid -0.249642 0.249642)
							(end -0.1778 0.2794)
						)
						(arc
							(start 0.1778 0.2794)
							(mid 0.249642 0.249642)
							(end 0.2794 0.1778)
						)
						(arc
							(start 0.2794 -0.1778)
							(mid 0.249642 -0.249642)
							(end 0.1778 -0.2794)
						)
					)
					(width 0)
					(fill yes)
				)
			)
		)
		(pad "2" smd custom
			(at 0 0.4445 90)
			(size 0.1397 0.1397)
			(layers "F.Cu" "F.Mask" "F.Paste")
			(net "I2C_D_SDA")
			(options
				(clearance outline)
				(anchor circle)
			)
			(primitives
				(gr_poly
					(pts
						(arc
							(start -0.1778 -0.2794)
							(mid -0.249642 -0.249642)
							(end -0.2794 -0.1778)
						)
						(arc
							(start -0.2794 0.1778)
							(mid -0.249642 0.249642)
							(end -0.1778 0.2794)
						)
						(arc
							(start 0.1778 0.2794)
							(mid 0.249642 0.249642)
							(end 0.2794 0.1778)
						)
						(arc
							(start 0.2794 -0.1778)
							(mid 0.249642 -0.249642)
							(end 0.1778 -0.2794)
						)
					)
					(width 0)
					(fill yes)
				)
			)
		)
	)
	(footprint ""
		(layer "F.Cu")
		(at 25.991312 -339.585808 90)
		(property "Reference" "C280"
			(at 0 0 90)
			(layer "F.SilkS")
			(hide yes)
			(effects
				(font
					(size 1.27 1.27)
				)
			)
		)
		(property "Value" "SCD01U50V2KX-1GP"
			(at 1.1811 -2.7051 90)
			(unlocked yes)
			(layer "F.Fab")
			(hide yes)
			(effects
				(font
					(size 1.016 1.016)
					(thickness 0.1524)
				)
			)
		)
		(property "Device Type" "C402H22"
			(at 1.1811 -4.2291 90)
			(unlocked yes)
			(layer "F.Fab")
			(hide yes)
			(effects
				(font
					(size 1.016 1.016)
					(thickness 0.1524)
				)
			)
		)
		(duplicate_pad_numbers_are_jumpers no)
		(fp_rect
			(start -0.4318 0.9525)
			(end 0.4318 -0.9525)
			(stroke
				(width 0)
				(type default)
			)
			(fill no)
			(layer "F.CrtYd")
		)
		(fp_rect
			(start -0.4318 0.9525)
			(end 0.4318 -0.9525)
			(stroke
				(width 0)
				(type default)
			)
			(fill no)
			(layer "F.Fab")
		)
		(pad "1" smd custom
			(at 0 -0.4445 90)
			(size 0.1524 0.1524)
			(layers "F.Cu" "F.Mask" "F.Paste")
			(net "SAS2X28_DRIVE_RX_N_B11")
			(options
				(clearance outline)
				(anchor circle)
			)
			(primitives
				(gr_poly
					(pts
						(arc
							(start 0.3048 -0.2032)
							(mid 0.275042 -0.275042)
							(end 0.2032 -0.3048)
						)
						(arc
							(start -0.2032 -0.3048)
							(mid -0.275042 -0.275042)
							(end -0.3048 -0.2032)
						)
						(arc
							(start -0.3048 0.2032)
							(mid -0.275042 0.275042)
							(end -0.2032 0.3048)
						)
						(arc
							(start 0.2032 0.3048)
							(mid 0.275042 0.275042)
							(end 0.3048 0.2032)
						)
					)
					(width 0)
					(fill yes)
				)
			)
		)
		(pad "2" smd custom
			(at 0 0.4445 90)
			(size 0.1524 0.1524)
			(layers "F.Cu" "F.Mask" "F.Paste")
			(net "SAS2X28_B_HDD11_RX_-")
			(options
				(clearance outline)
				(anchor circle)
			)
			(primitives
				(gr_poly
					(pts
						(arc
							(start 0.3048 -0.2032)
							(mid 0.275042 -0.275042)
							(end 0.2032 -0.3048)
						)
						(arc
							(start -0.2032 -0.3048)
							(mid -0.275042 -0.275042)
							(end -0.3048 -0.2032)
						)
						(arc
							(start -0.3048 0.2032)
							(mid -0.275042 0.275042)
							(end -0.2032 0.3048)
						)
						(arc
							(start 0.2032 0.3048)
							(mid 0.275042 0.275042)
							(end 0.3048 0.2032)
						)
					)
					(width 0)
					(fill yes)
				)
			)
		)
	)
	(footprint ""
		(layer "F.Cu")
		(at 216.584784 -172.436028)
		(property "Reference" "R152"
			(at 0 0 0)
			(layer "F.SilkS")
			(hide yes)
			(effects
				(font
					(size 1.27 1.27)
				)
			)
		)
		(property "Value" "220R3F-1-GP"
			(at -0.0254 -2.5146 0)
			(unlocked yes)
			(layer "F.Fab")
			(hide yes)
			(effects
				(font
					(size 1.016 1.016)
					(thickness 0.1524)
				)
			)
		)
		(property "Device Type" "R603H22"
			(at -0.0254 -4.0386 0)
			(unlocked yes)
			(layer "F.Fab")
			(hide yes)
			(effects
				(font
					(size 1.016 1.016)
					(thickness 0.1524)
				)
			)
		)
		(duplicate_pad_numbers_are_jumpers no)
		(fp_line
			(start -0.4826 0)
			(end -0.2032 0)
			(stroke
				(width 0.2032)
				(type default)
			)
			(layer "F.SilkS")
		)
		(fp_line
			(start 0.2032 0)
			(end 0.4826 0)
			(stroke
				(width 0.2032)
				(type default)
			)
			(layer "F.SilkS")
		)
		(fp_rect
			(start -0.5842 1.3335)
			(end 0.5842 -1.3335)
			(stroke
				(width 0)
				(type default)
			)
			(fill no)
			(layer "F.CrtYd")
		)
		(fp_rect
			(start -0.5842 1.3335)
			(end 0.5842 -1.3335)
			(stroke
				(width 0)
				(type default)
			)
			(fill no)
			(layer "F.Fab")
		)
		(pad "1" smd custom
			(at 0 -0.762)
			(size 0.2159 0.2159)
			(layers "F.Cu" "F.Mask" "F.Paste")
			(net "HDD_PRSNT_NET3")
			(options
				(clearance outline)
				(anchor circle)
			)
			(primitives
				(gr_poly
					(pts
						(arc
							(start -0.3302 -0.4318)
							(mid -0.402042 -0.402042)
							(end -0.4318 -0.3302)
						)
						(arc
							(start -0.4318 0.3302)
							(mid -0.402042 0.402042)
							(end -0.3302 0.4318)
						)
						(arc
							(start 0.3302 0.4318)
							(mid 0.402042 0.402042)
							(end 0.4318 0.3302)
						)
						(arc
							(start 0.4318 -0.3302)
							(mid 0.402042 -0.402042)
							(end 0.3302 -0.4318)
						)
					)
					(width 0)
					(fill yes)
				)
			)
		)
		(pad "2" smd custom
			(at 0 0.762)
			(size 0.2159 0.2159)
			(layers "F.Cu" "F.Mask" "F.Paste")
			(net "HDD_PRSNT3")
			(options
				(clearance outline)
				(anchor circle)
			)
			(primitives
				(gr_poly
					(pts
						(arc
							(start -0.3302 -0.4318)
							(mid -0.402042 -0.402042)
							(end -0.4318 -0.3302)
						)
						(arc
							(start -0.4318 0.3302)
							(mid -0.402042 0.402042)
							(end -0.3302 0.4318)
						)
						(arc
							(start 0.3302 0.4318)
							(mid 0.402042 0.402042)
							(end 0.4318 0.3302)
						)
						(arc
							(start 0.4318 -0.3302)
							(mid 0.402042 -0.402042)
							(end 0.3302 -0.4318)
						)
					)
					(width 0)
					(fill yes)
				)
			)
		)
	)
	(footprint ""
		(layer "F.Cu")
		(at 34.416746 -436.3847 180)
		(property "Reference" "U33"
			(at 0 0 180)
			(layer "F.SilkS")
			(hide yes)
			(effects
				(font
					(size 1.27 1.27)
				)
			)
		)
		(property "Value" "74LVC1G08GW-1-GP"
			(at -2.3368 -8.6868 180)
			(unlocked yes)
			(layer "F.Fab")
			(hide yes)
			(effects
				(font
					(size 1.016 1.016)
					(thickness 0.1524)
				)
			)
		)
		(property "Device Type" "SC70-5H44"
			(at -2.3114 -10.414 180)
			(unlocked yes)
			(layer "F.Fab")
			(hide yes)
			(effects
				(font
					(size 1.016 1.016)
					(thickness 0.1524)
				)
			)
		)
		(duplicate_pad_numbers_are_jumpers no)
		(fp_line
			(start 1.3843 -1.8034)
			(end 1.3843 -1.1176)
			(stroke
				(width 0.3302)
				(type default)
			)
			(layer "F.SilkS")
		)
		(fp_line
			(start 1.27 1.7018)
			(end -1.27 1.7018)
			(stroke
				(width 0.1524)
				(type default)
			)
			(layer "F.SilkS")
		)
		(fp_line
			(start 1.27 -1.7018)
			(end 1.27 1.7018)
			(stroke
				(width 0.1524)
				(type default)
			)
			(layer "F.SilkS")
		)
		(fp_line
			(start 0.6604 -1.8034)
			(end 1.3843 -1.8034)
			(stroke
				(width 0.3302)
				(type default)
			)
			(layer "F.SilkS")
		)
		(fp_line
			(start -1.27 1.7018)
			(end -1.27 -1.7018)
			(stroke
				(width 0.1524)
				(type default)
			)
			(layer "F.SilkS")
		)
		(fp_line
			(start -1.27 -1.7018)
			(end 1.27 -1.7018)
			(stroke
				(width 0.1524)
				(type default)
			)
			(layer "F.SilkS")
		)
		(fp_rect
			(start -1.524 1.9558)
			(end 1.524 -1.9558)
			(stroke
				(width 0)
				(type default)
			)
			(fill no)
			(layer "F.CrtYd")
		)
		(fp_poly
			(pts
				(xy -1.524 -1.9558) (xy 1.524 -1.9558) (xy 1.524 1.9558) (xy -1.524 1.9558)
			)
			(stroke
				(width 0)
				(type default)
			)
			(fill no)
			(layer "F.Fab")
		)
		(pad "1" smd rect
			(at 0.65024 -0.8255 180)
			(size 0.4064 1.2192)
			(layers "F.Cu" "F.Mask" "F.Paste")
			(net "SAS_EXP_B_PWR10")
		)
		(pad "2" smd rect
			(at 0 -0.8255 180)
			(size 0.4064 1.2192)
			(layers "F.Cu" "F.Mask" "F.Paste")
			(net "SAS_EXP_A_PWR10")
		)
		(pad "3" smd rect
			(at -0.65024 -0.8255 180)
			(size 0.4064 1.2192)
			(layers "F.Cu" "F.Mask" "F.Paste")
			(net "GND")
		)
		(pad "4" smd rect
			(at -0.65024 0.8255 180)
			(size 0.4064 1.2192)
			(layers "F.Cu" "F.Mask" "F.Paste")
			(net "DRIVE_PWR10")
		)
		(pad "5" smd rect
			(at 0.65024 0.8255 180)
			(size 0.4064 1.2192)
			(layers "F.Cu" "F.Mask" "F.Paste")
			(net "P3V3")
		)
	)
	(footprint ""
		(layer "F.Cu")
		(at 73.659746 -91.0717 90)
		(property "Reference" "U29"
			(at 0 0 90)
			(layer "F.SilkS")
			(hide yes)
			(effects
				(font
					(size 1.27 1.27)
				)
			)
		)
		(property "Value" "P2003EVG-GP"
			(at 0 -11.1252 90)
			(unlocked yes)
			(layer "F.Fab")
			(hide yes)
			(effects
				(font
					(size 1.016 1.016)
					(thickness 0.1524)
				)
			)
		)
		(property "Device Type" "SOIC8H79"
			(at 0 -12.6492 90)
			(unlocked yes)
			(layer "F.Fab")
			(hide yes)
			(effects
				(font
					(size 1.016 1.016)
					(thickness 0.1524)
				)
			)
		)
		(duplicate_pad_numbers_are_jumpers no)
		(fp_line
			(start 2.1336 -1.4224)
			(end -2.7432 -1.4224)
			(stroke
				(width 0.1524)
				(type default)
			)
			(layer "F.SilkS")
		)
		(fp_line
			(start -2.7432 -1.4224)
			(end -2.7432 1.4224)
			(stroke
				(width 0.1524)
				(type default)
			)
			(layer "F.SilkS")
		)
		(fp_line
			(start -2.7432 -0.508)
			(end -2.2352 0)
			(stroke
				(width 0.1524)
				(type default)
			)
			(layer "F.SilkS")
		)
		(fp_line
			(start -2.2352 0)
			(end -2.7432 0.508)
			(stroke
				(width 0.1524)
				(type default)
			)
			(layer "F.SilkS")
		)
		(fp_line
			(start 2.1336 1.4224)
			(end 2.1336 -1.4224)
			(stroke
				(width 0.1524)
				(type default)
			)
			(layer "F.SilkS")
		)
		(fp_line
			(start -2.7432 1.4224)
			(end 2.1336 1.4224)
			(stroke
				(width 0.1524)
				(type default)
			)
			(layer "F.SilkS")
		)
		(fp_line
			(start -2.6162 3.429)
			(end -2.6162 1.4732)
			(stroke
				(width 0.4064)
				(type default)
			)
			(layer "F.SilkS")
		)
		(fp_poly
			(pts
				(xy 2.2098 -1.4224) (xy 2.2098 1.4224) (xy -2.2225 1.4224) (xy -2.2225 -1.4224)
			)
			(stroke
				(width 0)
				(type default)
			)
			(fill yes)
			(layer "F.SilkS")
		)
		(fp_rect
			(start -2.4511 2.9972)
			(end 2.4511 -2.9972)
			(stroke
				(width 0)
				(type default)
			)
			(fill no)
			(layer "F.CrtYd")
		)
		(fp_poly
			(pts
				(xy -2.8194 3.6322) (xy -2.8194 -3.6322) (xy 2.8194 -3.6322) (xy 2.8194 -2.2987) (xy 2.4511 -2.2987)
				(xy 2.4511 -2.9972) (xy -2.4511 -2.9972) (xy -2.4511 2.9972) (xy 2.4511 2.9972) (xy 2.4511 -2.286)
				(xy 2.8194 -2.286) (xy 2.8194 3.6322)
			)
			(stroke
				(width 0)
				(type default)
			)
			(fill no)
			(layer "F.CrtYd")
		)
		(fp_rect
			(start -2.8194 3.6322)
			(end 2.8194 -3.6322)
			(stroke
				(width 0)
				(type default)
			)
			(fill no)
			(layer "F.Fab")
		)
		(pad "1" smd rect
			(at -1.905 2.54 90)
			(size 0.635 1.651)
			(layers "F.Cu" "F.Mask" "F.Paste")
			(net "P12V")
		)
		(pad "2" smd rect
			(at -0.635 2.54 90)
			(size 0.635 1.651)
			(layers "F.Cu" "F.Mask" "F.Paste")
			(net "P12V")
		)
		(pad "3" smd rect
			(at 0.635 2.54 90)
			(size 0.635 1.651)
			(layers "F.Cu" "F.Mask" "F.Paste")
			(net "P12V")
		)
		(pad "4" smd rect
			(at 1.905 2.54 90)
			(size 0.635 1.651)
			(layers "F.Cu" "F.Mask" "F.Paste")
			(net "SW_HDD9_N")
		)
		(pad "5" smd rect
			(at 1.905 -2.54 90)
			(size 0.635 1.651)
			(layers "F.Cu" "F.Mask" "F.Paste")
			(net "P12V_HDD9")
		)
		(pad "6" smd rect
			(at 0.635 -2.54 90)
			(size 0.635 1.651)
			(layers "F.Cu" "F.Mask" "F.Paste")
			(net "P12V_HDD9")
		)
		(pad "7" smd rect
			(at -0.635 -2.54 90)
			(size 0.635 1.651)
			(layers "F.Cu" "F.Mask" "F.Paste")
			(net "P12V_HDD9")
		)
		(pad "8" smd rect
			(at -1.905 -2.54 90)
			(size 0.635 1.651)
			(layers "F.Cu" "F.Mask" "F.Paste")
			(net "P12V_HDD9")
		)
	)
	(footprint ""
		(layer "F.Cu")
		(at 12.572746 -483.5017)
		(property "Reference" "PR51"
			(at 0 0 0)
			(layer "F.SilkS")
			(hide yes)
			(effects
				(font
					(size 1.27 1.27)
				)
			)
		)
		(property "Value" "10KR2F-2-GP"
			(at 0.064008 -3.993896 0)
			(unlocked yes)
			(layer "F.Fab")
			(hide yes)
			(effects
				(font
					(size 1.016 1.016)
					(thickness 0.1524)
				)
			)
		)
		(property "Device Type" "R402H16"
			(at 0.064008 -5.517896 0)
			(unlocked yes)
			(layer "F.Fab")
			(hide yes)
			(effects
				(font
					(size 1.016 1.016)
					(thickness 0.1524)
				)
			)
		)
		(duplicate_pad_numbers_are_jumpers no)
		(fp_line
			(start -0.508 -0.9398)
			(end -0.508 0.9398)
			(stroke
				(width 0.1524)
				(type default)
			)
			(layer "F.SilkS")
		)
		(fp_line
			(start 0.508 -0.9398)
			(end -0.508 -0.9398)
			(stroke
				(width 0.1524)
				(type default)
			)
			(layer "F.SilkS")
		)
		(fp_rect
			(start -0.508 0.9398)
			(end 0.508 -0.9398)
			(stroke
				(width 0)
				(type default)
			)
			(fill no)
			(layer "F.CrtYd")
		)
		(fp_rect
			(start -0.508 0.9398)
			(end 0.508 -0.9398)
			(stroke
				(width 0)
				(type default)
			)
			(fill no)
			(layer "F.Fab")
		)
		(pad "1" smd custom
			(at 0 -0.4445)
			(size 0.1397 0.1397)
			(layers "F.Cu" "F.Mask" "F.Paste")
			(net "P5VC_LL")
			(options
				(clearance outline)
				(anchor circle)
			)
			(primitives
				(gr_poly
					(pts
						(arc
							(start -0.1778 -0.2794)
							(mid -0.249642 -0.249642)
							(end -0.2794 -0.1778)
						)
						(arc
							(start -0.2794 0.1778)
							(mid -0.249642 0.249642)
							(end -0.1778 0.2794)
						)
						(arc
							(start 0.1778 0.2794)
							(mid 0.249642 0.249642)
							(end 0.2794 0.1778)
						)
						(arc
							(start 0.2794 -0.1778)
							(mid 0.249642 -0.249642)
							(end 0.1778 -0.2794)
						)
					)
					(width 0)
					(fill yes)
				)
			)
		)
		(pad "2" smd custom
			(at 0 0.4445)
			(size 0.1397 0.1397)
			(layers "F.Cu" "F.Mask" "F.Paste")
			(net "P5VC_LL_NET")
			(options
				(clearance outline)
				(anchor circle)
			)
			(primitives
				(gr_poly
					(pts
						(arc
							(start -0.1778 -0.2794)
							(mid -0.249642 -0.249642)
							(end -0.2794 -0.1778)
						)
						(arc
							(start -0.2794 0.1778)
							(mid -0.249642 0.249642)
							(end -0.1778 0.2794)
						)
						(arc
							(start 0.1778 0.2794)
							(mid 0.249642 0.249642)
							(end 0.2794 0.1778)
						)
						(arc
							(start 0.2794 -0.1778)
							(mid 0.249642 -0.249642)
							(end 0.1778 -0.2794)
						)
					)
					(width 0)
					(fill yes)
				)
			)
		)
	)
	(footprint ""
		(layer "F.Cu")
		(at 33.782 -305.308 90)
		(property "Reference" "R262"
			(at 0 0 90)
			(layer "F.SilkS")
			(hide yes)
			(effects
				(font
					(size 1.27 1.27)
				)
			)
		)
		(property "Value" "4K7R2J-2-GP"
			(at 0.064008 -3.993896 90)
			(unlocked yes)
			(layer "F.Fab")
			(hide yes)
			(effects
				(font
					(size 1.016 1.016)
					(thickness 0.1524)
				)
			)
		)
		(property "Device Type" "R402H16"
			(at 0.064008 -5.517896 90)
			(unlocked yes)
			(layer "F.Fab")
			(hide yes)
			(effects
				(font
					(size 1.016 1.016)
					(thickness 0.1524)
				)
			)
		)
		(duplicate_pad_numbers_are_jumpers no)
		(fp_line
			(start 0.508 -0.9398)
			(end -0.508 -0.9398)
			(stroke
				(width 0.1524)
				(type default)
			)
			(layer "F.SilkS")
		)
		(fp_line
			(start -0.508 -0.9398)
			(end -0.508 0.9398)
			(stroke
				(width 0.1524)
				(type default)
			)
			(layer "F.SilkS")
		)
		(fp_rect
			(start -0.508 0.9398)
			(end 0.508 -0.9398)
			(stroke
				(width 0)
				(type default)
			)
			(fill no)
			(layer "F.CrtYd")
		)
		(fp_rect
			(start -0.508 0.9398)
			(end 0.508 -0.9398)
			(stroke
				(width 0)
				(type default)
			)
			(fill no)
			(layer "F.Fab")
		)
		(pad "1" smd custom
			(at 0 -0.4445 90)
			(size 0.1397 0.1397)
			(layers "F.Cu" "F.Mask" "F.Paste")
			(net "P12V")
			(options
				(clearance outline)
				(anchor circle)
			)
			(primitives
				(gr_poly
					(pts
						(arc
							(start -0.1778 -0.2794)
							(mid -0.249642 -0.249642)
							(end -0.2794 -0.1778)
						)
						(arc
							(start -0.2794 0.1778)
							(mid -0.249642 0.249642)
							(end -0.1778 0.2794)
						)
						(arc
							(start 0.1778 0.2794)
							(mid 0.249642 0.249642)
							(end 0.2794 0.1778)
						)
						(arc
							(start 0.2794 -0.1778)
							(mid 0.249642 -0.249642)
							(end 0.1778 -0.2794)
						)
					)
					(width 0)
					(fill yes)
				)
			)
		)
		(pad "2" smd custom
			(at 0 0.4445 90)
			(size 0.1397 0.1397)
			(layers "F.Cu" "F.Mask" "F.Paste")
			(net "SW_HDD11_R")
			(options
				(clearance outline)
				(anchor circle)
			)
			(primitives
				(gr_poly
					(pts
						(arc
							(start -0.1778 -0.2794)
							(mid -0.249642 -0.249642)
							(end -0.2794 -0.1778)
						)
						(arc
							(start -0.2794 0.1778)
							(mid -0.249642 0.249642)
							(end -0.1778 0.2794)
						)
						(arc
							(start 0.1778 0.2794)
							(mid 0.249642 0.249642)
							(end 0.2794 0.1778)
						)
						(arc
							(start 0.2794 -0.1778)
							(mid 0.249642 -0.249642)
							(end 0.1778 -0.2794)
						)
					)
					(width 0)
					(fill yes)
				)
			)
		)
	)
	(footprint ""
		(layer "F.Cu")
		(at 17.500092 -26.329894 -90)
		(property "Reference" "SKT15"
			(at 0 0 270)
			(layer "F.SilkS")
			(hide yes)
			(effects
				(font
					(size 1.27 1.27)
				)
			)
		)
		(property "Value" "SKT-SATA14P-15P-12-GP"
			(at -22.6187 8.1788 270)
			(unlocked yes)
			(layer "F.Fab")
			(hide yes)
			(effects
				(font
					(size 1.016 1.016)
					(thickness 0.1524)
				)
			)
		)
		(property "Device Type" "87945-1001"
			(at -22.6187 6.6548 270)
			(unlocked yes)
			(layer "F.Fab")
			(hide yes)
			(effects
				(font
					(size 1.016 1.016)
					(thickness 0.1524)
				)
			)
		)
		(duplicate_pad_numbers_are_jumpers no)
		(fp_line
			(start -20.4724 9.652)
			(end -20.4724 2.3114)
			(stroke
				(width 0.1524)
				(type default)
			)
			(layer "F.SilkS")
		)
		(fp_line
			(start -17.8435 9.652)
			(end -20.4724 9.652)
			(stroke
				(width 0.1524)
				(type default)
			)
			(layer "F.SilkS")
		)
		(fp_line
			(start 17.8435 9.652)
			(end 17.8435 7.9502)
			(stroke
				(width 0.1524)
				(type default)
			)
			(layer "F.SilkS")
		)
		(fp_line
			(start 20.4724 9.652)
			(end 17.8435 9.652)
			(stroke
				(width 0.1524)
				(type default)
			)
			(layer "F.SilkS")
		)
		(fp_line
			(start -17.8435 7.9502)
			(end -17.8435 9.652)
			(stroke
				(width 0.1524)
				(type default)
			)
			(layer "F.SilkS")
		)
		(fp_line
			(start 17.8435 7.9502)
			(end -17.8435 7.9502)
			(stroke
				(width 0.1524)
				(type default)
			)
			(layer "F.SilkS")
		)
		(fp_line
			(start -23.7617 2.3114)
			(end -23.7617 -2.3114)
			(stroke
				(width 0.1524)
				(type default)
			)
			(layer "F.SilkS")
		)
		(fp_line
			(start -20.4724 2.3114)
			(end -23.7617 2.3114)
			(stroke
				(width 0.1524)
				(type default)
			)
			(layer "F.SilkS")
		)
		(fp_line
			(start 20.4724 2.3114)
			(end 20.4724 9.652)
			(stroke
				(width 0.1524)
				(type default)
			)
			(layer "F.SilkS")
		)
		(fp_line
			(start 23.7617 2.3114)
			(end 20.4724 2.3114)
			(stroke
				(width 0.1524)
				(type default)
			)
			(layer "F.SilkS")
		)
		(fp_line
			(start -23.117556 0.5461)
			(end -23.117556 -0.5461)
			(stroke
				(width 0.3048)
				(type default)
			)
			(layer "F.SilkS")
		)
		(fp_line
			(start 20.882356 0.5461)
			(end 20.882356 -0.5461)
			(stroke
				(width 0.3048)
				(type default)
			)
			(layer "F.SilkS")
		)
		(fp_line
			(start -20.882356 -0.5461)
			(end -20.882356 0.5461)
			(stroke
				(width 0.3048)
				(type default)
			)
			(layer "F.SilkS")
		)
		(fp_line
			(start 23.117556 -0.5461)
			(end 23.117556 0.5461)
			(stroke
				(width 0.3048)
				(type default)
			)
			(layer "F.SilkS")
		)
		(fp_line
			(start -23.7617 -2.3114)
			(end -20.4724 -2.3114)
			(stroke
				(width 0.1524)
				(type default)
			)
			(layer "F.SilkS")
		)
		(fp_line
			(start -20.4724 -2.3114)
			(end -20.4724 -5.7658)
			(stroke
				(width 0.1524)
				(type default)
			)
			(layer "F.SilkS")
		)
		(fp_line
			(start 20.4724 -2.3114)
			(end 23.7617 -2.3114)
			(stroke
				(width 0.1524)
				(type default)
			)
			(layer "F.SilkS")
		)
		(fp_line
			(start 23.7617 -2.3114)
			(end 23.7617 2.3114)
			(stroke
				(width 0.1524)
				(type default)
			)
			(layer "F.SilkS")
		)
		(fp_line
			(start -20.4724 -5.7658)
			(end 20.4724 -5.7658)
			(stroke
				(width 0.1524)
				(type default)
			)
			(layer "F.SilkS")
		)
		(fp_line
			(start 20.4724 -5.7658)
			(end 20.4724 -2.3114)
			(stroke
				(width 0.1524)
				(type default)
			)
			(layer "F.SilkS")
		)
		(fp_line
			(start -15.3924 -5.8547)
			(end -16.3576 -5.8547)
			(stroke
				(width 0.3302)
				(type default)
			)
			(layer "F.SilkS")
		)
		(fp_arc
			(start -20.882356 0.5461)
			(mid -21.999956 1.6637)
			(end -23.117556 0.5461)
			(stroke
				(width 0.3048)
				(type default)
			)
			(layer "F.SilkS")
		)
		(fp_arc
			(start 23.117556 0.5461)
			(mid 21.999956 1.6637)
			(end 20.882356 0.5461)
			(stroke
				(width 0.3048)
				(type default)
			)
			(layer "F.SilkS")
		)
		(fp_arc
			(start -23.117556 -0.5461)
			(mid -21.999956 -1.6637)
			(end -20.882356 -0.5461)
			(stroke
				(width 0.3048)
				(type default)
			)
			(layer "F.SilkS")
		)
		(fp_arc
			(start 20.882356 -0.5461)
			(mid 21.999956 -1.6637)
			(end 23.117556 -0.5461)
			(stroke
				(width 0.3048)
				(type default)
			)
			(layer "F.SilkS")
		)
		(fp_poly
			(pts
				(xy -15.87119 -5.838698) (xy -15.23619 -6.473698) (xy -16.50619 -6.473698)
			)
			(stroke
				(width 0)
				(type default)
			)
			(fill yes)
			(layer "F.SilkS")
		)
		(fp_poly
			(pts
				(xy -20.2184 -5.5118) (xy 20.2184 -5.5118) (xy 20.2184 -2.0574) (xy 23.5077 -2.0574) (xy 23.5077 2.0574)
				(xy 20.2184 2.0574) (xy 20.2184 9.398) (xy 18.0975 9.398) (xy 18.0975 7.6962) (xy -18.0975 7.6962)
				(xy -18.0975 9.398) (xy -20.2184 9.398) (xy -20.2184 2.0574) (xy -23.5077 2.0574) (xy -23.5077 -2.0574)
				(xy -20.2184 -2.0574)
			)
			(stroke
				(width 0)
				(type default)
			)
			(fill no)
			(layer "F.CrtYd")
		)
		(fp_poly
			(pts
				(xy -20.2184 -5.5118) (xy -20.2184 -6.0198) (xy -20.7264 -6.0198) (xy -20.7264 -2.5654) (xy -24.0157 -2.5654)
				(xy -24.0157 2.5654) (xy -20.7264 2.5654) (xy -20.7264 9.906) (xy -17.5895 9.906) (xy -17.5895 8.2042)
				(xy 17.5895 8.2042) (xy 17.5895 9.906) (xy 20.7264 9.906) (xy 20.7264 2.5654) (xy 24.0157 2.5654)
				(xy 24.0157 -2.5654) (xy 20.7264 -2.5654) (xy 20.7264 -6.0198) (xy -20.21586 -6.0198) (xy -20.21586 -5.5118)
				(xy 20.2184 -5.5118) (xy 20.2184 -2.0574) (xy 23.5077 -2.0574) (xy 23.5077 2.0574) (xy 20.2184 2.0574)
				(xy 20.2184 9.398) (xy 18.0975 9.398) (xy 18.0975 7.6962) (xy -18.0975 7.6962) (xy -18.0975 9.398)
				(xy -20.2184 9.398) (xy -20.2184 2.0574) (xy -23.5077 2.0574) (xy -23.5077 -2.0574) (xy -20.2184 -2.0574)
			)
			(stroke
				(width 0)
				(type default)
			)
			(fill no)
			(layer "F.CrtYd")
		)
		(fp_poly
			(pts
				(xy -20.7264 -6.0198) (xy -20.7264 -2.5654) (xy -24.0157 -2.5654) (xy -24.0157 2.5654) (xy -20.7264 2.5654)
				(xy -20.7264 9.906) (xy -17.5895 9.906) (xy -17.5895 8.2042) (xy 17.5895 8.2042) (xy 17.5895 9.906)
				(xy 20.7264 9.906) (xy 20.7264 2.5654) (xy 24.0157 2.5654) (xy 24.0157 -2.5654) (xy 20.7264 -2.5654)
				(xy 20.7264 -6.0198)
			)
			(stroke
				(width 0)
				(type default)
			)
			(fill no)
			(layer "F.Fab")
		)
		(pad "" np_thru_hole circle
			(at -18.999962 -2.350008 270)
			(size 0.254 0.254)
			(drill 1.8542)
			(layers "*.Cu" "*.Mask")
			(clearance 1.1557)
			(thermal_gap 1.1557)
		)
		(pad "" np_thru_hole circle
			(at 18.999962 -2.350008 270)
			(size 0.254 0.254)
			(drill 1.8542)
			(layers "*.Cu" "*.Mask")
			(clearance 1.1557)
			(thermal_gap 1.1557)
		)
		(pad "H1" thru_hole oval
			(at -21.999956 0 270)
			(size 1.524 2.6162)
			(drill oval 0.8128 1.905)
			(layers "*.Cu" "*.Mask")
			(remove_unused_layers no)
			(net "GND")
			(clearance 0.1524)
			(thermal_gap 0.1524)
		)
		(pad "H2" thru_hole oval
			(at 21.999956 0 270)
			(size 1.524 2.6162)
			(drill oval 0.8128 1.905)
			(layers "*.Cu" "*.Mask")
			(remove_unused_layers no)
			(net "GND")
			(clearance 0.1524)
			(thermal_gap 0.1524)
		)
		(pad "P1" smd rect
			(at -1.89992 -4.249928 270)
			(size 0.6604 2.3876)
			(layers "F.Cu" "F.Mask" "F.Paste")
			(net "Net_45")
		)
		(pad "P2" smd rect
			(at -0.62992 -4.249928 270)
			(size 0.6604 2.3876)
			(layers "F.Cu" "F.Mask" "F.Paste")
			(net "Net_44")
		)
		(pad "P3" smd rect
			(at 0.64008 -4.249928 270)
			(size 0.6604 2.3876)
			(layers "F.Cu" "F.Mask" "F.Paste")
			(net "Net_43")
		)
		(pad "P4" smd rect
			(at 1.91008 -4.249928 270)
			(size 0.6604 2.3876)
			(layers "F.Cu" "F.Mask" "F.Paste")
			(net "GND")
		)
		(pad "P5" smd rect
			(at 3.18008 -4.249928 270)
			(size 0.6604 2.3876)
			(layers "F.Cu" "F.Mask" "F.Paste")
			(net "HDD_PRSNT_NET14")
		)
		(pad "P6" smd rect
			(at 4.45008 -4.249928 270)
			(size 0.6604 2.3876)
			(layers "F.Cu" "F.Mask" "F.Paste")
			(net "GND")
		)
		(pad "P7" smd rect
			(at 5.72008 -4.249928 270)
			(size 0.6604 2.3876)
			(layers "F.Cu" "F.Mask" "F.Paste")
			(net "5V_PRE_14")
		)
		(pad "P8" smd rect
			(at 6.99008 -4.249928 270)
			(size 0.6604 2.3876)
			(layers "F.Cu" "F.Mask" "F.Paste")
			(net "P5V_HDD14")
		)
		(pad "P9" smd rect
			(at 8.26008 -4.249928 270)
			(size 0.6604 2.3876)
			(layers "F.Cu" "F.Mask" "F.Paste")
			(net "P5V_HDD14")
		)
		(pad "P10" smd rect
			(at 9.53008 -4.249928 270)
			(size 0.6604 2.3876)
			(layers "F.Cu" "F.Mask" "F.Paste")
			(net "GND")
		)
		(pad "P11" smd rect
			(at 10.80008 -4.249928 270)
			(size 0.6604 2.3876)
			(layers "F.Cu" "F.Mask" "F.Paste")
			(net "ACT_HDD14")
		)
		(pad "P12" smd rect
			(at 12.07008 -4.249928 270)
			(size 0.6604 2.3876)
			(layers "F.Cu" "F.Mask" "F.Paste")
			(net "GND")
		)
		(pad "P13" smd rect
			(at 13.34008 -4.249928 270)
			(size 0.6604 2.3876)
			(layers "F.Cu" "F.Mask" "F.Paste")
			(net "12V_PRE_14")
		)
		(pad "P14" smd rect
			(at 14.61008 -4.249928 270)
			(size 0.6604 2.3876)
			(layers "F.Cu" "F.Mask" "F.Paste")
			(net "P12V_HDD14")
		)
		(pad "P15" smd rect
			(at 15.88008 -4.249928 270)
			(size 0.6604 2.3876)
			(layers "F.Cu" "F.Mask" "F.Paste")
			(net "P12V_HDD14")
		)
		(pad "S1" smd rect
			(at -15.86992 -4.249928 270)
			(size 0.6604 2.3876)
			(layers "F.Cu" "F.Mask" "F.Paste")
			(net "GND")
		)
		(pad "S2" smd rect
			(at -14.59992 -4.249928 270)
			(size 0.6604 2.3876)
			(layers "F.Cu" "F.Mask" "F.Paste")
			(net "SAS2X28_A_HDD14_TX_+")
		)
		(pad "S3" smd rect
			(at -13.32992 -4.249928 270)
			(size 0.6604 2.3876)
			(layers "F.Cu" "F.Mask" "F.Paste")
			(net "SAS2X28_A_HDD14_TX_-")
		)
		(pad "S4" smd rect
			(at -12.05992 -4.249928 270)
			(size 0.6604 2.3876)
			(layers "F.Cu" "F.Mask" "F.Paste")
			(net "GND")
		)
		(pad "S5" smd rect
			(at -10.78992 -4.249928 270)
			(size 0.6604 2.3876)
			(layers "F.Cu" "F.Mask" "F.Paste")
			(net "SAS2X28_DRIVE_RX_N_A14")
		)
		(pad "S6" smd rect
			(at -9.51992 -4.249928 270)
			(size 0.6604 2.3876)
			(layers "F.Cu" "F.Mask" "F.Paste")
			(net "SAS2X28_DRIVE_RX_P_A14")
		)
		(pad "S7" smd rect
			(at -8.24992 -4.249928 270)
			(size 0.6604 2.3876)
			(layers "F.Cu" "F.Mask" "F.Paste")
			(net "GND")
		)
		(pad "S8" smd rect
			(at -7.480046 -2.100072 270)
			(size 0.508 1.905)
			(layers "F.Cu" "F.Mask" "F.Paste")
			(net "GND")
		)
		(pad "S9" smd rect
			(at -6.679946 -2.100072 270)
			(size 0.508 1.905)
			(layers "F.Cu" "F.Mask" "F.Paste")
			(net "SAS2X28_B_HDD14_TX_+")
		)
		(pad "S10" smd rect
			(at -5.8801 -2.100072 270)
			(size 0.508 1.905)
			(layers "F.Cu" "F.Mask" "F.Paste")
			(net "SAS2X28_B_HDD14_TX_-")
		)
		(pad "S11" smd rect
			(at -5.08 -2.100072 270)
			(size 0.508 1.905)
			(layers "F.Cu" "F.Mask" "F.Paste")
			(net "GND")
		)
		(pad "S12" smd rect
			(at -4.2799 -2.100072 270)
			(size 0.508 1.905)
			(layers "F.Cu" "F.Mask" "F.Paste")
			(net "SAS2X28_DRIVE_RX_N_B14")
		)
		(pad "S13" smd rect
			(at -3.480054 -2.100072 270)
			(size 0.508 1.905)
			(layers "F.Cu" "F.Mask" "F.Paste")
			(net "SAS2X28_DRIVE_RX_P_B14")
		)
		(pad "S14" smd rect
			(at -2.679954 -2.100072 270)
			(size 0.508 1.905)
			(layers "F.Cu" "F.Mask" "F.Paste")
			(net "GND")
		)
		(zone
			(layers "F.Cu" "B.Cu" "In1.Cu" "In2.Cu" "In3.Cu" "In4.Cu" "In5.Cu" "In6.Cu")
			(hatch none 0.5)
			(connect_pads
				(clearance 0)
			)
			(min_thickness 0.25)
			(keepout
				(tracks not_allowed)
				(vias allowed)
				(pads allowed)
				(copperpour not_allowed)
				(footprints allowed)
			)
			(placement
				(enabled no)
				(sheetname "")
			)
			(fill
				(thermal_gap 0.5)
				(thermal_bridge_width 0.5)
				(island_removal_mode 0)
			)
			(polygon
				(pts
					(arc
						(start 21.082 -45.329856)
						(mid 18.6182 -45.329856)
						(end 21.082 -45.329856)
					)
				)
			)
		)
		(zone
			(layers "F.Cu" "B.Cu" "In1.Cu" "In2.Cu" "In3.Cu" "In4.Cu" "In5.Cu" "In6.Cu")
			(hatch none 0.5)
			(connect_pads
				(clearance 0)
			)
			(min_thickness 0.25)
			(keepout
				(tracks not_allowed)
				(vias allowed)
				(pads allowed)
				(copperpour not_allowed)
				(footprints allowed)
			)
			(placement
				(enabled no)
				(sheetname "")
			)
			(fill
				(thermal_gap 0.5)
				(thermal_bridge_width 0.5)
				(island_removal_mode 0)
			)
			(polygon
				(pts
					(arc
						(start 21.082 -7.329932)
						(mid 18.6182 -7.329932)
						(end 21.082 -7.329932)
					)
				)
			)
		)
	)
	(footprint ""
		(layer "F.Cu")
		(at 14.922246 -166.747698 90)
		(property "Reference" "R282"
			(at 0 0 90)
			(layer "F.SilkS")
			(hide yes)
			(effects
				(font
					(size 1.27 1.27)
				)
			)
		)
		(property "Value" "10KR2F-2-GP"
			(at 0.064008 -3.993896 90)
			(unlocked yes)
			(layer "F.Fab")
			(hide yes)
			(effects
				(font
					(size 1.016 1.016)
					(thickness 0.1524)
				)
			)
		)
		(property "Device Type" "R402H16"
			(at 0.064008 -5.517896 90)
			(unlocked yes)
			(layer "F.Fab")
			(hide yes)
			(effects
				(font
					(size 1.016 1.016)
					(thickness 0.1524)
				)
			)
		)
		(duplicate_pad_numbers_are_jumpers no)
		(fp_line
			(start 0.508 -0.9398)
			(end -0.508 -0.9398)
			(stroke
				(width 0.1524)
				(type default)
			)
			(layer "F.SilkS")
		)
		(fp_line
			(start -0.508 -0.9398)
			(end -0.508 0.9398)
			(stroke
				(width 0.1524)
				(type default)
			)
			(layer "F.SilkS")
		)
		(fp_rect
			(start -0.508 0.9398)
			(end 0.508 -0.9398)
			(stroke
				(width 0)
				(type default)
			)
			(fill no)
			(layer "F.CrtYd")
		)
		(fp_rect
			(start -0.508 0.9398)
			(end 0.508 -0.9398)
			(stroke
				(width 0)
				(type default)
			)
			(fill no)
			(layer "F.Fab")
		)
		(pad "1" smd custom
			(at 0 -0.4445 90)
			(size 0.1397 0.1397)
			(layers "F.Cu" "F.Mask" "F.Paste")
			(net "P5VC")
			(options
				(clearance outline)
				(anchor circle)
			)
			(primitives
				(gr_poly
					(pts
						(arc
							(start -0.1778 -0.2794)
							(mid -0.249642 -0.249642)
							(end -0.2794 -0.1778)
						)
						(arc
							(start -0.2794 0.1778)
							(mid -0.249642 0.249642)
							(end -0.1778 0.2794)
						)
						(arc
							(start 0.1778 0.2794)
							(mid 0.249642 0.249642)
							(end 0.2794 0.1778)
						)
						(arc
							(start 0.2794 -0.1778)
							(mid 0.249642 -0.249642)
							(end 0.1778 -0.2794)
						)
					)
					(width 0)
					(fill yes)
				)
			)
		)
		(pad "2" smd custom
			(at 0 0.4445 90)
			(size 0.1397 0.1397)
			(layers "F.Cu" "F.Mask" "F.Paste")
			(net "DRIVE_ACT_13")
			(options
				(clearance outline)
				(anchor circle)
			)
			(primitives
				(gr_poly
					(pts
						(arc
							(start -0.1778 -0.2794)
							(mid -0.249642 -0.249642)
							(end -0.2794 -0.1778)
						)
						(arc
							(start -0.2794 0.1778)
							(mid -0.249642 0.249642)
							(end -0.1778 0.2794)
						)
						(arc
							(start 0.1778 0.2794)
							(mid 0.249642 0.249642)
							(end 0.2794 0.1778)
						)
						(arc
							(start 0.2794 -0.1778)
							(mid 0.249642 -0.249642)
							(end 0.1778 -0.2794)
						)
					)
					(width 0)
					(fill yes)
				)
			)
		)
	)
	(footprint ""
		(layer "F.Cu")
		(at 198.9328 -384.7338)
		(property "Reference" "C125"
			(at 0 0 0)
			(layer "F.SilkS")
			(hide yes)
			(effects
				(font
					(size 1.27 1.27)
				)
			)
		)
		(property "Value" "SCD1U10V2KX-5GP"
			(at 1.1811 -2.7051 0)
			(unlocked yes)
			(layer "F.Fab")
			(hide yes)
			(effects
				(font
					(size 1.016 1.016)
					(thickness 0.1524)
				)
			)
		)
		(property "Device Type" "C402H22"
			(at 1.1811 -4.2291 0)
			(unlocked yes)
			(layer "F.Fab")
			(hide yes)
			(effects
				(font
					(size 1.016 1.016)
					(thickness 0.1524)
				)
			)
		)
		(duplicate_pad_numbers_are_jumpers no)
		(fp_rect
			(start -0.4318 0.9525)
			(end 0.4318 -0.9525)
			(stroke
				(width 0)
				(type default)
			)
			(fill no)
			(layer "F.CrtYd")
		)
		(fp_rect
			(start -0.4318 0.9525)
			(end 0.4318 -0.9525)
			(stroke
				(width 0)
				(type default)
			)
			(fill no)
			(layer "F.Fab")
		)
		(pad "1" smd custom
			(at 0 -0.4445)
			(size 0.1524 0.1524)
			(layers "F.Cu" "F.Mask" "F.Paste")
			(net "P3V3")
			(options
				(clearance outline)
				(anchor circle)
			)
			(primitives
				(gr_poly
					(pts
						(arc
							(start 0.3048 -0.2032)
							(mid 0.275042 -0.275042)
							(end 0.2032 -0.3048)
						)
						(arc
							(start -0.2032 -0.3048)
							(mid -0.275042 -0.275042)
							(end -0.3048 -0.2032)
						)
						(arc
							(start -0.3048 0.2032)
							(mid -0.275042 0.275042)
							(end -0.2032 0.3048)
						)
						(arc
							(start 0.2032 0.3048)
							(mid 0.275042 0.275042)
							(end 0.3048 0.2032)
						)
					)
					(width 0)
					(fill yes)
				)
			)
		)
		(pad "2" smd custom
			(at 0 0.4445)
			(size 0.1524 0.1524)
			(layers "F.Cu" "F.Mask" "F.Paste")
			(net "GND")
			(options
				(clearance outline)
				(anchor circle)
			)
			(primitives
				(gr_poly
					(pts
						(arc
							(start 0.3048 -0.2032)
							(mid 0.275042 -0.275042)
							(end 0.2032 -0.3048)
						)
						(arc
							(start -0.2032 -0.3048)
							(mid -0.275042 -0.275042)
							(end -0.3048 -0.2032)
						)
						(arc
							(start -0.3048 0.2032)
							(mid -0.275042 0.275042)
							(end -0.2032 0.3048)
						)
						(arc
							(start 0.2032 0.3048)
							(mid 0.275042 0.275042)
							(end 0.3048 0.2032)
						)
					)
					(width 0)
					(fill yes)
				)
			)
		)
	)
	(footprint ""
		(layer "F.Cu")
		(at 19.240246 -468.150702 -90)
		(property "Reference" "R242"
			(at 0 0 270)
			(layer "F.SilkS")
			(hide yes)
			(effects
				(font
					(size 1.27 1.27)
				)
			)
		)
		(property "Value" "0R2J-2-GP"
			(at 0.064008 -3.993896 270)
			(unlocked yes)
			(layer "F.Fab")
			(hide yes)
			(effects
				(font
					(size 1.016 1.016)
					(thickness 0.1524)
				)
			)
		)
		(property "Device Type" "R402H16"
			(at 0.064008 -5.517896 270)
			(unlocked yes)
			(layer "F.Fab")
			(hide yes)
			(effects
				(font
					(size 1.016 1.016)
					(thickness 0.1524)
				)
			)
		)
		(duplicate_pad_numbers_are_jumpers no)
		(fp_line
			(start -0.508 -0.9398)
			(end -0.508 0.9398)
			(stroke
				(width 0.1524)
				(type default)
			)
			(layer "F.SilkS")
		)
		(fp_line
			(start 0.508 -0.9398)
			(end -0.508 -0.9398)
			(stroke
				(width 0.1524)
				(type default)
			)
			(layer "F.SilkS")
		)
		(fp_rect
			(start -0.508 0.9398)
			(end 0.508 -0.9398)
			(stroke
				(width 0)
				(type default)
			)
			(fill no)
			(layer "F.CrtYd")
		)
		(fp_rect
			(start -0.508 0.9398)
			(end 0.508 -0.9398)
			(stroke
				(width 0)
				(type default)
			)
			(fill no)
			(layer "F.Fab")
		)
		(pad "1" smd custom
			(at 0 -0.4445 270)
			(size 0.1397 0.1397)
			(layers "F.Cu" "F.Mask" "F.Paste")
			(net "DRV_ACT_NET10")
			(options
				(clearance outline)
				(anchor circle)
			)
			(primitives
				(gr_poly
					(pts
						(arc
							(start -0.1778 -0.2794)
							(mid -0.249642 -0.249642)
							(end -0.2794 -0.1778)
						)
						(arc
							(start -0.2794 0.1778)
							(mid -0.249642 0.249642)
							(end -0.1778 0.2794)
						)
						(arc
							(start 0.1778 0.2794)
							(mid 0.249642 0.249642)
							(end 0.2794 0.1778)
						)
						(arc
							(start 0.2794 -0.1778)
							(mid 0.249642 -0.249642)
							(end 0.1778 -0.2794)
						)
					)
					(width 0)
					(fill yes)
				)
			)
		)
		(pad "2" smd custom
			(at 0 0.4445 270)
			(size 0.1397 0.1397)
			(layers "F.Cu" "F.Mask" "F.Paste")
			(net "DRIVE_ACT_10")
			(options
				(clearance outline)
				(anchor circle)
			)
			(primitives
				(gr_poly
					(pts
						(arc
							(start -0.1778 -0.2794)
							(mid -0.249642 -0.249642)
							(end -0.2794 -0.1778)
						)
						(arc
							(start -0.2794 0.1778)
							(mid -0.249642 0.249642)
							(end -0.1778 0.2794)
						)
						(arc
							(start 0.1778 0.2794)
							(mid 0.249642 0.249642)
							(end 0.2794 0.1778)
						)
						(arc
							(start 0.2794 -0.1778)
							(mid 0.249642 -0.249642)
							(end 0.1778 -0.2794)
						)
					)
					(width 0)
					(fill yes)
				)
			)
		)
	)
	(footprint ""
		(layer "F.Cu")
		(at 40.436546 -131.7879 180)
		(property "Reference" "R315"
			(at 0 0 180)
			(layer "F.SilkS")
			(hide yes)
			(effects
				(font
					(size 1.27 1.27)
				)
			)
		)
		(property "Value" "4K7R2J-2-GP"
			(at 0.064008 -3.993896 180)
			(unlocked yes)
			(layer "F.Fab")
			(hide yes)
			(effects
				(font
					(size 1.016 1.016)
					(thickness 0.1524)
				)
			)
		)
		(property "Device Type" "R402H16"
			(at 0.064008 -5.517896 180)
			(unlocked yes)
			(layer "F.Fab")
			(hide yes)
			(effects
				(font
					(size 1.016 1.016)
					(thickness 0.1524)
				)
			)
		)
		(duplicate_pad_numbers_are_jumpers no)
		(fp_line
			(start 0.508 -0.9398)
			(end -0.508 -0.9398)
			(stroke
				(width 0.1524)
				(type default)
			)
			(layer "F.SilkS")
		)
		(fp_line
			(start -0.508 -0.9398)
			(end -0.508 0.9398)
			(stroke
				(width 0.1524)
				(type default)
			)
			(layer "F.SilkS")
		)
		(fp_rect
			(start -0.508 0.9398)
			(end 0.508 -0.9398)
			(stroke
				(width 0)
				(type default)
			)
			(fill no)
			(layer "F.CrtYd")
		)
		(fp_rect
			(start -0.508 0.9398)
			(end 0.508 -0.9398)
			(stroke
				(width 0)
				(type default)
			)
			(fill no)
			(layer "F.Fab")
		)
		(pad "1" smd custom
			(at 0 -0.4445 180)
			(size 0.1397 0.1397)
			(layers "F.Cu" "F.Mask" "F.Paste")
			(net "P3V3")
			(options
				(clearance outline)
				(anchor circle)
			)
			(primitives
				(gr_poly
					(pts
						(arc
							(start -0.1778 -0.2794)
							(mid -0.249642 -0.249642)
							(end -0.2794 -0.1778)
						)
						(arc
							(start -0.2794 0.1778)
							(mid -0.249642 0.249642)
							(end -0.1778 0.2794)
						)
						(arc
							(start 0.1778 0.2794)
							(mid 0.249642 0.249642)
							(end 0.2794 0.1778)
						)
						(arc
							(start 0.2794 -0.1778)
							(mid 0.249642 -0.249642)
							(end 0.1778 -0.2794)
						)
					)
					(width 0)
					(fill yes)
				)
			)
		)
		(pad "2" smd custom
			(at 0 0.4445 180)
			(size 0.1397 0.1397)
			(layers "F.Cu" "F.Mask" "F.Paste")
			(net "I2C_B_TMP2_A2")
			(options
				(clearance outline)
				(anchor circle)
			)
			(primitives
				(gr_poly
					(pts
						(arc
							(start -0.1778 -0.2794)
							(mid -0.249642 -0.249642)
							(end -0.2794 -0.1778)
						)
						(arc
							(start -0.2794 0.1778)
							(mid -0.249642 0.249642)
							(end -0.1778 0.2794)
						)
						(arc
							(start 0.1778 0.2794)
							(mid 0.249642 0.249642)
							(end 0.2794 0.1778)
						)
						(arc
							(start 0.2794 -0.1778)
							(mid 0.249642 -0.249642)
							(end 0.1778 -0.2794)
						)
					)
					(width 0)
					(fill yes)
				)
			)
		)
	)
	(footprint ""
		(layer "F.Cu")
		(at 218.142058 -378.662184)
		(property "Reference" "C131"
			(at 0 0 0)
			(layer "F.SilkS")
			(hide yes)
			(effects
				(font
					(size 1.27 1.27)
				)
			)
		)
		(property "Value" "SCD01U50V2KX-1GP"
			(at 1.1811 -2.7051 0)
			(unlocked yes)
			(layer "F.Fab")
			(hide yes)
			(effects
				(font
					(size 1.016 1.016)
					(thickness 0.1524)
				)
			)
		)
		(property "Device Type" "C402H22"
			(at 1.1811 -4.2291 0)
			(unlocked yes)
			(layer "F.Fab")
			(hide yes)
			(effects
				(font
					(size 1.016 1.016)
					(thickness 0.1524)
				)
			)
		)
		(duplicate_pad_numbers_are_jumpers no)
		(fp_rect
			(start -0.4318 0.9525)
			(end 0.4318 -0.9525)
			(stroke
				(width 0)
				(type default)
			)
			(fill no)
			(layer "F.CrtYd")
		)
		(fp_rect
			(start -0.4318 0.9525)
			(end 0.4318 -0.9525)
			(stroke
				(width 0)
				(type default)
			)
			(fill no)
			(layer "F.Fab")
		)
		(pad "1" smd custom
			(at 0 -0.4445)
			(size 0.1524 0.1524)
			(layers "F.Cu" "F.Mask" "F.Paste")
			(net "HDD_PRSNT_NET1")
			(options
				(clearance outline)
				(anchor circle)
			)
			(primitives
				(gr_poly
					(pts
						(arc
							(start 0.3048 -0.2032)
							(mid 0.275042 -0.275042)
							(end 0.2032 -0.3048)
						)
						(arc
							(start -0.2032 -0.3048)
							(mid -0.275042 -0.275042)
							(end -0.3048 -0.2032)
						)
						(arc
							(start -0.3048 0.2032)
							(mid -0.275042 0.275042)
							(end -0.2032 0.3048)
						)
						(arc
							(start 0.2032 0.3048)
							(mid 0.275042 0.275042)
							(end 0.3048 0.2032)
						)
					)
					(width 0)
					(fill yes)
				)
			)
		)
		(pad "2" smd custom
			(at 0 0.4445)
			(size 0.1524 0.1524)
			(layers "F.Cu" "F.Mask" "F.Paste")
			(net "GND")
			(options
				(clearance outline)
				(anchor circle)
			)
			(primitives
				(gr_poly
					(pts
						(arc
							(start 0.3048 -0.2032)
							(mid 0.275042 -0.275042)
							(end 0.2032 -0.3048)
						)
						(arc
							(start -0.2032 -0.3048)
							(mid -0.275042 -0.275042)
							(end -0.3048 -0.2032)
						)
						(arc
							(start -0.3048 0.2032)
							(mid -0.275042 0.275042)
							(end -0.2032 0.3048)
						)
						(arc
							(start 0.2032 0.3048)
							(mid 0.275042 0.275042)
							(end 0.3048 0.2032)
						)
					)
					(width 0)
					(fill yes)
				)
			)
		)
	)
	(footprint ""
		(layer "F.Cu")
		(at 52.958746 -212.372702 -90)
		(property "Reference" "U38"
			(at 0 0 270)
			(layer "F.SilkS")
			(hide yes)
			(effects
				(font
					(size 1.27 1.27)
				)
			)
		)
		(property "Value" "P2003EVG-GP"
			(at 0 -11.1252 270)
			(unlocked yes)
			(layer "F.Fab")
			(hide yes)
			(effects
				(font
					(size 1.016 1.016)
					(thickness 0.1524)
				)
			)
		)
		(property "Device Type" "SOIC8H79"
			(at 0 -12.6492 270)
			(unlocked yes)
			(layer "F.Fab")
			(hide yes)
			(effects
				(font
					(size 1.016 1.016)
					(thickness 0.1524)
				)
			)
		)
		(duplicate_pad_numbers_are_jumpers no)
		(fp_line
			(start -2.6162 3.429)
			(end -2.6162 1.4732)
			(stroke
				(width 0.4064)
				(type default)
			)
			(layer "F.SilkS")
		)
		(fp_line
			(start -2.7432 1.4224)
			(end 2.1336 1.4224)
			(stroke
				(width 0.1524)
				(type default)
			)
			(layer "F.SilkS")
		)
		(fp_line
			(start 2.1336 1.4224)
			(end 2.1336 -1.4224)
			(stroke
				(width 0.1524)
				(type default)
			)
			(layer "F.SilkS")
		)
		(fp_line
			(start -2.2352 0)
			(end -2.7432 0.508)
			(stroke
				(width 0.1524)
				(type default)
			)
			(layer "F.SilkS")
		)
		(fp_line
			(start -2.7432 -0.508)
			(end -2.2352 0)
			(stroke
				(width 0.1524)
				(type default)
			)
			(layer "F.SilkS")
		)
		(fp_line
			(start -2.7432 -1.4224)
			(end -2.7432 1.4224)
			(stroke
				(width 0.1524)
				(type default)
			)
			(layer "F.SilkS")
		)
		(fp_line
			(start 2.1336 -1.4224)
			(end -2.7432 -1.4224)
			(stroke
				(width 0.1524)
				(type default)
			)
			(layer "F.SilkS")
		)
		(fp_poly
			(pts
				(xy 2.2098 -1.4224) (xy 2.2098 1.4224) (xy -2.2225 1.4224) (xy -2.2225 -1.4224)
			)
			(stroke
				(width 0)
				(type default)
			)
			(fill yes)
			(layer "F.SilkS")
		)
		(fp_rect
			(start -2.4511 2.9972)
			(end 2.4511 -2.9972)
			(stroke
				(width 0)
				(type default)
			)
			(fill no)
			(layer "F.CrtYd")
		)
		(fp_poly
			(pts
				(xy -2.8194 3.6322) (xy -2.8194 -3.6322) (xy 2.8194 -3.6322) (xy 2.8194 -2.2987) (xy 2.4511 -2.2987)
				(xy 2.4511 -2.9972) (xy -2.4511 -2.9972) (xy -2.4511 2.9972) (xy 2.4511 2.9972) (xy 2.4511 -2.286)
				(xy 2.8194 -2.286) (xy 2.8194 3.6322)
			)
			(stroke
				(width 0)
				(type default)
			)
			(fill no)
			(layer "F.CrtYd")
		)
		(fp_rect
			(start -2.8194 3.6322)
			(end 2.8194 -3.6322)
			(stroke
				(width 0)
				(type default)
			)
			(fill no)
			(layer "F.Fab")
		)
		(pad "1" smd rect
			(at -1.905 2.54 270)
			(size 0.635 1.651)
			(layers "F.Cu" "F.Mask" "F.Paste")
			(net "P12V")
		)
		(pad "2" smd rect
			(at -0.635 2.54 270)
			(size 0.635 1.651)
			(layers "F.Cu" "F.Mask" "F.Paste")
			(net "P12V")
		)
		(pad "3" smd rect
			(at 0.635 2.54 270)
			(size 0.635 1.651)
			(layers "F.Cu" "F.Mask" "F.Paste")
			(net "P12V")
		)
		(pad "4" smd rect
			(at 1.905 2.54 270)
			(size 0.635 1.651)
			(layers "F.Cu" "F.Mask" "F.Paste")
			(net "SW_HDD12_N")
		)
		(pad "5" smd rect
			(at 1.905 -2.54 270)
			(size 0.635 1.651)
			(layers "F.Cu" "F.Mask" "F.Paste")
			(net "P12V_HDD12")
		)
		(pad "6" smd rect
			(at 0.635 -2.54 270)
			(size 0.635 1.651)
			(layers "F.Cu" "F.Mask" "F.Paste")
			(net "P12V_HDD12")
		)
		(pad "7" smd rect
			(at -0.635 -2.54 270)
			(size 0.635 1.651)
			(layers "F.Cu" "F.Mask" "F.Paste")
			(net "P12V_HDD12")
		)
		(pad "8" smd rect
			(at -1.905 -2.54 270)
			(size 0.635 1.651)
			(layers "F.Cu" "F.Mask" "F.Paste")
			(net "P12V_HDD12")
		)
	)
	(footprint ""
		(layer "F.Cu")
		(at 37.718746 -310.797702 -90)
		(property "Reference" "U35"
			(at 0 0 270)
			(layer "F.SilkS")
			(hide yes)
			(effects
				(font
					(size 1.27 1.27)
				)
			)
		)
		(property "Value" "P2003EVG-GP"
			(at 0 -11.1252 270)
			(unlocked yes)
			(layer "F.Fab")
			(hide yes)
			(effects
				(font
					(size 1.016 1.016)
					(thickness 0.1524)
				)
			)
		)
		(property "Device Type" "SOIC8H79"
			(at 0 -12.6492 270)
			(unlocked yes)
			(layer "F.Fab")
			(hide yes)
			(effects
				(font
					(size 1.016 1.016)
					(thickness 0.1524)
				)
			)
		)
		(duplicate_pad_numbers_are_jumpers no)
		(fp_line
			(start -2.6162 3.429)
			(end -2.6162 1.4732)
			(stroke
				(width 0.4064)
				(type default)
			)
			(layer "F.SilkS")
		)
		(fp_line
			(start -2.7432 1.4224)
			(end 2.1336 1.4224)
			(stroke
				(width 0.1524)
				(type default)
			)
			(layer "F.SilkS")
		)
		(fp_line
			(start 2.1336 1.4224)
			(end 2.1336 -1.4224)
			(stroke
				(width 0.1524)
				(type default)
			)
			(layer "F.SilkS")
		)
		(fp_line
			(start -2.2352 0)
			(end -2.7432 0.508)
			(stroke
				(width 0.1524)
				(type default)
			)
			(layer "F.SilkS")
		)
		(fp_line
			(start -2.7432 -0.508)
			(end -2.2352 0)
			(stroke
				(width 0.1524)
				(type default)
			)
			(layer "F.SilkS")
		)
		(fp_line
			(start -2.7432 -1.4224)
			(end -2.7432 1.4224)
			(stroke
				(width 0.1524)
				(type default)
			)
			(layer "F.SilkS")
		)
		(fp_line
			(start 2.1336 -1.4224)
			(end -2.7432 -1.4224)
			(stroke
				(width 0.1524)
				(type default)
			)
			(layer "F.SilkS")
		)
		(fp_poly
			(pts
				(xy 2.2098 -1.4224) (xy 2.2098 1.4224) (xy -2.2225 1.4224) (xy -2.2225 -1.4224)
			)
			(stroke
				(width 0)
				(type default)
			)
			(fill yes)
			(layer "F.SilkS")
		)
		(fp_rect
			(start -2.4511 2.9972)
			(end 2.4511 -2.9972)
			(stroke
				(width 0)
				(type default)
			)
			(fill no)
			(layer "F.CrtYd")
		)
		(fp_poly
			(pts
				(xy -2.8194 3.6322) (xy -2.8194 -3.6322) (xy 2.8194 -3.6322) (xy 2.8194 -2.2987) (xy 2.4511 -2.2987)
				(xy 2.4511 -2.9972) (xy -2.4511 -2.9972) (xy -2.4511 2.9972) (xy 2.4511 2.9972) (xy 2.4511 -2.286)
				(xy 2.8194 -2.286) (xy 2.8194 3.6322)
			)
			(stroke
				(width 0)
				(type default)
			)
			(fill no)
			(layer "F.CrtYd")
		)
		(fp_rect
			(start -2.8194 3.6322)
			(end 2.8194 -3.6322)
			(stroke
				(width 0)
				(type default)
			)
			(fill no)
			(layer "F.Fab")
		)
		(pad "1" smd rect
			(at -1.905 2.54 270)
			(size 0.635 1.651)
			(layers "F.Cu" "F.Mask" "F.Paste")
			(net "P12V")
		)
		(pad "2" smd rect
			(at -0.635 2.54 270)
			(size 0.635 1.651)
			(layers "F.Cu" "F.Mask" "F.Paste")
			(net "P12V")
		)
		(pad "3" smd rect
			(at 0.635 2.54 270)
			(size 0.635 1.651)
			(layers "F.Cu" "F.Mask" "F.Paste")
			(net "P12V")
		)
		(pad "4" smd rect
			(at 1.905 2.54 270)
			(size 0.635 1.651)
			(layers "F.Cu" "F.Mask" "F.Paste")
			(net "SW_HDD11_N")
		)
		(pad "5" smd rect
			(at 1.905 -2.54 270)
			(size 0.635 1.651)
			(layers "F.Cu" "F.Mask" "F.Paste")
			(net "P12V_HDD11")
		)
		(pad "6" smd rect
			(at 0.635 -2.54 270)
			(size 0.635 1.651)
			(layers "F.Cu" "F.Mask" "F.Paste")
			(net "P12V_HDD11")
		)
		(pad "7" smd rect
			(at -0.635 -2.54 270)
			(size 0.635 1.651)
			(layers "F.Cu" "F.Mask" "F.Paste")
			(net "P12V_HDD11")
		)
		(pad "8" smd rect
			(at -1.905 -2.54 270)
			(size 0.635 1.651)
			(layers "F.Cu" "F.Mask" "F.Paste")
			(net "P12V_HDD11")
		)
	)
	(footprint ""
		(layer "F.Cu")
		(at 30.734 -282.829 90)
		(property "Reference" "C371"
			(at 0 0 90)
			(layer "F.SilkS")
			(hide yes)
			(effects
				(font
					(size 1.27 1.27)
				)
			)
		)
		(property "Value" "SCD033U25V2KX-GP"
			(at 1.1811 -2.7051 90)
			(unlocked yes)
			(layer "F.Fab")
			(hide yes)
			(effects
				(font
					(size 1.016 1.016)
					(thickness 0.1524)
				)
			)
		)
		(property "Device Type" "C402H22"
			(at 1.1811 -4.2291 90)
			(unlocked yes)
			(layer "F.Fab")
			(hide yes)
			(effects
				(font
					(size 1.016 1.016)
					(thickness 0.1524)
				)
			)
		)
		(duplicate_pad_numbers_are_jumpers no)
		(fp_rect
			(start -0.4318 0.9525)
			(end 0.4318 -0.9525)
			(stroke
				(width 0)
				(type default)
			)
			(fill no)
			(layer "F.CrtYd")
		)
		(fp_rect
			(start -0.4318 0.9525)
			(end 0.4318 -0.9525)
			(stroke
				(width 0)
				(type default)
			)
			(fill no)
			(layer "F.Fab")
		)
		(pad "1" smd custom
			(at 0 -0.4445 90)
			(size 0.1524 0.1524)
			(layers "F.Cu" "F.Mask" "F.Paste")
			(net "SW_HDD7_P")
			(options
				(clearance outline)
				(anchor circle)
			)
			(primitives
				(gr_poly
					(pts
						(arc
							(start 0.3048 -0.2032)
							(mid 0.275042 -0.275042)
							(end 0.2032 -0.3048)
						)
						(arc
							(start -0.2032 -0.3048)
							(mid -0.275042 -0.275042)
							(end -0.3048 -0.2032)
						)
						(arc
							(start -0.3048 0.2032)
							(mid -0.275042 0.275042)
							(end -0.2032 0.3048)
						)
						(arc
							(start 0.2032 0.3048)
							(mid 0.275042 0.275042)
							(end 0.3048 0.2032)
						)
					)
					(width 0)
					(fill yes)
				)
			)
		)
		(pad "2" smd custom
			(at 0 0.4445 90)
			(size 0.1524 0.1524)
			(layers "F.Cu" "F.Mask" "F.Paste")
			(net "GND")
			(options
				(clearance outline)
				(anchor circle)
			)
			(primitives
				(gr_poly
					(pts
						(arc
							(start 0.3048 -0.2032)
							(mid 0.275042 -0.275042)
							(end 0.2032 -0.3048)
						)
						(arc
							(start -0.2032 -0.3048)
							(mid -0.275042 -0.275042)
							(end -0.3048 -0.2032)
						)
						(arc
							(start -0.3048 0.2032)
							(mid -0.275042 0.275042)
							(end -0.2032 0.3048)
						)
						(arc
							(start 0.2032 0.3048)
							(mid 0.275042 0.275042)
							(end 0.3048 0.2032)
						)
					)
					(width 0)
					(fill yes)
				)
			)
		)
	)
	(footprint ""
		(layer "F.Cu")
		(at 33.273746 -269.2527 -90)
		(property "Reference" "C216"
			(at 0 0 270)
			(layer "F.SilkS")
			(hide yes)
			(effects
				(font
					(size 1.27 1.27)
				)
			)
		)
		(property "Value" "SCD01U50V2KX-1GP"
			(at 1.1811 -2.7051 270)
			(unlocked yes)
			(layer "F.Fab")
			(hide yes)
			(effects
				(font
					(size 1.016 1.016)
					(thickness 0.1524)
				)
			)
		)
		(property "Device Type" "C402H22"
			(at 1.1811 -4.2291 270)
			(unlocked yes)
			(layer "F.Fab")
			(hide yes)
			(effects
				(font
					(size 1.016 1.016)
					(thickness 0.1524)
				)
			)
		)
		(duplicate_pad_numbers_are_jumpers no)
		(fp_rect
			(start -0.4318 0.9525)
			(end 0.4318 -0.9525)
			(stroke
				(width 0)
				(type default)
			)
			(fill no)
			(layer "F.CrtYd")
		)
		(fp_rect
			(start -0.4318 0.9525)
			(end 0.4318 -0.9525)
			(stroke
				(width 0)
				(type default)
			)
			(fill no)
			(layer "F.Fab")
		)
		(pad "1" smd custom
			(at 0 -0.4445 270)
			(size 0.1524 0.1524)
			(layers "F.Cu" "F.Mask" "F.Paste")
			(net "SAS2X28_DRIVE_RX_N_B7")
			(options
				(clearance outline)
				(anchor circle)
			)
			(primitives
				(gr_poly
					(pts
						(arc
							(start 0.3048 -0.2032)
							(mid 0.275042 -0.275042)
							(end 0.2032 -0.3048)
						)
						(arc
							(start -0.2032 -0.3048)
							(mid -0.275042 -0.275042)
							(end -0.3048 -0.2032)
						)
						(arc
							(start -0.3048 0.2032)
							(mid -0.275042 0.275042)
							(end -0.2032 0.3048)
						)
						(arc
							(start 0.2032 0.3048)
							(mid 0.275042 0.275042)
							(end 0.3048 0.2032)
						)
					)
					(width 0)
					(fill yes)
				)
			)
		)
		(pad "2" smd custom
			(at 0 0.4445 270)
			(size 0.1524 0.1524)
			(layers "F.Cu" "F.Mask" "F.Paste")
			(net "SAS2X28_B_HDD7_RX_-")
			(options
				(clearance outline)
				(anchor circle)
			)
			(primitives
				(gr_poly
					(pts
						(arc
							(start 0.3048 -0.2032)
							(mid 0.275042 -0.275042)
							(end 0.2032 -0.3048)
						)
						(arc
							(start -0.2032 -0.3048)
							(mid -0.275042 -0.275042)
							(end -0.3048 -0.2032)
						)
						(arc
							(start -0.3048 0.2032)
							(mid -0.275042 0.275042)
							(end -0.2032 0.3048)
						)
						(arc
							(start 0.2032 0.3048)
							(mid 0.275042 0.275042)
							(end 0.3048 0.2032)
						)
					)
					(width 0)
					(fill yes)
				)
			)
		)
	)
	(footprint ""
		(layer "F.Cu")
		(at 26.542746 -322.735702)
		(property "Reference" "C284"
			(at 0 0 0)
			(layer "F.SilkS")
			(hide yes)
			(effects
				(font
					(size 1.27 1.27)
				)
			)
		)
		(property "Value" "SC1U16V3KX-5GP"
			(at 0 -2.8194 0)
			(unlocked yes)
			(layer "F.Fab")
			(hide yes)
			(effects
				(font
					(size 1.016 1.016)
					(thickness 0.1524)
				)
			)
		)
		(property "Device Type" "C603H36"
			(at 0 -4.3434 0)
			(unlocked yes)
			(layer "F.Fab")
			(hide yes)
			(effects
				(font
					(size 1.016 1.016)
					(thickness 0.1524)
				)
			)
		)
		(duplicate_pad_numbers_are_jumpers no)
		(fp_line
			(start 0.508 0)
			(end -0.508 0)
			(stroke
				(width 0.2032)
				(type default)
			)
			(layer "F.SilkS")
		)
		(fp_rect
			(start -0.5842 1.3335)
			(end 0.5842 -1.3335)
			(stroke
				(width 0)
				(type default)
			)
			(fill no)
			(layer "F.CrtYd")
		)
		(fp_rect
			(start -0.5842 1.3335)
			(end 0.5842 -1.3335)
			(stroke
				(width 0)
				(type default)
			)
			(fill no)
			(layer "F.Fab")
		)
		(pad "1" smd custom
			(at 0 -0.762)
			(size 0.2159 0.2159)
			(layers "F.Cu" "F.Mask" "F.Paste")
			(net "P5V_HDD11")
			(options
				(clearance outline)
				(anchor circle)
			)
			(primitives
				(gr_poly
					(pts
						(arc
							(start -0.3302 -0.4318)
							(mid -0.402042 -0.402042)
							(end -0.4318 -0.3302)
						)
						(arc
							(start -0.4318 0.3302)
							(mid -0.402042 0.402042)
							(end -0.3302 0.4318)
						)
						(arc
							(start 0.3302 0.4318)
							(mid 0.402042 0.402042)
							(end 0.4318 0.3302)
						)
						(arc
							(start 0.4318 -0.3302)
							(mid 0.402042 -0.402042)
							(end 0.3302 -0.4318)
						)
					)
					(width 0)
					(fill yes)
				)
			)
		)
		(pad "2" smd custom
			(at 0 0.762)
			(size 0.2159 0.2159)
			(layers "F.Cu" "F.Mask" "F.Paste")
			(net "GND")
			(options
				(clearance outline)
				(anchor circle)
			)
			(primitives
				(gr_poly
					(pts
						(arc
							(start -0.3302 -0.4318)
							(mid -0.402042 -0.402042)
							(end -0.4318 -0.3302)
						)
						(arc
							(start -0.4318 0.3302)
							(mid -0.402042 0.402042)
							(end -0.3302 0.4318)
						)
						(arc
							(start 0.3302 0.4318)
							(mid 0.402042 0.402042)
							(end 0.4318 0.3302)
						)
						(arc
							(start 0.4318 -0.3302)
							(mid 0.402042 -0.402042)
							(end 0.3302 -0.4318)
						)
					)
					(width 0)
					(fill yes)
				)
			)
		)
	)
	(footprint ""
		(layer "F.Cu")
		(at 56.209946 -191.7827 180)
		(property "Reference" "C242"
			(at 0 0 180)
			(layer "F.SilkS")
			(hide yes)
			(effects
				(font
					(size 1.27 1.27)
				)
			)
		)
		(property "Value" "SC10U25V6KX-1GP"
			(at -0.0762 -5.1308 180)
			(unlocked yes)
			(layer "F.Fab")
			(hide yes)
			(effects
				(font
					(size 1.016 1.016)
					(thickness 0.1524)
				)
			)
		)
		(property "Device Type" "C1206H71"
			(at -0.127 -6.6548 180)
			(unlocked yes)
			(layer "F.Fab")
			(hide yes)
			(effects
				(font
					(size 1.016 1.016)
					(thickness 0.1524)
				)
			)
		)
		(duplicate_pad_numbers_are_jumpers no)
		(fp_line
			(start 1.016 2.2352)
			(end -1.016 2.2352)
			(stroke
				(width 0.1524)
				(type default)
			)
			(layer "F.SilkS")
		)
		(fp_line
			(start 1.016 0.8382)
			(end 1.016 2.2352)
			(stroke
				(width 0.1524)
				(type default)
			)
			(layer "F.SilkS")
		)
		(fp_line
			(start 1.016 -2.2352)
			(end 1.016 -0.8382)
			(stroke
				(width 0.1524)
				(type default)
			)
			(layer "F.SilkS")
		)
		(fp_line
			(start -1.016 2.2352)
			(end -1.016 0.8382)
			(stroke
				(width 0.1524)
				(type default)
			)
			(layer "F.SilkS")
		)
		(fp_line
			(start -1.016 -0.8382)
			(end -1.016 -2.2352)
			(stroke
				(width 0.1524)
				(type default)
			)
			(layer "F.SilkS")
		)
		(fp_line
			(start -1.016 -2.2352)
			(end 1.016 -2.2352)
			(stroke
				(width 0.1524)
				(type default)
			)
			(layer "F.SilkS")
		)
		(fp_rect
			(start -1.0922 2.3114)
			(end 1.0922 -2.3114)
			(stroke
				(width 0)
				(type default)
			)
			(fill no)
			(layer "F.CrtYd")
		)
		(fp_poly
			(pts
				(xy 1.0922 -2.3114) (xy 1.0922 2.3114) (xy -1.0922 2.3114) (xy -1.0922 -2.3114)
			)
			(stroke
				(width 0)
				(type default)
			)
			(fill no)
			(layer "F.Fab")
		)
		(pad "1" smd rect
			(at 0 -1.397 180)
			(size 1.651 1.27)
			(layers "F.Cu" "F.Mask" "F.Paste")
			(net "P12V_HDD8")
		)
		(pad "2" smd rect
			(at 0 1.397 180)
			(size 1.651 1.27)
			(layers "F.Cu" "F.Mask" "F.Paste")
			(net "GND")
		)
	)
	(footprint ""
		(layer "F.Cu")
		(at 218.646756 -476.151702 -90)
		(property "Reference" "C105"
			(at 0 0 270)
			(layer "F.SilkS")
			(hide yes)
			(effects
				(font
					(size 1.27 1.27)
				)
			)
		)
		(property "Value" "SCD01U50V2KX-1GP"
			(at 1.1811 -2.7051 270)
			(unlocked yes)
			(layer "F.Fab")
			(hide yes)
			(effects
				(font
					(size 1.016 1.016)
					(thickness 0.1524)
				)
			)
		)
		(property "Device Type" "C402H22"
			(at 1.1811 -4.2291 270)
			(unlocked yes)
			(layer "F.Fab")
			(hide yes)
			(effects
				(font
					(size 1.016 1.016)
					(thickness 0.1524)
				)
			)
		)
		(duplicate_pad_numbers_are_jumpers no)
		(fp_rect
			(start -0.4318 0.9525)
			(end 0.4318 -0.9525)
			(stroke
				(width 0)
				(type default)
			)
			(fill no)
			(layer "F.CrtYd")
		)
		(fp_rect
			(start -0.4318 0.9525)
			(end 0.4318 -0.9525)
			(stroke
				(width 0)
				(type default)
			)
			(fill no)
			(layer "F.Fab")
		)
		(pad "1" smd custom
			(at 0 -0.4445 270)
			(size 0.1524 0.1524)
			(layers "F.Cu" "F.Mask" "F.Paste")
			(net "SAS2X28_DRIVE_RX_P_B0")
			(options
				(clearance outline)
				(anchor circle)
			)
			(primitives
				(gr_poly
					(pts
						(arc
							(start 0.3048 -0.2032)
							(mid 0.275042 -0.275042)
							(end 0.2032 -0.3048)
						)
						(arc
							(start -0.2032 -0.3048)
							(mid -0.275042 -0.275042)
							(end -0.3048 -0.2032)
						)
						(arc
							(start -0.3048 0.2032)
							(mid -0.275042 0.275042)
							(end -0.2032 0.3048)
						)
						(arc
							(start 0.2032 0.3048)
							(mid 0.275042 0.275042)
							(end 0.3048 0.2032)
						)
					)
					(width 0)
					(fill yes)
				)
			)
		)
		(pad "2" smd custom
			(at 0 0.4445 270)
			(size 0.1524 0.1524)
			(layers "F.Cu" "F.Mask" "F.Paste")
			(net "SAS2X28_B_HDD0_RX_+")
			(options
				(clearance outline)
				(anchor circle)
			)
			(primitives
				(gr_poly
					(pts
						(arc
							(start 0.3048 -0.2032)
							(mid 0.275042 -0.275042)
							(end 0.2032 -0.3048)
						)
						(arc
							(start -0.2032 -0.3048)
							(mid -0.275042 -0.275042)
							(end -0.3048 -0.2032)
						)
						(arc
							(start -0.3048 0.2032)
							(mid -0.275042 0.275042)
							(end -0.2032 0.3048)
						)
						(arc
							(start 0.2032 0.3048)
							(mid 0.275042 0.275042)
							(end 0.3048 0.2032)
						)
					)
					(width 0)
					(fill yes)
				)
			)
		)
	)
	(footprint ""
		(layer "F.Cu")
		(at 17.500092 -438.330086 -90)
		(property "Reference" "SKT11"
			(at 0 0 270)
			(layer "F.SilkS")
			(hide yes)
			(effects
				(font
					(size 1.27 1.27)
				)
			)
		)
		(property "Value" "SKT-SATA14P-15P-12-GP"
			(at -22.6187 8.1788 270)
			(unlocked yes)
			(layer "F.Fab")
			(hide yes)
			(effects
				(font
					(size 1.016 1.016)
					(thickness 0.1524)
				)
			)
		)
		(property "Device Type" "87945-1001"
			(at -22.6187 6.6548 270)
			(unlocked yes)
			(layer "F.Fab")
			(hide yes)
			(effects
				(font
					(size 1.016 1.016)
					(thickness 0.1524)
				)
			)
		)
		(duplicate_pad_numbers_are_jumpers no)
		(fp_line
			(start -20.4724 9.652)
			(end -20.4724 2.3114)
			(stroke
				(width 0.1524)
				(type default)
			)
			(layer "F.SilkS")
		)
		(fp_line
			(start -17.8435 9.652)
			(end -20.4724 9.652)
			(stroke
				(width 0.1524)
				(type default)
			)
			(layer "F.SilkS")
		)
		(fp_line
			(start 17.8435 9.652)
			(end 17.8435 7.9502)
			(stroke
				(width 0.1524)
				(type default)
			)
			(layer "F.SilkS")
		)
		(fp_line
			(start 20.4724 9.652)
			(end 17.8435 9.652)
			(stroke
				(width 0.1524)
				(type default)
			)
			(layer "F.SilkS")
		)
		(fp_line
			(start -17.8435 7.9502)
			(end -17.8435 9.652)
			(stroke
				(width 0.1524)
				(type default)
			)
			(layer "F.SilkS")
		)
		(fp_line
			(start 17.8435 7.9502)
			(end -17.8435 7.9502)
			(stroke
				(width 0.1524)
				(type default)
			)
			(layer "F.SilkS")
		)
		(fp_line
			(start -23.7617 2.3114)
			(end -23.7617 -2.3114)
			(stroke
				(width 0.1524)
				(type default)
			)
			(layer "F.SilkS")
		)
		(fp_line
			(start -20.4724 2.3114)
			(end -23.7617 2.3114)
			(stroke
				(width 0.1524)
				(type default)
			)
			(layer "F.SilkS")
		)
		(fp_line
			(start 20.4724 2.3114)
			(end 20.4724 9.652)
			(stroke
				(width 0.1524)
				(type default)
			)
			(layer "F.SilkS")
		)
		(fp_line
			(start 23.7617 2.3114)
			(end 20.4724 2.3114)
			(stroke
				(width 0.1524)
				(type default)
			)
			(layer "F.SilkS")
		)
		(fp_line
			(start -23.117556 0.5461)
			(end -23.117556 -0.5461)
			(stroke
				(width 0.3048)
				(type default)
			)
			(layer "F.SilkS")
		)
		(fp_line
			(start 20.882356 0.5461)
			(end 20.882356 -0.5461)
			(stroke
				(width 0.3048)
				(type default)
			)
			(layer "F.SilkS")
		)
		(fp_line
			(start -20.882356 -0.5461)
			(end -20.882356 0.5461)
			(stroke
				(width 0.3048)
				(type default)
			)
			(layer "F.SilkS")
		)
		(fp_line
			(start 23.117556 -0.5461)
			(end 23.117556 0.5461)
			(stroke
				(width 0.3048)
				(type default)
			)
			(layer "F.SilkS")
		)
		(fp_line
			(start -23.7617 -2.3114)
			(end -20.4724 -2.3114)
			(stroke
				(width 0.1524)
				(type default)
			)
			(layer "F.SilkS")
		)
		(fp_line
			(start -20.4724 -2.3114)
			(end -20.4724 -5.7658)
			(stroke
				(width 0.1524)
				(type default)
			)
			(layer "F.SilkS")
		)
		(fp_line
			(start 20.4724 -2.3114)
			(end 23.7617 -2.3114)
			(stroke
				(width 0.1524)
				(type default)
			)
			(layer "F.SilkS")
		)
		(fp_line
			(start 23.7617 -2.3114)
			(end 23.7617 2.3114)
			(stroke
				(width 0.1524)
				(type default)
			)
			(layer "F.SilkS")
		)
		(fp_line
			(start -20.4724 -5.7658)
			(end 20.4724 -5.7658)
			(stroke
				(width 0.1524)
				(type default)
			)
			(layer "F.SilkS")
		)
		(fp_line
			(start 20.4724 -5.7658)
			(end 20.4724 -2.3114)
			(stroke
				(width 0.1524)
				(type default)
			)
			(layer "F.SilkS")
		)
		(fp_line
			(start -15.3924 -5.8547)
			(end -16.3576 -5.8547)
			(stroke
				(width 0.3302)
				(type default)
			)
			(layer "F.SilkS")
		)
		(fp_arc
			(start -20.882356 0.5461)
			(mid -21.999956 1.6637)
			(end -23.117556 0.5461)
			(stroke
				(width 0.3048)
				(type default)
			)
			(layer "F.SilkS")
		)
		(fp_arc
			(start 23.117556 0.5461)
			(mid 21.999956 1.6637)
			(end 20.882356 0.5461)
			(stroke
				(width 0.3048)
				(type default)
			)
			(layer "F.SilkS")
		)
		(fp_arc
			(start -23.117556 -0.5461)
			(mid -21.999956 -1.6637)
			(end -20.882356 -0.5461)
			(stroke
				(width 0.3048)
				(type default)
			)
			(layer "F.SilkS")
		)
		(fp_arc
			(start 20.882356 -0.5461)
			(mid 21.999956 -1.6637)
			(end 23.117556 -0.5461)
			(stroke
				(width 0.3048)
				(type default)
			)
			(layer "F.SilkS")
		)
		(fp_poly
			(pts
				(xy -15.87119 -5.838698) (xy -15.23619 -6.473698) (xy -16.50619 -6.473698)
			)
			(stroke
				(width 0)
				(type default)
			)
			(fill yes)
			(layer "F.SilkS")
		)
		(fp_poly
			(pts
				(xy -20.2184 -5.5118) (xy 20.2184 -5.5118) (xy 20.2184 -2.0574) (xy 23.5077 -2.0574) (xy 23.5077 2.0574)
				(xy 20.2184 2.0574) (xy 20.2184 9.398) (xy 18.0975 9.398) (xy 18.0975 7.6962) (xy -18.0975 7.6962)
				(xy -18.0975 9.398) (xy -20.2184 9.398) (xy -20.2184 2.0574) (xy -23.5077 2.0574) (xy -23.5077 -2.0574)
				(xy -20.2184 -2.0574)
			)
			(stroke
				(width 0)
				(type default)
			)
			(fill no)
			(layer "F.CrtYd")
		)
		(fp_poly
			(pts
				(xy -20.2184 -5.5118) (xy -20.2184 -6.0198) (xy -20.7264 -6.0198) (xy -20.7264 -2.5654) (xy -24.0157 -2.5654)
				(xy -24.0157 2.5654) (xy -20.7264 2.5654) (xy -20.7264 9.906) (xy -17.5895 9.906) (xy -17.5895 8.2042)
				(xy 17.5895 8.2042) (xy 17.5895 9.906) (xy 20.7264 9.906) (xy 20.7264 2.5654) (xy 24.0157 2.5654)
				(xy 24.0157 -2.5654) (xy 20.7264 -2.5654) (xy 20.7264 -6.0198) (xy -20.21586 -6.0198) (xy -20.21586 -5.5118)
				(xy 20.2184 -5.5118) (xy 20.2184 -2.0574) (xy 23.5077 -2.0574) (xy 23.5077 2.0574) (xy 20.2184 2.0574)
				(xy 20.2184 9.398) (xy 18.0975 9.398) (xy 18.0975 7.6962) (xy -18.0975 7.6962) (xy -18.0975 9.398)
				(xy -20.2184 9.398) (xy -20.2184 2.0574) (xy -23.5077 2.0574) (xy -23.5077 -2.0574) (xy -20.2184 -2.0574)
			)
			(stroke
				(width 0)
				(type default)
			)
			(fill no)
			(layer "F.CrtYd")
		)
		(fp_poly
			(pts
				(xy -20.7264 -6.0198) (xy -20.7264 -2.5654) (xy -24.0157 -2.5654) (xy -24.0157 2.5654) (xy -20.7264 2.5654)
				(xy -20.7264 9.906) (xy -17.5895 9.906) (xy -17.5895 8.2042) (xy 17.5895 8.2042) (xy 17.5895 9.906)
				(xy 20.7264 9.906) (xy 20.7264 2.5654) (xy 24.0157 2.5654) (xy 24.0157 -2.5654) (xy 20.7264 -2.5654)
				(xy 20.7264 -6.0198)
			)
			(stroke
				(width 0)
				(type default)
			)
			(fill no)
			(layer "F.Fab")
		)
		(pad "" np_thru_hole circle
			(at -18.999962 -2.350008 270)
			(size 0.254 0.254)
			(drill 1.8542)
			(layers "*.Cu" "*.Mask")
			(clearance 1.1557)
			(thermal_gap 1.1557)
		)
		(pad "" np_thru_hole circle
			(at 18.999962 -2.350008 270)
			(size 0.254 0.254)
			(drill 1.8542)
			(layers "*.Cu" "*.Mask")
			(clearance 1.1557)
			(thermal_gap 1.1557)
		)
		(pad "H1" thru_hole oval
			(at -21.999956 0 270)
			(size 1.524 2.6162)
			(drill oval 0.8128 1.905)
			(layers "*.Cu" "*.Mask")
			(remove_unused_layers no)
			(net "GND")
			(clearance 0.1524)
			(thermal_gap 0.1524)
		)
		(pad "H2" thru_hole oval
			(at 21.999956 0 270)
			(size 1.524 2.6162)
			(drill oval 0.8128 1.905)
			(layers "*.Cu" "*.Mask")
			(remove_unused_layers no)
			(net "GND")
			(clearance 0.1524)
			(thermal_gap 0.1524)
		)
		(pad "P1" smd rect
			(at -1.89992 -4.249928 270)
			(size 0.6604 2.3876)
			(layers "F.Cu" "F.Mask" "F.Paste")
			(net "Net_65")
		)
		(pad "P2" smd rect
			(at -0.62992 -4.249928 270)
			(size 0.6604 2.3876)
			(layers "F.Cu" "F.Mask" "F.Paste")
			(net "Net_64")
		)
		(pad "P3" smd rect
			(at 0.64008 -4.249928 270)
			(size 0.6604 2.3876)
			(layers "F.Cu" "F.Mask" "F.Paste")
			(net "Net_63")
		)
		(pad "P4" smd rect
			(at 1.91008 -4.249928 270)
			(size 0.6604 2.3876)
			(layers "F.Cu" "F.Mask" "F.Paste")
			(net "GND")
		)
		(pad "P5" smd rect
			(at 3.18008 -4.249928 270)
			(size 0.6604 2.3876)
			(layers "F.Cu" "F.Mask" "F.Paste")
			(net "HDD_PRSNT_NET10")
		)
		(pad "P6" smd rect
			(at 4.45008 -4.249928 270)
			(size 0.6604 2.3876)
			(layers "F.Cu" "F.Mask" "F.Paste")
			(net "GND")
		)
		(pad "P7" smd rect
			(at 5.72008 -4.249928 270)
			(size 0.6604 2.3876)
			(layers "F.Cu" "F.Mask" "F.Paste")
			(net "5V_PRE_10")
		)
		(pad "P8" smd rect
			(at 6.99008 -4.249928 270)
			(size 0.6604 2.3876)
			(layers "F.Cu" "F.Mask" "F.Paste")
			(net "P5V_HDD10")
		)
		(pad "P9" smd rect
			(at 8.26008 -4.249928 270)
			(size 0.6604 2.3876)
			(layers "F.Cu" "F.Mask" "F.Paste")
			(net "P5V_HDD10")
		)
		(pad "P10" smd rect
			(at 9.53008 -4.249928 270)
			(size 0.6604 2.3876)
			(layers "F.Cu" "F.Mask" "F.Paste")
			(net "GND")
		)
		(pad "P11" smd rect
			(at 10.80008 -4.249928 270)
			(size 0.6604 2.3876)
			(layers "F.Cu" "F.Mask" "F.Paste")
			(net "ACT_HDD10")
		)
		(pad "P12" smd rect
			(at 12.07008 -4.249928 270)
			(size 0.6604 2.3876)
			(layers "F.Cu" "F.Mask" "F.Paste")
			(net "GND")
		)
		(pad "P13" smd rect
			(at 13.34008 -4.249928 270)
			(size 0.6604 2.3876)
			(layers "F.Cu" "F.Mask" "F.Paste")
			(net "12V_PRE_10")
		)
		(pad "P14" smd rect
			(at 14.61008 -4.249928 270)
			(size 0.6604 2.3876)
			(layers "F.Cu" "F.Mask" "F.Paste")
			(net "P12V_HDD10")
		)
		(pad "P15" smd rect
			(at 15.88008 -4.249928 270)
			(size 0.6604 2.3876)
			(layers "F.Cu" "F.Mask" "F.Paste")
			(net "P12V_HDD10")
		)
		(pad "S1" smd rect
			(at -15.86992 -4.249928 270)
			(size 0.6604 2.3876)
			(layers "F.Cu" "F.Mask" "F.Paste")
			(net "GND")
		)
		(pad "S2" smd rect
			(at -14.59992 -4.249928 270)
			(size 0.6604 2.3876)
			(layers "F.Cu" "F.Mask" "F.Paste")
			(net "SAS2X28_A_HDD10_TX_+")
		)
		(pad "S3" smd rect
			(at -13.32992 -4.249928 270)
			(size 0.6604 2.3876)
			(layers "F.Cu" "F.Mask" "F.Paste")
			(net "SAS2X28_A_HDD10_TX_-")
		)
		(pad "S4" smd rect
			(at -12.05992 -4.249928 270)
			(size 0.6604 2.3876)
			(layers "F.Cu" "F.Mask" "F.Paste")
			(net "GND")
		)
		(pad "S5" smd rect
			(at -10.78992 -4.249928 270)
			(size 0.6604 2.3876)
			(layers "F.Cu" "F.Mask" "F.Paste")
			(net "SAS2X28_DRIVE_RX_N_A10")
		)
		(pad "S6" smd rect
			(at -9.51992 -4.249928 270)
			(size 0.6604 2.3876)
			(layers "F.Cu" "F.Mask" "F.Paste")
			(net "SAS2X28_DRIVE_RX_P_A10")
		)
		(pad "S7" smd rect
			(at -8.24992 -4.249928 270)
			(size 0.6604 2.3876)
			(layers "F.Cu" "F.Mask" "F.Paste")
			(net "GND")
		)
		(pad "S8" smd rect
			(at -7.480046 -2.100072 270)
			(size 0.508 1.905)
			(layers "F.Cu" "F.Mask" "F.Paste")
			(net "GND")
		)
		(pad "S9" smd rect
			(at -6.679946 -2.100072 270)
			(size 0.508 1.905)
			(layers "F.Cu" "F.Mask" "F.Paste")
			(net "SAS2X28_B_HDD10_TX_+")
		)
		(pad "S10" smd rect
			(at -5.8801 -2.100072 270)
			(size 0.508 1.905)
			(layers "F.Cu" "F.Mask" "F.Paste")
			(net "SAS2X28_B_HDD10_TX_-")
		)
		(pad "S11" smd rect
			(at -5.08 -2.100072 270)
			(size 0.508 1.905)
			(layers "F.Cu" "F.Mask" "F.Paste")
			(net "GND")
		)
		(pad "S12" smd rect
			(at -4.2799 -2.100072 270)
			(size 0.508 1.905)
			(layers "F.Cu" "F.Mask" "F.Paste")
			(net "SAS2X28_DRIVE_RX_N_B10")
		)
		(pad "S13" smd rect
			(at -3.480054 -2.100072 270)
			(size 0.508 1.905)
			(layers "F.Cu" "F.Mask" "F.Paste")
			(net "SAS2X28_DRIVE_RX_P_B10")
		)
		(pad "S14" smd rect
			(at -2.679954 -2.100072 270)
			(size 0.508 1.905)
			(layers "F.Cu" "F.Mask" "F.Paste")
			(net "GND")
		)
		(zone
			(layers "F.Cu" "B.Cu" "In1.Cu" "In2.Cu" "In3.Cu" "In4.Cu" "In5.Cu" "In6.Cu")
			(hatch none 0.5)
			(connect_pads
				(clearance 0)
			)
			(min_thickness 0.25)
			(keepout
				(tracks not_allowed)
				(vias allowed)
				(pads allowed)
				(copperpour not_allowed)
				(footprints allowed)
			)
			(placement
				(enabled no)
				(sheetname "")
			)
			(fill
				(thermal_gap 0.5)
				(thermal_bridge_width 0.5)
				(island_removal_mode 0)
			)
			(polygon
				(pts
					(arc
						(start 21.082 -457.330048)
						(mid 18.6182 -457.330048)
						(end 21.082 -457.330048)
					)
				)
			)
		)
		(zone
			(layers "F.Cu" "B.Cu" "In1.Cu" "In2.Cu" "In3.Cu" "In4.Cu" "In5.Cu" "In6.Cu")
			(hatch none 0.5)
			(connect_pads
				(clearance 0)
			)
			(min_thickness 0.25)
			(keepout
				(tracks not_allowed)
				(vias allowed)
				(pads allowed)
				(copperpour not_allowed)
				(footprints allowed)
			)
			(placement
				(enabled no)
				(sheetname "")
			)
			(fill
				(thermal_gap 0.5)
				(thermal_bridge_width 0.5)
				(island_removal_mode 0)
			)
			(polygon
				(pts
					(arc
						(start 21.082 -419.330124)
						(mid 18.6182 -419.330124)
						(end 21.082 -419.330124)
					)
				)
			)
		)
	)
	(footprint ""
		(layer "F.Cu")
		(at 204.088746 -379.9967)
		(property "Reference" "TP26"
			(at 0 0 0)
			(layer "F.SilkS")
			(hide yes)
			(effects
				(font
					(size 1.27 1.27)
				)
			)
		)
		(property "Value" "TPAD32-GP"
			(at 0 -3.166364 0)
			(unlocked yes)
			(layer "F.Fab")
			(hide yes)
			(effects
				(font
					(size 1.016 1.016)
					(thickness 0.1524)
				)
			)
		)
		(property "Device Type" "TPAD32"
			(at 0 -4.690618 0)
			(unlocked yes)
			(layer "F.Fab")
			(hide yes)
			(effects
				(font
					(size 1.016 1.016)
					(thickness 0.1524)
				)
			)
		)
		(duplicate_pad_numbers_are_jumpers no)
		(fp_poly
			(pts
				(arc
					(start 0.4064 0)
					(mid -0.4064 0)
					(end 0.4064 0)
				)
			)
			(stroke
				(width 0)
				(type default)
			)
			(fill no)
			(layer "F.CrtYd")
		)
		(fp_poly
			(pts
				(arc
					(start 0.7112 0)
					(mid -0.7112 0)
					(end 0.7112 0)
				)
			)
			(stroke
				(width 0)
				(type default)
			)
			(fill no)
			(layer "F.Fab")
		)
		(pad "1" smd circle
			(at 0 0)
			(size 0.8128 0.8128)
			(layers "F.Cu" "F.Mask" "F.Paste")
			(net "ACT_HDD1")
		)
	)
	(footprint ""
		(layer "F.Cu")
		(at 200.278746 -492.5187)
		(property "Reference" "U1"
			(at 0 0 0)
			(layer "F.SilkS")
			(hide yes)
			(effects
				(font
					(size 1.27 1.27)
				)
			)
		)
		(property "Value" "74LVC1G08GW-1-GP"
			(at -2.3368 -8.6868 0)
			(unlocked yes)
			(layer "F.Fab")
			(hide yes)
			(effects
				(font
					(size 1.016 1.016)
					(thickness 0.1524)
				)
			)
		)
		(property "Device Type" "SC70-5H44"
			(at -2.3114 -10.414 0)
			(unlocked yes)
			(layer "F.Fab")
			(hide yes)
			(effects
				(font
					(size 1.016 1.016)
					(thickness 0.1524)
				)
			)
		)
		(duplicate_pad_numbers_are_jumpers no)
		(fp_line
			(start -1.27 -1.7018)
			(end 1.27 -1.7018)
			(stroke
				(width 0.1524)
				(type default)
			)
			(layer "F.SilkS")
		)
		(fp_line
			(start -1.27 1.7018)
			(end -1.27 -1.7018)
			(stroke
				(width 0.1524)
				(type default)
			)
			(layer "F.SilkS")
		)
		(fp_line
			(start 0.6604 -1.8034)
			(end 1.3843 -1.8034)
			(stroke
				(width 0.3302)
				(type default)
			)
			(layer "F.SilkS")
		)
		(fp_line
			(start 1.27 -1.7018)
			(end 1.27 1.7018)
			(stroke
				(width 0.1524)
				(type default)
			)
			(layer "F.SilkS")
		)
		(fp_line
			(start 1.27 1.7018)
			(end -1.27 1.7018)
			(stroke
				(width 0.1524)
				(type default)
			)
			(layer "F.SilkS")
		)
		(fp_line
			(start 1.3843 -1.8034)
			(end 1.3843 -1.1176)
			(stroke
				(width 0.3302)
				(type default)
			)
			(layer "F.SilkS")
		)
		(fp_rect
			(start -1.524 1.9558)
			(end 1.524 -1.9558)
			(stroke
				(width 0)
				(type default)
			)
			(fill no)
			(layer "F.CrtYd")
		)
		(fp_poly
			(pts
				(xy -1.524 -1.9558) (xy 1.524 -1.9558) (xy 1.524 1.9558) (xy -1.524 1.9558)
			)
			(stroke
				(width 0)
				(type default)
			)
			(fill no)
			(layer "F.Fab")
		)
		(pad "1" smd rect
			(at 0.65024 -0.8255)
			(size 0.4064 1.2192)
			(layers "F.Cu" "F.Mask" "F.Paste")
			(net "SAS2X28_B_HDD0_FLT")
		)
		(pad "2" smd rect
			(at 0 -0.8255)
			(size 0.4064 1.2192)
			(layers "F.Cu" "F.Mask" "F.Paste")
			(net "SAS2X28_A_HDD0_FLT")
		)
		(pad "3" smd rect
			(at -0.65024 -0.8255)
			(size 0.4064 1.2192)
			(layers "F.Cu" "F.Mask" "F.Paste")
			(net "GND")
		)
		(pad "4" smd rect
			(at -0.65024 0.8255)
			(size 0.4064 1.2192)
			(layers "F.Cu" "F.Mask" "F.Paste")
			(net "FLT_HDD0_DRIVE")
		)
		(pad "5" smd rect
			(at 0.65024 0.8255)
			(size 0.4064 1.2192)
			(layers "F.Cu" "F.Mask" "F.Paste")
			(net "P3V3")
		)
	)
	(footprint ""
		(layer "F.Cu")
		(at 20.066 -397.9926)
		(property "Reference" "R507"
			(at 0 0 0)
			(layer "F.SilkS")
			(hide yes)
			(effects
				(font
					(size 1.27 1.27)
				)
			)
		)
		(property "Value" "0R2J-2-GP"
			(at 0.064008 -3.993896 0)
			(unlocked yes)
			(layer "F.Fab")
			(hide yes)
			(effects
				(font
					(size 1.016 1.016)
					(thickness 0.1524)
				)
			)
		)
		(property "Device Type" "R402H16"
			(at 0.064008 -5.517896 0)
			(unlocked yes)
			(layer "F.Fab")
			(hide yes)
			(effects
				(font
					(size 1.016 1.016)
					(thickness 0.1524)
				)
			)
		)
		(duplicate_pad_numbers_are_jumpers no)
		(fp_line
			(start -0.508 -0.9398)
			(end -0.508 0.9398)
			(stroke
				(width 0.1524)
				(type default)
			)
			(layer "F.SilkS")
		)
		(fp_line
			(start 0.508 -0.9398)
			(end -0.508 -0.9398)
			(stroke
				(width 0.1524)
				(type default)
			)
			(layer "F.SilkS")
		)
		(fp_rect
			(start -0.508 0.9398)
			(end 0.508 -0.9398)
			(stroke
				(width 0)
				(type default)
			)
			(fill no)
			(layer "F.CrtYd")
		)
		(fp_rect
			(start -0.508 0.9398)
			(end 0.508 -0.9398)
			(stroke
				(width 0)
				(type default)
			)
			(fill no)
			(layer "F.Fab")
		)
		(pad "1" smd custom
			(at 0 -0.4445)
			(size 0.1397 0.1397)
			(layers "F.Cu" "F.Mask" "F.Paste")
			(net "I2C_C_SDA_DAMP_A")
			(options
				(clearance outline)
				(anchor circle)
			)
			(primitives
				(gr_poly
					(pts
						(arc
							(start -0.1778 -0.2794)
							(mid -0.249642 -0.249642)
							(end -0.2794 -0.1778)
						)
						(arc
							(start -0.2794 0.1778)
							(mid -0.249642 0.249642)
							(end -0.1778 0.2794)
						)
						(arc
							(start 0.1778 0.2794)
							(mid 0.249642 0.249642)
							(end 0.2794 0.1778)
						)
						(arc
							(start 0.2794 -0.1778)
							(mid 0.249642 -0.249642)
							(end 0.1778 -0.2794)
						)
					)
					(width 0)
					(fill yes)
				)
			)
		)
		(pad "2" smd custom
			(at 0 0.4445)
			(size 0.1397 0.1397)
			(layers "F.Cu" "F.Mask" "F.Paste")
			(net "I2C_C_SDA")
			(options
				(clearance outline)
				(anchor circle)
			)
			(primitives
				(gr_poly
					(pts
						(arc
							(start -0.1778 -0.2794)
							(mid -0.249642 -0.249642)
							(end -0.2794 -0.1778)
						)
						(arc
							(start -0.2794 0.1778)
							(mid -0.249642 0.249642)
							(end -0.1778 0.2794)
						)
						(arc
							(start 0.1778 0.2794)
							(mid 0.249642 0.249642)
							(end 0.2794 0.1778)
						)
						(arc
							(start 0.2794 -0.1778)
							(mid 0.249642 -0.249642)
							(end 0.1778 -0.2794)
						)
					)
					(width 0)
					(fill yes)
				)
			)
		)
	)
	(footprint ""
		(layer "F.Cu")
		(at 34.035746 -422.938702 180)
		(property "Reference" "C271"
			(at 0 0 180)
			(layer "F.SilkS")
			(hide yes)
			(effects
				(font
					(size 1.27 1.27)
				)
			)
		)
		(property "Value" "SC10U25V6KX-1GP"
			(at -0.0762 -5.1308 180)
			(unlocked yes)
			(layer "F.Fab")
			(hide yes)
			(effects
				(font
					(size 1.016 1.016)
					(thickness 0.1524)
				)
			)
		)
		(property "Device Type" "C1206H71"
			(at -0.127 -6.6548 180)
			(unlocked yes)
			(layer "F.Fab")
			(hide yes)
			(effects
				(font
					(size 1.016 1.016)
					(thickness 0.1524)
				)
			)
		)
		(duplicate_pad_numbers_are_jumpers no)
		(fp_line
			(start 1.016 2.2352)
			(end -1.016 2.2352)
			(stroke
				(width 0.1524)
				(type default)
			)
			(layer "F.SilkS")
		)
		(fp_line
			(start 1.016 0.8382)
			(end 1.016 2.2352)
			(stroke
				(width 0.1524)
				(type default)
			)
			(layer "F.SilkS")
		)
		(fp_line
			(start 1.016 -2.2352)
			(end 1.016 -0.8382)
			(stroke
				(width 0.1524)
				(type default)
			)
			(layer "F.SilkS")
		)
		(fp_line
			(start -1.016 2.2352)
			(end -1.016 0.8382)
			(stroke
				(width 0.1524)
				(type default)
			)
			(layer "F.SilkS")
		)
		(fp_line
			(start -1.016 -0.8382)
			(end -1.016 -2.2352)
			(stroke
				(width 0.1524)
				(type default)
			)
			(layer "F.SilkS")
		)
		(fp_line
			(start -1.016 -2.2352)
			(end 1.016 -2.2352)
			(stroke
				(width 0.1524)
				(type default)
			)
			(layer "F.SilkS")
		)
		(fp_rect
			(start -1.0922 2.3114)
			(end 1.0922 -2.3114)
			(stroke
				(width 0)
				(type default)
			)
			(fill no)
			(layer "F.CrtYd")
		)
		(fp_poly
			(pts
				(xy 1.0922 -2.3114) (xy 1.0922 2.3114) (xy -1.0922 2.3114) (xy -1.0922 -2.3114)
			)
			(stroke
				(width 0)
				(type default)
			)
			(fill no)
			(layer "F.Fab")
		)
		(pad "1" smd rect
			(at 0 -1.397 180)
			(size 1.651 1.27)
			(layers "F.Cu" "F.Mask" "F.Paste")
			(net "P12V_HDD10")
		)
		(pad "2" smd rect
			(at 0 1.397 180)
			(size 1.651 1.27)
			(layers "F.Cu" "F.Mask" "F.Paste")
			(net "GND")
		)
	)
	(footprint ""
		(layer "F.Cu")
		(at 197.911974 -389.100822 -90)
		(property "Reference" "R429"
			(at 0 0 270)
			(layer "F.SilkS")
			(hide yes)
			(effects
				(font
					(size 1.27 1.27)
				)
			)
		)
		(property "Value" "4K7R2J-2-GP"
			(at 0.064008 -3.993896 270)
			(unlocked yes)
			(layer "F.Fab")
			(hide yes)
			(effects
				(font
					(size 1.016 1.016)
					(thickness 0.1524)
				)
			)
		)
		(property "Device Type" "R402H16"
			(at 0.064008 -5.517896 270)
			(unlocked yes)
			(layer "F.Fab")
			(hide yes)
			(effects
				(font
					(size 1.016 1.016)
					(thickness 0.1524)
				)
			)
		)
		(duplicate_pad_numbers_are_jumpers no)
		(fp_line
			(start -0.508 -0.9398)
			(end -0.508 0.9398)
			(stroke
				(width 0.1524)
				(type default)
			)
			(layer "F.SilkS")
		)
		(fp_line
			(start 0.508 -0.9398)
			(end -0.508 -0.9398)
			(stroke
				(width 0.1524)
				(type default)
			)
			(layer "F.SilkS")
		)
		(fp_rect
			(start -0.508 0.9398)
			(end 0.508 -0.9398)
			(stroke
				(width 0)
				(type default)
			)
			(fill no)
			(layer "F.CrtYd")
		)
		(fp_rect
			(start -0.508 0.9398)
			(end 0.508 -0.9398)
			(stroke
				(width 0)
				(type default)
			)
			(fill no)
			(layer "F.Fab")
		)
		(pad "1" smd custom
			(at 0 -0.4445 270)
			(size 0.1397 0.1397)
			(layers "F.Cu" "F.Mask" "F.Paste")
			(net "P3V3")
			(options
				(clearance outline)
				(anchor circle)
			)
			(primitives
				(gr_poly
					(pts
						(arc
							(start -0.1778 -0.2794)
							(mid -0.249642 -0.249642)
							(end -0.2794 -0.1778)
						)
						(arc
							(start -0.2794 0.1778)
							(mid -0.249642 0.249642)
							(end -0.1778 0.2794)
						)
						(arc
							(start 0.1778 0.2794)
							(mid 0.249642 0.249642)
							(end 0.2794 0.1778)
						)
						(arc
							(start 0.2794 -0.1778)
							(mid 0.249642 -0.249642)
							(end 0.1778 -0.2794)
						)
					)
					(width 0)
					(fill yes)
				)
			)
		)
		(pad "2" smd custom
			(at 0 0.4445 270)
			(size 0.1397 0.1397)
			(layers "F.Cu" "F.Mask" "F.Paste")
			(net "SAS_EXP_A_PWR1")
			(options
				(clearance outline)
				(anchor circle)
			)
			(primitives
				(gr_poly
					(pts
						(arc
							(start -0.1778 -0.2794)
							(mid -0.249642 -0.249642)
							(end -0.2794 -0.1778)
						)
						(arc
							(start -0.2794 0.1778)
							(mid -0.249642 0.249642)
							(end -0.1778 0.2794)
						)
						(arc
							(start 0.1778 0.2794)
							(mid 0.249642 0.249642)
							(end 0.2794 0.1778)
						)
						(arc
							(start 0.2794 -0.1778)
							(mid 0.249642 -0.249642)
							(end 0.1778 -0.2794)
						)
					)
					(width 0)
					(fill yes)
				)
			)
		)
	)
	(footprint ""
		(layer "F.Cu")
		(at 12.725146 -55.1434 90)
		(property "Reference" "R504"
			(at 0 0 90)
			(layer "F.SilkS")
			(hide yes)
			(effects
				(font
					(size 1.27 1.27)
				)
			)
		)
		(property "Value" "1KR2F-3-GP"
			(at 0.064008 -3.993896 90)
			(unlocked yes)
			(layer "F.Fab")
			(hide yes)
			(effects
				(font
					(size 1.016 1.016)
					(thickness 0.1524)
				)
			)
		)
		(property "Device Type" "R402H16"
			(at 0.064008 -5.517896 90)
			(unlocked yes)
			(layer "F.Fab")
			(hide yes)
			(effects
				(font
					(size 1.016 1.016)
					(thickness 0.1524)
				)
			)
		)
		(duplicate_pad_numbers_are_jumpers no)
		(fp_line
			(start 0.508 -0.9398)
			(end -0.508 -0.9398)
			(stroke
				(width 0.1524)
				(type default)
			)
			(layer "F.SilkS")
		)
		(fp_line
			(start -0.508 -0.9398)
			(end -0.508 0.9398)
			(stroke
				(width 0.1524)
				(type default)
			)
			(layer "F.SilkS")
		)
		(fp_rect
			(start -0.508 0.9398)
			(end 0.508 -0.9398)
			(stroke
				(width 0)
				(type default)
			)
			(fill no)
			(layer "F.CrtYd")
		)
		(fp_rect
			(start -0.508 0.9398)
			(end 0.508 -0.9398)
			(stroke
				(width 0)
				(type default)
			)
			(fill no)
			(layer "F.Fab")
		)
		(pad "1" smd custom
			(at 0 -0.4445 90)
			(size 0.1397 0.1397)
			(layers "F.Cu" "F.Mask" "F.Paste")
			(net "FLT_HDD14_B")
			(options
				(clearance outline)
				(anchor circle)
			)
			(primitives
				(gr_poly
					(pts
						(arc
							(start -0.1778 -0.2794)
							(mid -0.249642 -0.249642)
							(end -0.2794 -0.1778)
						)
						(arc
							(start -0.2794 0.1778)
							(mid -0.249642 0.249642)
							(end -0.1778 0.2794)
						)
						(arc
							(start 0.1778 0.2794)
							(mid 0.249642 0.249642)
							(end 0.2794 0.1778)
						)
						(arc
							(start 0.2794 -0.1778)
							(mid 0.249642 -0.249642)
							(end 0.1778 -0.2794)
						)
					)
					(width 0)
					(fill yes)
				)
			)
		)
		(pad "2" smd custom
			(at 0 0.4445 90)
			(size 0.1397 0.1397)
			(layers "F.Cu" "F.Mask" "F.Paste")
			(net "FLT_HDD14_DRIVE")
			(options
				(clearance outline)
				(anchor circle)
			)
			(primitives
				(gr_poly
					(pts
						(arc
							(start -0.1778 -0.2794)
							(mid -0.249642 -0.249642)
							(end -0.2794 -0.1778)
						)
						(arc
							(start -0.2794 0.1778)
							(mid -0.249642 0.249642)
							(end -0.1778 0.2794)
						)
						(arc
							(start 0.1778 0.2794)
							(mid 0.249642 0.249642)
							(end 0.2794 0.1778)
						)
						(arc
							(start 0.2794 -0.1778)
							(mid 0.249642 -0.249642)
							(end 0.1778 -0.2794)
						)
					)
					(width 0)
					(fill yes)
				)
			)
		)
	)
	(footprint ""
		(layer "F.Cu")
		(at 9.905746 -94.52864)
		(property "Reference" "TP6"
			(at 0 0 0)
			(layer "F.SilkS")
			(hide yes)
			(effects
				(font
					(size 1.27 1.27)
				)
			)
		)
		(property "Value" "TPAD32-GP"
			(at 0 -3.166364 0)
			(unlocked yes)
			(layer "F.Fab")
			(hide yes)
			(effects
				(font
					(size 1.016 1.016)
					(thickness 0.1524)
				)
			)
		)
		(property "Device Type" "TPAD32"
			(at 0 -4.690618 0)
			(unlocked yes)
			(layer "F.Fab")
			(hide yes)
			(effects
				(font
					(size 1.016 1.016)
					(thickness 0.1524)
				)
			)
		)
		(duplicate_pad_numbers_are_jumpers no)
		(fp_poly
			(pts
				(arc
					(start 0.4064 0)
					(mid -0.4064 0)
					(end 0.4064 0)
				)
			)
			(stroke
				(width 0)
				(type default)
			)
			(fill no)
			(layer "F.CrtYd")
		)
		(fp_poly
			(pts
				(arc
					(start 0.7112 0)
					(mid -0.7112 0)
					(end 0.7112 0)
				)
			)
			(stroke
				(width 0)
				(type default)
			)
			(fill no)
			(layer "F.Fab")
		)
		(pad "1" smd circle
			(at 0 0)
			(size 0.8128 0.8128)
			(layers "F.Cu" "F.Mask" "F.Paste")
			(net "SAS2X28_B_PRSNT15")
		)
	)
	(footprint ""
		(layer "F.Cu")
		(at 26.796746 -448.9577 90)
		(property "Reference" "C262"
			(at 0 0 90)
			(layer "F.SilkS")
			(hide yes)
			(effects
				(font
					(size 1.27 1.27)
				)
			)
		)
		(property "Value" "SCD01U50V2KX-1GP"
			(at 1.1811 -2.7051 90)
			(unlocked yes)
			(layer "F.Fab")
			(hide yes)
			(effects
				(font
					(size 1.016 1.016)
					(thickness 0.1524)
				)
			)
		)
		(property "Device Type" "C402H22"
			(at 1.1811 -4.2291 90)
			(unlocked yes)
			(layer "F.Fab")
			(hide yes)
			(effects
				(font
					(size 1.016 1.016)
					(thickness 0.1524)
				)
			)
		)
		(duplicate_pad_numbers_are_jumpers no)
		(fp_rect
			(start -0.4318 0.9525)
			(end 0.4318 -0.9525)
			(stroke
				(width 0)
				(type default)
			)
			(fill no)
			(layer "F.CrtYd")
		)
		(fp_rect
			(start -0.4318 0.9525)
			(end 0.4318 -0.9525)
			(stroke
				(width 0)
				(type default)
			)
			(fill no)
			(layer "F.Fab")
		)
		(pad "1" smd custom
			(at 0 -0.4445 90)
			(size 0.1524 0.1524)
			(layers "F.Cu" "F.Mask" "F.Paste")
			(net "SAS2X28_DRIVE_RX_N_A10")
			(options
				(clearance outline)
				(anchor circle)
			)
			(primitives
				(gr_poly
					(pts
						(arc
							(start 0.3048 -0.2032)
							(mid 0.275042 -0.275042)
							(end 0.2032 -0.3048)
						)
						(arc
							(start -0.2032 -0.3048)
							(mid -0.275042 -0.275042)
							(end -0.3048 -0.2032)
						)
						(arc
							(start -0.3048 0.2032)
							(mid -0.275042 0.275042)
							(end -0.2032 0.3048)
						)
						(arc
							(start 0.2032 0.3048)
							(mid 0.275042 0.275042)
							(end 0.3048 0.2032)
						)
					)
					(width 0)
					(fill yes)
				)
			)
		)
		(pad "2" smd custom
			(at 0 0.4445 90)
			(size 0.1524 0.1524)
			(layers "F.Cu" "F.Mask" "F.Paste")
			(net "SAS2X28_A_HDD10_RX_-")
			(options
				(clearance outline)
				(anchor circle)
			)
			(primitives
				(gr_poly
					(pts
						(arc
							(start 0.3048 -0.2032)
							(mid 0.275042 -0.275042)
							(end 0.2032 -0.3048)
						)
						(arc
							(start -0.2032 -0.3048)
							(mid -0.275042 -0.275042)
							(end -0.3048 -0.2032)
						)
						(arc
							(start -0.3048 0.2032)
							(mid -0.275042 0.275042)
							(end -0.2032 0.3048)
						)
						(arc
							(start 0.2032 0.3048)
							(mid 0.275042 0.275042)
							(end 0.3048 0.2032)
						)
					)
					(width 0)
					(fill yes)
				)
			)
		)
	)
	(footprint ""
		(layer "F.Cu")
		(at 215.221058 -381.405384 -90)
		(property "Reference" "R121"
			(at 0 0 270)
			(layer "F.SilkS")
			(hide yes)
			(effects
				(font
					(size 1.27 1.27)
				)
			)
		)
		(property "Value" "2R2010J-1-GP"
			(at 0.254 -8.0772 270)
			(unlocked yes)
			(layer "F.Fab")
			(hide yes)
			(effects
				(font
					(size 1.016 1.016)
					(thickness 0.1524)
				)
			)
		)
		(property "Device Type" "R2010H28"
			(at 0.254 -9.6774 270)
			(unlocked yes)
			(layer "F.Fab")
			(hide yes)
			(effects
				(font
					(size 1.016 1.016)
					(thickness 0.1524)
				)
			)
		)
		(duplicate_pad_numbers_are_jumpers no)
		(fp_line
			(start -1.651 3.302)
			(end 1.651 3.302)
			(stroke
				(width 0.1524)
				(type default)
			)
			(layer "F.SilkS")
		)
		(fp_line
			(start 1.651 3.302)
			(end 1.651 -3.302)
			(stroke
				(width 0.1524)
				(type default)
			)
			(layer "F.SilkS")
		)
		(fp_line
			(start -1.651 -3.302)
			(end -1.651 3.302)
			(stroke
				(width 0.1524)
				(type default)
			)
			(layer "F.SilkS")
		)
		(fp_line
			(start 1.651 -3.302)
			(end -1.651 -3.302)
			(stroke
				(width 0.1524)
				(type default)
			)
			(layer "F.SilkS")
		)
		(fp_rect
			(start -1.7272 -3.3782)
			(end 1.7272 3.3782)
			(stroke
				(width 0)
				(type default)
			)
			(fill no)
			(layer "F.CrtYd")
		)
		(fp_poly
			(pts
				(xy 1.7272 3.3782) (xy 1.7272 -3.3782) (xy -1.7272 -3.3782) (xy -1.7272 3.3782)
			)
			(stroke
				(width 0)
				(type default)
			)
			(fill no)
			(layer "F.Fab")
		)
		(pad "1" smd rect
			(at 0 -2.3495 270)
			(size 2.794 1.143)
			(layers "F.Cu" "F.Mask" "F.Paste")
			(net "5V_PRE_1")
		)
		(pad "2" smd rect
			(at 0 2.3495 270)
			(size 2.794 1.143)
			(layers "F.Cu" "F.Mask" "F.Paste")
			(net "P5V_HDD1")
		)
	)
	(footprint ""
		(layer "F.Cu")
		(at 203.245974 -391.894822 -90)
		(property "Reference" "R427"
			(at 0 0 270)
			(layer "F.SilkS")
			(hide yes)
			(effects
				(font
					(size 1.27 1.27)
				)
			)
		)
		(property "Value" "4K7R2J-2-GP"
			(at 0.064008 -3.993896 270)
			(unlocked yes)
			(layer "F.Fab")
			(hide yes)
			(effects
				(font
					(size 1.016 1.016)
					(thickness 0.1524)
				)
			)
		)
		(property "Device Type" "R402H16"
			(at 0.064008 -5.517896 270)
			(unlocked yes)
			(layer "F.Fab")
			(hide yes)
			(effects
				(font
					(size 1.016 1.016)
					(thickness 0.1524)
				)
			)
		)
		(duplicate_pad_numbers_are_jumpers no)
		(fp_line
			(start -0.508 -0.9398)
			(end -0.508 0.9398)
			(stroke
				(width 0.1524)
				(type default)
			)
			(layer "F.SilkS")
		)
		(fp_line
			(start 0.508 -0.9398)
			(end -0.508 -0.9398)
			(stroke
				(width 0.1524)
				(type default)
			)
			(layer "F.SilkS")
		)
		(fp_rect
			(start -0.508 0.9398)
			(end 0.508 -0.9398)
			(stroke
				(width 0)
				(type default)
			)
			(fill no)
			(layer "F.CrtYd")
		)
		(fp_rect
			(start -0.508 0.9398)
			(end 0.508 -0.9398)
			(stroke
				(width 0)
				(type default)
			)
			(fill no)
			(layer "F.Fab")
		)
		(pad "1" smd custom
			(at 0 -0.4445 270)
			(size 0.1397 0.1397)
			(layers "F.Cu" "F.Mask" "F.Paste")
			(net "P3V3")
			(options
				(clearance outline)
				(anchor circle)
			)
			(primitives
				(gr_poly
					(pts
						(arc
							(start -0.1778 -0.2794)
							(mid -0.249642 -0.249642)
							(end -0.2794 -0.1778)
						)
						(arc
							(start -0.2794 0.1778)
							(mid -0.249642 0.249642)
							(end -0.1778 0.2794)
						)
						(arc
							(start 0.1778 0.2794)
							(mid 0.249642 0.249642)
							(end 0.2794 0.1778)
						)
						(arc
							(start 0.2794 -0.1778)
							(mid 0.249642 -0.249642)
							(end 0.1778 -0.2794)
						)
					)
					(width 0)
					(fill yes)
				)
			)
		)
		(pad "2" smd custom
			(at 0 0.4445 270)
			(size 0.1397 0.1397)
			(layers "F.Cu" "F.Mask" "F.Paste")
			(net "SAS2X28_A_HDD1_FLT")
			(options
				(clearance outline)
				(anchor circle)
			)
			(primitives
				(gr_poly
					(pts
						(arc
							(start -0.1778 -0.2794)
							(mid -0.249642 -0.249642)
							(end -0.2794 -0.1778)
						)
						(arc
							(start -0.2794 0.1778)
							(mid -0.249642 0.249642)
							(end -0.1778 0.2794)
						)
						(arc
							(start 0.1778 0.2794)
							(mid 0.249642 0.249642)
							(end 0.2794 0.1778)
						)
						(arc
							(start 0.2794 -0.1778)
							(mid 0.249642 -0.249642)
							(end 0.1778 -0.2794)
						)
					)
					(width 0)
					(fill yes)
				)
			)
		)
	)
	(footprint ""
		(layer "F.Cu")
		(at 207.391 -72.263)
		(property "Reference" "C368"
			(at 0 0 0)
			(layer "F.SilkS")
			(hide yes)
			(effects
				(font
					(size 1.27 1.27)
				)
			)
		)
		(property "Value" "SCD033U25V2KX-GP"
			(at 1.1811 -2.7051 0)
			(unlocked yes)
			(layer "F.Fab")
			(hide yes)
			(effects
				(font
					(size 1.016 1.016)
					(thickness 0.1524)
				)
			)
		)
		(property "Device Type" "C402H22"
			(at 1.1811 -4.2291 0)
			(unlocked yes)
			(layer "F.Fab")
			(hide yes)
			(effects
				(font
					(size 1.016 1.016)
					(thickness 0.1524)
				)
			)
		)
		(duplicate_pad_numbers_are_jumpers no)
		(fp_rect
			(start -0.4318 0.9525)
			(end 0.4318 -0.9525)
			(stroke
				(width 0)
				(type default)
			)
			(fill no)
			(layer "F.CrtYd")
		)
		(fp_rect
			(start -0.4318 0.9525)
			(end 0.4318 -0.9525)
			(stroke
				(width 0)
				(type default)
			)
			(fill no)
			(layer "F.Fab")
		)
		(pad "1" smd custom
			(at 0 -0.4445)
			(size 0.1524 0.1524)
			(layers "F.Cu" "F.Mask" "F.Paste")
			(net "SW_HDD4_P")
			(options
				(clearance outline)
				(anchor circle)
			)
			(primitives
				(gr_poly
					(pts
						(arc
							(start 0.3048 -0.2032)
							(mid 0.275042 -0.275042)
							(end 0.2032 -0.3048)
						)
						(arc
							(start -0.2032 -0.3048)
							(mid -0.275042 -0.275042)
							(end -0.3048 -0.2032)
						)
						(arc
							(start -0.3048 0.2032)
							(mid -0.275042 0.275042)
							(end -0.2032 0.3048)
						)
						(arc
							(start 0.2032 0.3048)
							(mid 0.275042 0.275042)
							(end 0.3048 0.2032)
						)
					)
					(width 0)
					(fill yes)
				)
			)
		)
		(pad "2" smd custom
			(at 0 0.4445)
			(size 0.1524 0.1524)
			(layers "F.Cu" "F.Mask" "F.Paste")
			(net "GND")
			(options
				(clearance outline)
				(anchor circle)
			)
			(primitives
				(gr_poly
					(pts
						(arc
							(start 0.3048 -0.2032)
							(mid 0.275042 -0.275042)
							(end 0.2032 -0.3048)
						)
						(arc
							(start -0.2032 -0.3048)
							(mid -0.275042 -0.275042)
							(end -0.3048 -0.2032)
						)
						(arc
							(start -0.3048 0.2032)
							(mid -0.275042 0.275042)
							(end -0.2032 0.3048)
						)
						(arc
							(start 0.2032 0.3048)
							(mid 0.275042 0.275042)
							(end 0.3048 0.2032)
						)
					)
					(width 0)
					(fill yes)
				)
			)
		)
	)
	(footprint ""
		(layer "F.Cu")
		(at 24.637746 -414.5407)
		(property "Reference" "TP35"
			(at 0 0 0)
			(layer "F.SilkS")
			(hide yes)
			(effects
				(font
					(size 1.27 1.27)
				)
			)
		)
		(property "Value" "TPAD32-GP"
			(at 0 -3.166364 0)
			(unlocked yes)
			(layer "F.Fab")
			(hide yes)
			(effects
				(font
					(size 1.016 1.016)
					(thickness 0.1524)
				)
			)
		)
		(property "Device Type" "TPAD32"
			(at 0 -4.690618 0)
			(unlocked yes)
			(layer "F.Fab")
			(hide yes)
			(effects
				(font
					(size 1.016 1.016)
					(thickness 0.1524)
				)
			)
		)
		(duplicate_pad_numbers_are_jumpers no)
		(fp_poly
			(pts
				(arc
					(start 0.4064 0)
					(mid -0.4064 0)
					(end 0.4064 0)
				)
			)
			(stroke
				(width 0)
				(type default)
			)
			(fill no)
			(layer "F.CrtYd")
		)
		(fp_poly
			(pts
				(arc
					(start 0.7112 0)
					(mid -0.7112 0)
					(end 0.7112 0)
				)
			)
			(stroke
				(width 0)
				(type default)
			)
			(fill no)
			(layer "F.Fab")
		)
		(pad "1" smd circle
			(at 0 0)
			(size 0.8128 0.8128)
			(layers "F.Cu" "F.Mask" "F.Paste")
			(net "ACT_HDD10")
		)
	)
	(footprint ""
		(layer "F.Cu")
		(at 217.854784 -160.117028 -90)
		(property "Reference" "C150"
			(at 0 0 270)
			(layer "F.SilkS")
			(hide yes)
			(effects
				(font
					(size 1.27 1.27)
				)
			)
		)
		(property "Value" "SCD01U50V2KX-1GP"
			(at 1.1811 -2.7051 270)
			(unlocked yes)
			(layer "F.Fab")
			(hide yes)
			(effects
				(font
					(size 1.016 1.016)
					(thickness 0.1524)
				)
			)
		)
		(property "Device Type" "C402H22"
			(at 1.1811 -4.2291 270)
			(unlocked yes)
			(layer "F.Fab")
			(hide yes)
			(effects
				(font
					(size 1.016 1.016)
					(thickness 0.1524)
				)
			)
		)
		(duplicate_pad_numbers_are_jumpers no)
		(fp_rect
			(start -0.4318 0.9525)
			(end 0.4318 -0.9525)
			(stroke
				(width 0)
				(type default)
			)
			(fill no)
			(layer "F.CrtYd")
		)
		(fp_rect
			(start -0.4318 0.9525)
			(end 0.4318 -0.9525)
			(stroke
				(width 0)
				(type default)
			)
			(fill no)
			(layer "F.Fab")
		)
		(pad "1" smd custom
			(at 0 -0.4445 270)
			(size 0.1524 0.1524)
			(layers "F.Cu" "F.Mask" "F.Paste")
			(net "SAS2X28_DRIVE_RX_N_A3")
			(options
				(clearance outline)
				(anchor circle)
			)
			(primitives
				(gr_poly
					(pts
						(arc
							(start 0.3048 -0.2032)
							(mid 0.275042 -0.275042)
							(end 0.2032 -0.3048)
						)
						(arc
							(start -0.2032 -0.3048)
							(mid -0.275042 -0.275042)
							(end -0.3048 -0.2032)
						)
						(arc
							(start -0.3048 0.2032)
							(mid -0.275042 0.275042)
							(end -0.2032 0.3048)
						)
						(arc
							(start 0.2032 0.3048)
							(mid 0.275042 0.275042)
							(end 0.3048 0.2032)
						)
					)
					(width 0)
					(fill yes)
				)
			)
		)
		(pad "2" smd custom
			(at 0 0.4445 270)
			(size 0.1524 0.1524)
			(layers "F.Cu" "F.Mask" "F.Paste")
			(net "SAS2X28_A_HDD3_RX_-")
			(options
				(clearance outline)
				(anchor circle)
			)
			(primitives
				(gr_poly
					(pts
						(arc
							(start 0.3048 -0.2032)
							(mid 0.275042 -0.275042)
							(end 0.2032 -0.3048)
						)
						(arc
							(start -0.2032 -0.3048)
							(mid -0.275042 -0.275042)
							(end -0.3048 -0.2032)
						)
						(arc
							(start -0.3048 0.2032)
							(mid -0.275042 0.275042)
							(end -0.2032 0.3048)
						)
						(arc
							(start 0.2032 0.3048)
							(mid 0.275042 0.275042)
							(end 0.3048 0.2032)
						)
					)
					(width 0)
					(fill yes)
				)
			)
		)
	)
	(footprint ""
		(layer "F.Cu")
		(at 80.390746 -395.4907 -90)
		(property "Reference" "U21"
			(at 0 0 270)
			(layer "F.SilkS")
			(hide yes)
			(effects
				(font
					(size 1.27 1.27)
				)
			)
		)
		(property "Value" "74LVC1G08GW-1-GP"
			(at -2.3368 -8.6868 270)
			(unlocked yes)
			(layer "F.Fab")
			(hide yes)
			(effects
				(font
					(size 1.016 1.016)
					(thickness 0.1524)
				)
			)
		)
		(property "Device Type" "SC70-5H44"
			(at -2.3114 -10.414 270)
			(unlocked yes)
			(layer "F.Fab")
			(hide yes)
			(effects
				(font
					(size 1.016 1.016)
					(thickness 0.1524)
				)
			)
		)
		(duplicate_pad_numbers_are_jumpers no)
		(fp_line
			(start -1.27 1.7018)
			(end -1.27 -1.7018)
			(stroke
				(width 0.1524)
				(type default)
			)
			(layer "F.SilkS")
		)
		(fp_line
			(start 1.27 1.7018)
			(end -1.27 1.7018)
			(stroke
				(width 0.1524)
				(type default)
			)
			(layer "F.SilkS")
		)
		(fp_line
			(start -1.27 -1.7018)
			(end 1.27 -1.7018)
			(stroke
				(width 0.1524)
				(type default)
			)
			(layer "F.SilkS")
		)
		(fp_line
			(start 1.27 -1.7018)
			(end 1.27 1.7018)
			(stroke
				(width 0.1524)
				(type default)
			)
			(layer "F.SilkS")
		)
		(fp_line
			(start 0.6604 -1.8034)
			(end 1.3843 -1.8034)
			(stroke
				(width 0.3302)
				(type default)
			)
			(layer "F.SilkS")
		)
		(fp_line
			(start 1.3843 -1.8034)
			(end 1.3843 -1.1176)
			(stroke
				(width 0.3302)
				(type default)
			)
			(layer "F.SilkS")
		)
		(fp_rect
			(start -1.524 1.9558)
			(end 1.524 -1.9558)
			(stroke
				(width 0)
				(type default)
			)
			(fill no)
			(layer "F.CrtYd")
		)
		(fp_poly
			(pts
				(xy -1.524 -1.9558) (xy 1.524 -1.9558) (xy 1.524 1.9558) (xy -1.524 1.9558)
			)
			(stroke
				(width 0)
				(type default)
			)
			(fill no)
			(layer "F.Fab")
		)
		(pad "1" smd rect
			(at 0.65024 -0.8255 270)
			(size 0.4064 1.2192)
			(layers "F.Cu" "F.Mask" "F.Paste")
			(net "SAS_EXP_B_PWR6")
		)
		(pad "2" smd rect
			(at 0 -0.8255 270)
			(size 0.4064 1.2192)
			(layers "F.Cu" "F.Mask" "F.Paste")
			(net "SAS_EXP_A_PWR6")
		)
		(pad "3" smd rect
			(at -0.65024 -0.8255 270)
			(size 0.4064 1.2192)
			(layers "F.Cu" "F.Mask" "F.Paste")
			(net "GND")
		)
		(pad "4" smd rect
			(at -0.65024 0.8255 270)
			(size 0.4064 1.2192)
			(layers "F.Cu" "F.Mask" "F.Paste")
			(net "DRIVE_PWR6")
		)
		(pad "5" smd rect
			(at 0.65024 0.8255 270)
			(size 0.4064 1.2192)
			(layers "F.Cu" "F.Mask" "F.Paste")
			(net "P3V3")
		)
	)
	(footprint ""
		(layer "F.Cu")
		(at 47.243746 -126.5301)
		(property "Reference" "R506"
			(at 0 0 0)
			(layer "F.SilkS")
			(hide yes)
			(effects
				(font
					(size 1.27 1.27)
				)
			)
		)
		(property "Value" "4K7R2J-2-GP"
			(at 0.064008 -3.993896 0)
			(unlocked yes)
			(layer "F.Fab")
			(hide yes)
			(effects
				(font
					(size 1.016 1.016)
					(thickness 0.1524)
				)
			)
		)
		(property "Device Type" "R402H16"
			(at 0.064008 -5.517896 0)
			(unlocked yes)
			(layer "F.Fab")
			(hide yes)
			(effects
				(font
					(size 1.016 1.016)
					(thickness 0.1524)
				)
			)
		)
		(duplicate_pad_numbers_are_jumpers no)
		(fp_line
			(start -0.508 -0.9398)
			(end -0.508 0.9398)
			(stroke
				(width 0.1524)
				(type default)
			)
			(layer "F.SilkS")
		)
		(fp_line
			(start 0.508 -0.9398)
			(end -0.508 -0.9398)
			(stroke
				(width 0.1524)
				(type default)
			)
			(layer "F.SilkS")
		)
		(fp_rect
			(start -0.508 0.9398)
			(end 0.508 -0.9398)
			(stroke
				(width 0)
				(type default)
			)
			(fill no)
			(layer "F.CrtYd")
		)
		(fp_rect
			(start -0.508 0.9398)
			(end 0.508 -0.9398)
			(stroke
				(width 0)
				(type default)
			)
			(fill no)
			(layer "F.Fab")
		)
		(pad "1" smd custom
			(at 0 -0.4445)
			(size 0.1397 0.1397)
			(layers "F.Cu" "F.Mask" "F.Paste")
			(net "P3V3")
			(options
				(clearance outline)
				(anchor circle)
			)
			(primitives
				(gr_poly
					(pts
						(arc
							(start -0.1778 -0.2794)
							(mid -0.249642 -0.249642)
							(end -0.2794 -0.1778)
						)
						(arc
							(start -0.2794 0.1778)
							(mid -0.249642 0.249642)
							(end -0.1778 0.2794)
						)
						(arc
							(start 0.1778 0.2794)
							(mid 0.249642 0.249642)
							(end 0.2794 0.1778)
						)
						(arc
							(start 0.2794 -0.1778)
							(mid 0.249642 -0.249642)
							(end 0.1778 -0.2794)
						)
					)
					(width 0)
					(fill yes)
				)
			)
		)
		(pad "2" smd custom
			(at 0 0.4445)
			(size 0.1397 0.1397)
			(layers "F.Cu" "F.Mask" "F.Paste")
			(net "SAS2X28_B_HDD13_FLT")
			(options
				(clearance outline)
				(anchor circle)
			)
			(primitives
				(gr_poly
					(pts
						(arc
							(start -0.1778 -0.2794)
							(mid -0.249642 -0.249642)
							(end -0.2794 -0.1778)
						)
						(arc
							(start -0.2794 0.1778)
							(mid -0.249642 0.249642)
							(end -0.1778 0.2794)
						)
						(arc
							(start 0.1778 0.2794)
							(mid 0.249642 0.249642)
							(end 0.2794 0.1778)
						)
						(arc
							(start 0.2794 -0.1778)
							(mid 0.249642 -0.249642)
							(end 0.1778 -0.2794)
						)
					)
					(width 0)
					(fill yes)
				)
			)
		)
	)
	(footprint ""
		(layer "F.Cu")
		(at 7.112 -23.622 180)
		(property "Reference" "R607"
			(at 0 0 180)
			(layer "F.SilkS")
			(hide yes)
			(effects
				(font
					(size 1.27 1.27)
				)
			)
		)
		(property "Value" "2R2010J-1-GP"
			(at 0.254 -8.0772 180)
			(unlocked yes)
			(layer "F.Fab")
			(hide yes)
			(effects
				(font
					(size 1.016 1.016)
					(thickness 0.1524)
				)
			)
		)
		(property "Device Type" "R2010H28"
			(at 0.254 -9.6774 180)
			(unlocked yes)
			(layer "F.Fab")
			(hide yes)
			(effects
				(font
					(size 1.016 1.016)
					(thickness 0.1524)
				)
			)
		)
		(duplicate_pad_numbers_are_jumpers no)
		(fp_line
			(start 1.651 3.302)
			(end 1.651 -3.302)
			(stroke
				(width 0.1524)
				(type default)
			)
			(layer "F.SilkS")
		)
		(fp_line
			(start 1.651 -3.302)
			(end -1.651 -3.302)
			(stroke
				(width 0.1524)
				(type default)
			)
			(layer "F.SilkS")
		)
		(fp_line
			(start -1.651 3.302)
			(end 1.651 3.302)
			(stroke
				(width 0.1524)
				(type default)
			)
			(layer "F.SilkS")
		)
		(fp_line
			(start -1.651 -3.302)
			(end -1.651 3.302)
			(stroke
				(width 0.1524)
				(type default)
			)
			(layer "F.SilkS")
		)
		(fp_rect
			(start -1.7272 -3.3782)
			(end 1.7272 3.3782)
			(stroke
				(width 0)
				(type default)
			)
			(fill no)
			(layer "F.CrtYd")
		)
		(fp_poly
			(pts
				(xy 1.7272 3.3782) (xy 1.7272 -3.3782) (xy -1.7272 -3.3782) (xy -1.7272 3.3782)
			)
			(stroke
				(width 0)
				(type default)
			)
			(fill no)
			(layer "F.Fab")
		)
		(pad "1" smd rect
			(at 0 -2.3495 180)
			(size 2.794 1.143)
			(layers "F.Cu" "F.Mask" "F.Paste")
			(net "GND")
		)
		(pad "2" smd rect
			(at 0 2.3495 180)
			(size 2.794 1.143)
			(layers "F.Cu" "F.Mask" "F.Paste")
			(net "PRSNT_B")
		)
	)
	(footprint ""
		(layer "F.Cu")
		(at 14.922246 -164.715698 90)
		(property "Reference" "R286"
			(at 0 0 90)
			(layer "F.SilkS")
			(hide yes)
			(effects
				(font
					(size 1.27 1.27)
				)
			)
		)
		(property "Value" "0R2J-2-GP"
			(at 0.064008 -3.993896 90)
			(unlocked yes)
			(layer "F.Fab")
			(hide yes)
			(effects
				(font
					(size 1.016 1.016)
					(thickness 0.1524)
				)
			)
		)
		(property "Device Type" "R402H16"
			(at 0.064008 -5.517896 90)
			(unlocked yes)
			(layer "F.Fab")
			(hide yes)
			(effects
				(font
					(size 1.016 1.016)
					(thickness 0.1524)
				)
			)
		)
		(duplicate_pad_numbers_are_jumpers no)
		(fp_line
			(start 0.508 -0.9398)
			(end -0.508 -0.9398)
			(stroke
				(width 0.1524)
				(type default)
			)
			(layer "F.SilkS")
		)
		(fp_line
			(start -0.508 -0.9398)
			(end -0.508 0.9398)
			(stroke
				(width 0.1524)
				(type default)
			)
			(layer "F.SilkS")
		)
		(fp_rect
			(start -0.508 0.9398)
			(end 0.508 -0.9398)
			(stroke
				(width 0)
				(type default)
			)
			(fill no)
			(layer "F.CrtYd")
		)
		(fp_rect
			(start -0.508 0.9398)
			(end 0.508 -0.9398)
			(stroke
				(width 0)
				(type default)
			)
			(fill no)
			(layer "F.Fab")
		)
		(pad "1" smd custom
			(at 0 -0.4445 90)
			(size 0.1397 0.1397)
			(layers "F.Cu" "F.Mask" "F.Paste")
			(net "FLT_NET_HDD13")
			(options
				(clearance outline)
				(anchor circle)
			)
			(primitives
				(gr_poly
					(pts
						(arc
							(start -0.1778 -0.2794)
							(mid -0.249642 -0.249642)
							(end -0.2794 -0.1778)
						)
						(arc
							(start -0.2794 0.1778)
							(mid -0.249642 0.249642)
							(end -0.1778 0.2794)
						)
						(arc
							(start 0.1778 0.2794)
							(mid 0.249642 0.249642)
							(end 0.2794 0.1778)
						)
						(arc
							(start 0.2794 -0.1778)
							(mid 0.249642 -0.249642)
							(end 0.1778 -0.2794)
						)
					)
					(width 0)
					(fill yes)
				)
			)
		)
		(pad "2" smd custom
			(at 0 0.4445 90)
			(size 0.1397 0.1397)
			(layers "F.Cu" "F.Mask" "F.Paste")
			(net "FLT_HDD13_DRIVE")
			(options
				(clearance outline)
				(anchor circle)
			)
			(primitives
				(gr_poly
					(pts
						(arc
							(start -0.1778 -0.2794)
							(mid -0.249642 -0.249642)
							(end -0.2794 -0.1778)
						)
						(arc
							(start -0.2794 0.1778)
							(mid -0.249642 0.249642)
							(end -0.1778 0.2794)
						)
						(arc
							(start 0.1778 0.2794)
							(mid 0.249642 0.249642)
							(end 0.2794 0.1778)
						)
						(arc
							(start 0.2794 -0.1778)
							(mid 0.249642 -0.249642)
							(end 0.1778 -0.2794)
						)
					)
					(width 0)
					(fill yes)
				)
			)
		)
	)
	(footprint ""
		(layer "F.Cu")
		(at 60.3758 -497.6114 180)
		(property "Reference" "C194"
			(at 0 0 180)
			(layer "F.SilkS")
			(hide yes)
			(effects
				(font
					(size 1.27 1.27)
				)
			)
		)
		(property "Value" "SC10U25V6KX-1GP"
			(at -0.0762 -5.1308 180)
			(unlocked yes)
			(layer "F.Fab")
			(hide yes)
			(effects
				(font
					(size 1.016 1.016)
					(thickness 0.1524)
				)
			)
		)
		(property "Device Type" "C1206H71"
			(at -0.127 -6.6548 180)
			(unlocked yes)
			(layer "F.Fab")
			(hide yes)
			(effects
				(font
					(size 1.016 1.016)
					(thickness 0.1524)
				)
			)
		)
		(duplicate_pad_numbers_are_jumpers no)
		(fp_line
			(start 1.016 2.2352)
			(end -1.016 2.2352)
			(stroke
				(width 0.1524)
				(type default)
			)
			(layer "F.SilkS")
		)
		(fp_line
			(start 1.016 0.8382)
			(end 1.016 2.2352)
			(stroke
				(width 0.1524)
				(type default)
			)
			(layer "F.SilkS")
		)
		(fp_line
			(start 1.016 -2.2352)
			(end 1.016 -0.8382)
			(stroke
				(width 0.1524)
				(type default)
			)
			(layer "F.SilkS")
		)
		(fp_line
			(start -1.016 2.2352)
			(end -1.016 0.8382)
			(stroke
				(width 0.1524)
				(type default)
			)
			(layer "F.SilkS")
		)
		(fp_line
			(start -1.016 -0.8382)
			(end -1.016 -2.2352)
			(stroke
				(width 0.1524)
				(type default)
			)
			(layer "F.SilkS")
		)
		(fp_line
			(start -1.016 -2.2352)
			(end 1.016 -2.2352)
			(stroke
				(width 0.1524)
				(type default)
			)
			(layer "F.SilkS")
		)
		(fp_rect
			(start -1.0922 2.3114)
			(end 1.0922 -2.3114)
			(stroke
				(width 0)
				(type default)
			)
			(fill no)
			(layer "F.CrtYd")
		)
		(fp_poly
			(pts
				(xy 1.0922 -2.3114) (xy 1.0922 2.3114) (xy -1.0922 2.3114) (xy -1.0922 -2.3114)
			)
			(stroke
				(width 0)
				(type default)
			)
			(fill no)
			(layer "F.Fab")
		)
		(pad "1" smd rect
			(at 0 -1.397 180)
			(size 1.651 1.27)
			(layers "F.Cu" "F.Mask" "F.Paste")
			(net "P12V_HDD5")
		)
		(pad "2" smd rect
			(at 0 1.397 180)
			(size 1.651 1.27)
			(layers "F.Cu" "F.Mask" "F.Paste")
			(net "GND")
		)
	)
	(footprint ""
		(layer "F.Cu")
		(at 210.312 -478.282 180)
		(property "Reference" "R342"
			(at 0 0 180)
			(layer "F.SilkS")
			(hide yes)
			(effects
				(font
					(size 1.27 1.27)
				)
			)
		)
		(property "Value" "10KR2F-2-GP"
			(at 0.064008 -3.993896 180)
			(unlocked yes)
			(layer "F.Fab")
			(hide yes)
			(effects
				(font
					(size 1.016 1.016)
					(thickness 0.1524)
				)
			)
		)
		(property "Device Type" "R402H16"
			(at 0.064008 -5.517896 180)
			(unlocked yes)
			(layer "F.Fab")
			(hide yes)
			(effects
				(font
					(size 1.016 1.016)
					(thickness 0.1524)
				)
			)
		)
		(duplicate_pad_numbers_are_jumpers no)
		(fp_line
			(start 0.508 -0.9398)
			(end -0.508 -0.9398)
			(stroke
				(width 0.1524)
				(type default)
			)
			(layer "F.SilkS")
		)
		(fp_line
			(start -0.508 -0.9398)
			(end -0.508 0.9398)
			(stroke
				(width 0.1524)
				(type default)
			)
			(layer "F.SilkS")
		)
		(fp_rect
			(start -0.508 0.9398)
			(end 0.508 -0.9398)
			(stroke
				(width 0)
				(type default)
			)
			(fill no)
			(layer "F.CrtYd")
		)
		(fp_rect
			(start -0.508 0.9398)
			(end 0.508 -0.9398)
			(stroke
				(width 0)
				(type default)
			)
			(fill no)
			(layer "F.Fab")
		)
		(pad "1" smd custom
			(at 0 -0.4445 180)
			(size 0.1397 0.1397)
			(layers "F.Cu" "F.Mask" "F.Paste")
			(net "P12V")
			(options
				(clearance outline)
				(anchor circle)
			)
			(primitives
				(gr_poly
					(pts
						(arc
							(start -0.1778 -0.2794)
							(mid -0.249642 -0.249642)
							(end -0.2794 -0.1778)
						)
						(arc
							(start -0.2794 0.1778)
							(mid -0.249642 0.249642)
							(end -0.1778 0.2794)
						)
						(arc
							(start 0.1778 0.2794)
							(mid 0.249642 0.249642)
							(end 0.2794 0.1778)
						)
						(arc
							(start 0.2794 -0.1778)
							(mid 0.249642 -0.249642)
							(end 0.1778 -0.2794)
						)
					)
					(width 0)
					(fill yes)
				)
			)
		)
		(pad "2" smd custom
			(at 0 0.4445 180)
			(size 0.1397 0.1397)
			(layers "F.Cu" "F.Mask" "F.Paste")
			(net "HDD0_LED_G")
			(options
				(clearance outline)
				(anchor circle)
			)
			(primitives
				(gr_poly
					(pts
						(arc
							(start -0.1778 -0.2794)
							(mid -0.249642 -0.249642)
							(end -0.2794 -0.1778)
						)
						(arc
							(start -0.2794 0.1778)
							(mid -0.249642 0.249642)
							(end -0.1778 0.2794)
						)
						(arc
							(start 0.1778 0.2794)
							(mid 0.249642 0.249642)
							(end 0.2794 0.1778)
						)
						(arc
							(start 0.2794 -0.1778)
							(mid 0.249642 -0.249642)
							(end 0.1778 -0.2794)
						)
					)
					(width 0)
					(fill yes)
				)
			)
		)
	)
	(footprint ""
		(layer "F.Cu")
		(at 191.897 -89.281 90)
		(property "Reference" "R165"
			(at 0 0 90)
			(layer "F.SilkS")
			(hide yes)
			(effects
				(font
					(size 1.27 1.27)
				)
			)
		)
		(property "Value" "4K7R2J-2-GP"
			(at 0.064008 -3.993896 90)
			(unlocked yes)
			(layer "F.Fab")
			(hide yes)
			(effects
				(font
					(size 1.016 1.016)
					(thickness 0.1524)
				)
			)
		)
		(property "Device Type" "R402H16"
			(at 0.064008 -5.517896 90)
			(unlocked yes)
			(layer "F.Fab")
			(hide yes)
			(effects
				(font
					(size 1.016 1.016)
					(thickness 0.1524)
				)
			)
		)
		(duplicate_pad_numbers_are_jumpers no)
		(fp_line
			(start 0.508 -0.9398)
			(end -0.508 -0.9398)
			(stroke
				(width 0.1524)
				(type default)
			)
			(layer "F.SilkS")
		)
		(fp_line
			(start -0.508 -0.9398)
			(end -0.508 0.9398)
			(stroke
				(width 0.1524)
				(type default)
			)
			(layer "F.SilkS")
		)
		(fp_rect
			(start -0.508 0.9398)
			(end 0.508 -0.9398)
			(stroke
				(width 0)
				(type default)
			)
			(fill no)
			(layer "F.CrtYd")
		)
		(fp_rect
			(start -0.508 0.9398)
			(end 0.508 -0.9398)
			(stroke
				(width 0)
				(type default)
			)
			(fill no)
			(layer "F.Fab")
		)
		(pad "1" smd custom
			(at 0 -0.4445 90)
			(size 0.1397 0.1397)
			(layers "F.Cu" "F.Mask" "F.Paste")
			(net "P12V")
			(options
				(clearance outline)
				(anchor circle)
			)
			(primitives
				(gr_poly
					(pts
						(arc
							(start -0.1778 -0.2794)
							(mid -0.249642 -0.249642)
							(end -0.2794 -0.1778)
						)
						(arc
							(start -0.2794 0.1778)
							(mid -0.249642 0.249642)
							(end -0.1778 0.2794)
						)
						(arc
							(start 0.1778 0.2794)
							(mid 0.249642 0.249642)
							(end 0.2794 0.1778)
						)
						(arc
							(start 0.2794 -0.1778)
							(mid 0.249642 -0.249642)
							(end 0.1778 -0.2794)
						)
					)
					(width 0)
					(fill yes)
				)
			)
		)
		(pad "2" smd custom
			(at 0 0.4445 90)
			(size 0.1397 0.1397)
			(layers "F.Cu" "F.Mask" "F.Paste")
			(net "SW_HDD4_R")
			(options
				(clearance outline)
				(anchor circle)
			)
			(primitives
				(gr_poly
					(pts
						(arc
							(start -0.1778 -0.2794)
							(mid -0.249642 -0.249642)
							(end -0.2794 -0.1778)
						)
						(arc
							(start -0.2794 0.1778)
							(mid -0.249642 0.249642)
							(end -0.1778 0.2794)
						)
						(arc
							(start 0.1778 0.2794)
							(mid 0.249642 0.249642)
							(end 0.2794 0.1778)
						)
						(arc
							(start 0.2794 -0.1778)
							(mid 0.249642 -0.249642)
							(end 0.1778 -0.2794)
						)
					)
					(width 0)
					(fill yes)
				)
			)
		)
	)
	(footprint ""
		(layer "F.Cu")
		(at 28.447746 -311.305702 180)
		(property "Reference" "R267"
			(at 0 0 180)
			(layer "F.SilkS")
			(hide yes)
			(effects
				(font
					(size 1.27 1.27)
				)
			)
		)
		(property "Value" "0R2J-2-GP"
			(at 0.064008 -3.993896 180)
			(unlocked yes)
			(layer "F.Fab")
			(hide yes)
			(effects
				(font
					(size 1.016 1.016)
					(thickness 0.1524)
				)
			)
		)
		(property "Device Type" "R402H16"
			(at 0.064008 -5.517896 180)
			(unlocked yes)
			(layer "F.Fab")
			(hide yes)
			(effects
				(font
					(size 1.016 1.016)
					(thickness 0.1524)
				)
			)
		)
		(duplicate_pad_numbers_are_jumpers no)
		(fp_line
			(start 0.508 -0.9398)
			(end -0.508 -0.9398)
			(stroke
				(width 0.1524)
				(type default)
			)
			(layer "F.SilkS")
		)
		(fp_line
			(start -0.508 -0.9398)
			(end -0.508 0.9398)
			(stroke
				(width 0.1524)
				(type default)
			)
			(layer "F.SilkS")
		)
		(fp_rect
			(start -0.508 0.9398)
			(end 0.508 -0.9398)
			(stroke
				(width 0)
				(type default)
			)
			(fill no)
			(layer "F.CrtYd")
		)
		(fp_rect
			(start -0.508 0.9398)
			(end 0.508 -0.9398)
			(stroke
				(width 0)
				(type default)
			)
			(fill no)
			(layer "F.Fab")
		)
		(pad "1" smd custom
			(at 0 -0.4445 180)
			(size 0.1397 0.1397)
			(layers "F.Cu" "F.Mask" "F.Paste")
			(net "DRIVE_PWR11")
			(options
				(clearance outline)
				(anchor circle)
			)
			(primitives
				(gr_poly
					(pts
						(arc
							(start -0.1778 -0.2794)
							(mid -0.249642 -0.249642)
							(end -0.2794 -0.1778)
						)
						(arc
							(start -0.2794 0.1778)
							(mid -0.249642 0.249642)
							(end -0.1778 0.2794)
						)
						(arc
							(start 0.1778 0.2794)
							(mid 0.249642 0.249642)
							(end 0.2794 0.1778)
						)
						(arc
							(start 0.2794 -0.1778)
							(mid 0.249642 -0.249642)
							(end 0.1778 -0.2794)
						)
					)
					(width 0)
					(fill yes)
				)
			)
		)
		(pad "2" smd custom
			(at 0 0.4445 180)
			(size 0.1397 0.1397)
			(layers "F.Cu" "F.Mask" "F.Paste")
			(net "SW_PWR_HDD11")
			(options
				(clearance outline)
				(anchor circle)
			)
			(primitives
				(gr_poly
					(pts
						(arc
							(start -0.1778 -0.2794)
							(mid -0.249642 -0.249642)
							(end -0.2794 -0.1778)
						)
						(arc
							(start -0.2794 0.1778)
							(mid -0.249642 0.249642)
							(end -0.1778 0.2794)
						)
						(arc
							(start 0.1778 0.2794)
							(mid 0.249642 0.249642)
							(end 0.2794 0.1778)
						)
						(arc
							(start 0.2794 -0.1778)
							(mid 0.249642 -0.249642)
							(end 0.1778 -0.2794)
						)
					)
					(width 0)
					(fill yes)
				)
			)
		)
	)
	(footprint ""
		(layer "F.Cu")
		(at 101.599746 -10.4267)
		(property "Reference" "R308"
			(at 0 0 0)
			(layer "F.SilkS")
			(hide yes)
			(effects
				(font
					(size 1.27 1.27)
				)
			)
		)
		(property "Value" "0R2J-2-GP"
			(at 0.064008 -3.993896 0)
			(unlocked yes)
			(layer "F.Fab")
			(hide yes)
			(effects
				(font
					(size 1.016 1.016)
					(thickness 0.1524)
				)
			)
		)
		(property "Device Type" "R402H16"
			(at 0.064008 -5.517896 0)
			(unlocked yes)
			(layer "F.Fab")
			(hide yes)
			(effects
				(font
					(size 1.016 1.016)
					(thickness 0.1524)
				)
			)
		)
		(duplicate_pad_numbers_are_jumpers no)
		(fp_line
			(start -0.508 -0.9398)
			(end -0.508 0.9398)
			(stroke
				(width 0.1524)
				(type default)
			)
			(layer "F.SilkS")
		)
		(fp_line
			(start 0.508 -0.9398)
			(end -0.508 -0.9398)
			(stroke
				(width 0.1524)
				(type default)
			)
			(layer "F.SilkS")
		)
		(fp_rect
			(start -0.508 0.9398)
			(end 0.508 -0.9398)
			(stroke
				(width 0)
				(type default)
			)
			(fill no)
			(layer "F.CrtYd")
		)
		(fp_rect
			(start -0.508 0.9398)
			(end 0.508 -0.9398)
			(stroke
				(width 0)
				(type default)
			)
			(fill no)
			(layer "F.Fab")
		)
		(pad "1" smd custom
			(at 0 -0.4445)
			(size 0.1397 0.1397)
			(layers "F.Cu" "F.Mask" "F.Paste")
			(net "SW_PWR_HDD14")
			(options
				(clearance outline)
				(anchor circle)
			)
			(primitives
				(gr_poly
					(pts
						(arc
							(start -0.1778 -0.2794)
							(mid -0.249642 -0.249642)
							(end -0.2794 -0.1778)
						)
						(arc
							(start -0.2794 0.1778)
							(mid -0.249642 0.249642)
							(end -0.1778 0.2794)
						)
						(arc
							(start 0.1778 0.2794)
							(mid 0.249642 0.249642)
							(end 0.2794 0.1778)
						)
						(arc
							(start 0.2794 -0.1778)
							(mid 0.249642 -0.249642)
							(end 0.1778 -0.2794)
						)
					)
					(width 0)
					(fill yes)
				)
			)
		)
		(pad "2" smd custom
			(at 0 0.4445)
			(size 0.1397 0.1397)
			(layers "F.Cu" "F.Mask" "F.Paste")
			(net "SW_PWR_R_HDD14")
			(options
				(clearance outline)
				(anchor circle)
			)
			(primitives
				(gr_poly
					(pts
						(arc
							(start -0.1778 -0.2794)
							(mid -0.249642 -0.249642)
							(end -0.2794 -0.1778)
						)
						(arc
							(start -0.2794 0.1778)
							(mid -0.249642 0.249642)
							(end -0.1778 0.2794)
						)
						(arc
							(start 0.1778 0.2794)
							(mid 0.249642 0.249642)
							(end 0.2794 0.1778)
						)
						(arc
							(start 0.2794 -0.1778)
							(mid 0.249642 -0.249642)
							(end 0.1778 -0.2794)
						)
					)
					(width 0)
					(fill yes)
				)
			)
		)
	)
	(footprint ""
		(layer "F.Cu")
		(at 46.202346 -126.5301)
		(property "Reference" "R505"
			(at 0 0 0)
			(layer "F.SilkS")
			(hide yes)
			(effects
				(font
					(size 1.27 1.27)
				)
			)
		)
		(property "Value" "4K7R2J-2-GP"
			(at 0.064008 -3.993896 0)
			(unlocked yes)
			(layer "F.Fab")
			(hide yes)
			(effects
				(font
					(size 1.016 1.016)
					(thickness 0.1524)
				)
			)
		)
		(property "Device Type" "R402H16"
			(at 0.064008 -5.517896 0)
			(unlocked yes)
			(layer "F.Fab")
			(hide yes)
			(effects
				(font
					(size 1.016 1.016)
					(thickness 0.1524)
				)
			)
		)
		(duplicate_pad_numbers_are_jumpers no)
		(fp_line
			(start -0.508 -0.9398)
			(end -0.508 0.9398)
			(stroke
				(width 0.1524)
				(type default)
			)
			(layer "F.SilkS")
		)
		(fp_line
			(start 0.508 -0.9398)
			(end -0.508 -0.9398)
			(stroke
				(width 0.1524)
				(type default)
			)
			(layer "F.SilkS")
		)
		(fp_rect
			(start -0.508 0.9398)
			(end 0.508 -0.9398)
			(stroke
				(width 0)
				(type default)
			)
			(fill no)
			(layer "F.CrtYd")
		)
		(fp_rect
			(start -0.508 0.9398)
			(end 0.508 -0.9398)
			(stroke
				(width 0)
				(type default)
			)
			(fill no)
			(layer "F.Fab")
		)
		(pad "1" smd custom
			(at 0 -0.4445)
			(size 0.1397 0.1397)
			(layers "F.Cu" "F.Mask" "F.Paste")
			(net "P3V3")
			(options
				(clearance outline)
				(anchor circle)
			)
			(primitives
				(gr_poly
					(pts
						(arc
							(start -0.1778 -0.2794)
							(mid -0.249642 -0.249642)
							(end -0.2794 -0.1778)
						)
						(arc
							(start -0.2794 0.1778)
							(mid -0.249642 0.249642)
							(end -0.1778 0.2794)
						)
						(arc
							(start 0.1778 0.2794)
							(mid 0.249642 0.249642)
							(end 0.2794 0.1778)
						)
						(arc
							(start 0.2794 -0.1778)
							(mid 0.249642 -0.249642)
							(end 0.1778 -0.2794)
						)
					)
					(width 0)
					(fill yes)
				)
			)
		)
		(pad "2" smd custom
			(at 0 0.4445)
			(size 0.1397 0.1397)
			(layers "F.Cu" "F.Mask" "F.Paste")
			(net "SAS2X28_A_HDD13_FLT")
			(options
				(clearance outline)
				(anchor circle)
			)
			(primitives
				(gr_poly
					(pts
						(arc
							(start -0.1778 -0.2794)
							(mid -0.249642 -0.249642)
							(end -0.2794 -0.1778)
						)
						(arc
							(start -0.2794 0.1778)
							(mid -0.249642 0.249642)
							(end -0.1778 0.2794)
						)
						(arc
							(start 0.1778 0.2794)
							(mid 0.249642 0.249642)
							(end 0.2794 0.1778)
						)
						(arc
							(start 0.2794 -0.1778)
							(mid 0.249642 -0.249642)
							(end 0.1778 -0.2794)
						)
					)
					(width 0)
					(fill yes)
				)
			)
		)
	)
	(footprint ""
		(layer "F.Cu")
		(at 77.977746 -87.2617 90)
		(property "Reference" "R238"
			(at 0 0 90)
			(layer "F.SilkS")
			(hide yes)
			(effects
				(font
					(size 1.27 1.27)
				)
			)
		)
		(property "Value" "0R2J-2-GP"
			(at 0.064008 -3.993896 90)
			(unlocked yes)
			(layer "F.Fab")
			(hide yes)
			(effects
				(font
					(size 1.016 1.016)
					(thickness 0.1524)
				)
			)
		)
		(property "Device Type" "R402H16"
			(at 0.064008 -5.517896 90)
			(unlocked yes)
			(layer "F.Fab")
			(hide yes)
			(effects
				(font
					(size 1.016 1.016)
					(thickness 0.1524)
				)
			)
		)
		(duplicate_pad_numbers_are_jumpers no)
		(fp_line
			(start 0.508 -0.9398)
			(end -0.508 -0.9398)
			(stroke
				(width 0.1524)
				(type default)
			)
			(layer "F.SilkS")
		)
		(fp_line
			(start -0.508 -0.9398)
			(end -0.508 0.9398)
			(stroke
				(width 0.1524)
				(type default)
			)
			(layer "F.SilkS")
		)
		(fp_rect
			(start -0.508 0.9398)
			(end 0.508 -0.9398)
			(stroke
				(width 0)
				(type default)
			)
			(fill no)
			(layer "F.CrtYd")
		)
		(fp_rect
			(start -0.508 0.9398)
			(end 0.508 -0.9398)
			(stroke
				(width 0)
				(type default)
			)
			(fill no)
			(layer "F.Fab")
		)
		(pad "1" smd custom
			(at 0 -0.4445 90)
			(size 0.1397 0.1397)
			(layers "F.Cu" "F.Mask" "F.Paste")
			(net "SW_PWR_HDD9")
			(options
				(clearance outline)
				(anchor circle)
			)
			(primitives
				(gr_poly
					(pts
						(arc
							(start -0.1778 -0.2794)
							(mid -0.249642 -0.249642)
							(end -0.2794 -0.1778)
						)
						(arc
							(start -0.2794 0.1778)
							(mid -0.249642 0.249642)
							(end -0.1778 0.2794)
						)
						(arc
							(start 0.1778 0.2794)
							(mid 0.249642 0.249642)
							(end 0.2794 0.1778)
						)
						(arc
							(start 0.2794 -0.1778)
							(mid 0.249642 -0.249642)
							(end 0.1778 -0.2794)
						)
					)
					(width 0)
					(fill yes)
				)
			)
		)
		(pad "2" smd custom
			(at 0 0.4445 90)
			(size 0.1397 0.1397)
			(layers "F.Cu" "F.Mask" "F.Paste")
			(net "SW_PWR_R_HDD9")
			(options
				(clearance outline)
				(anchor circle)
			)
			(primitives
				(gr_poly
					(pts
						(arc
							(start -0.1778 -0.2794)
							(mid -0.249642 -0.249642)
							(end -0.2794 -0.1778)
						)
						(arc
							(start -0.2794 0.1778)
							(mid -0.249642 0.249642)
							(end -0.1778 0.2794)
						)
						(arc
							(start 0.1778 0.2794)
							(mid 0.249642 0.249642)
							(end 0.2794 0.1778)
						)
						(arc
							(start 0.2794 -0.1778)
							(mid 0.249642 -0.249642)
							(end 0.1778 -0.2794)
						)
					)
					(width 0)
					(fill yes)
				)
			)
		)
	)
	(footprint ""
		(layer "F.Cu")
		(at 27.177746 -32.0167 90)
		(property "Reference" "C329"
			(at 0 0 90)
			(layer "F.SilkS")
			(hide yes)
			(effects
				(font
					(size 1.27 1.27)
				)
			)
		)
		(property "Value" "SCD01U50V2KX-1GP"
			(at 1.1811 -2.7051 90)
			(unlocked yes)
			(layer "F.Fab")
			(hide yes)
			(effects
				(font
					(size 1.016 1.016)
					(thickness 0.1524)
				)
			)
		)
		(property "Device Type" "C402H22"
			(at 1.1811 -4.2291 90)
			(unlocked yes)
			(layer "F.Fab")
			(hide yes)
			(effects
				(font
					(size 1.016 1.016)
					(thickness 0.1524)
				)
			)
		)
		(duplicate_pad_numbers_are_jumpers no)
		(fp_rect
			(start -0.4318 0.9525)
			(end 0.4318 -0.9525)
			(stroke
				(width 0)
				(type default)
			)
			(fill no)
			(layer "F.CrtYd")
		)
		(fp_rect
			(start -0.4318 0.9525)
			(end 0.4318 -0.9525)
			(stroke
				(width 0)
				(type default)
			)
			(fill no)
			(layer "F.Fab")
		)
		(pad "1" smd custom
			(at 0 -0.4445 90)
			(size 0.1524 0.1524)
			(layers "F.Cu" "F.Mask" "F.Paste")
			(net "SAS2X28_DRIVE_RX_P_B14")
			(options
				(clearance outline)
				(anchor circle)
			)
			(primitives
				(gr_poly
					(pts
						(arc
							(start 0.3048 -0.2032)
							(mid 0.275042 -0.275042)
							(end 0.2032 -0.3048)
						)
						(arc
							(start -0.2032 -0.3048)
							(mid -0.275042 -0.275042)
							(end -0.3048 -0.2032)
						)
						(arc
							(start -0.3048 0.2032)
							(mid -0.275042 0.275042)
							(end -0.2032 0.3048)
						)
						(arc
							(start 0.2032 0.3048)
							(mid 0.275042 0.275042)
							(end 0.3048 0.2032)
						)
					)
					(width 0)
					(fill yes)
				)
			)
		)
		(pad "2" smd custom
			(at 0 0.4445 90)
			(size 0.1524 0.1524)
			(layers "F.Cu" "F.Mask" "F.Paste")
			(net "SAS2X28_B_HDD14_RX_+")
			(options
				(clearance outline)
				(anchor circle)
			)
			(primitives
				(gr_poly
					(pts
						(arc
							(start 0.3048 -0.2032)
							(mid 0.275042 -0.275042)
							(end 0.2032 -0.3048)
						)
						(arc
							(start -0.2032 -0.3048)
							(mid -0.275042 -0.275042)
							(end -0.3048 -0.2032)
						)
						(arc
							(start -0.3048 0.2032)
							(mid -0.275042 0.275042)
							(end -0.2032 0.3048)
						)
						(arc
							(start 0.2032 0.3048)
							(mid 0.275042 0.275042)
							(end 0.3048 0.2032)
						)
					)
					(width 0)
					(fill yes)
				)
			)
		)
	)
	(footprint ""
		(layer "F.Cu")
		(at 42.290746 -205.895702 180)
		(property "Reference" "R471"
			(at 0 0 180)
			(layer "F.SilkS")
			(hide yes)
			(effects
				(font
					(size 1.27 1.27)
				)
			)
		)
		(property "Value" "4K7R2J-2-GP"
			(at 0.064008 -3.993896 180)
			(unlocked yes)
			(layer "F.Fab")
			(hide yes)
			(effects
				(font
					(size 1.016 1.016)
					(thickness 0.1524)
				)
			)
		)
		(property "Device Type" "R402H16"
			(at 0.064008 -5.517896 180)
			(unlocked yes)
			(layer "F.Fab")
			(hide yes)
			(effects
				(font
					(size 1.016 1.016)
					(thickness 0.1524)
				)
			)
		)
		(duplicate_pad_numbers_are_jumpers no)
		(fp_line
			(start 0.508 -0.9398)
			(end -0.508 -0.9398)
			(stroke
				(width 0.1524)
				(type default)
			)
			(layer "F.SilkS")
		)
		(fp_line
			(start -0.508 -0.9398)
			(end -0.508 0.9398)
			(stroke
				(width 0.1524)
				(type default)
			)
			(layer "F.SilkS")
		)
		(fp_rect
			(start -0.508 0.9398)
			(end 0.508 -0.9398)
			(stroke
				(width 0)
				(type default)
			)
			(fill no)
			(layer "F.CrtYd")
		)
		(fp_rect
			(start -0.508 0.9398)
			(end 0.508 -0.9398)
			(stroke
				(width 0)
				(type default)
			)
			(fill no)
			(layer "F.Fab")
		)
		(pad "1" smd custom
			(at 0 -0.4445 180)
			(size 0.1397 0.1397)
			(layers "F.Cu" "F.Mask" "F.Paste")
			(net "P3V3")
			(options
				(clearance outline)
				(anchor circle)
			)
			(primitives
				(gr_poly
					(pts
						(arc
							(start -0.1778 -0.2794)
							(mid -0.249642 -0.249642)
							(end -0.2794 -0.1778)
						)
						(arc
							(start -0.2794 0.1778)
							(mid -0.249642 0.249642)
							(end -0.1778 0.2794)
						)
						(arc
							(start 0.1778 0.2794)
							(mid 0.249642 0.249642)
							(end 0.2794 0.1778)
						)
						(arc
							(start 0.2794 -0.1778)
							(mid 0.249642 -0.249642)
							(end 0.1778 -0.2794)
						)
					)
					(width 0)
					(fill yes)
				)
			)
		)
		(pad "2" smd custom
			(at 0 0.4445 180)
			(size 0.1397 0.1397)
			(layers "F.Cu" "F.Mask" "F.Paste")
			(net "SAS_EXP_B_PWR12")
			(options
				(clearance outline)
				(anchor circle)
			)
			(primitives
				(gr_poly
					(pts
						(arc
							(start -0.1778 -0.2794)
							(mid -0.249642 -0.249642)
							(end -0.2794 -0.1778)
						)
						(arc
							(start -0.2794 0.1778)
							(mid -0.249642 0.249642)
							(end -0.1778 0.2794)
						)
						(arc
							(start 0.1778 0.2794)
							(mid 0.249642 0.249642)
							(end 0.2794 0.1778)
						)
						(arc
							(start 0.2794 -0.1778)
							(mid 0.249642 -0.249642)
							(end 0.1778 -0.2794)
						)
					)
					(width 0)
					(fill yes)
				)
			)
		)
	)
	(footprint ""
		(layer "F.Cu")
		(at 58.039 -280.1874 90)
		(property "Reference" "R205"
			(at 0 0 90)
			(layer "F.SilkS")
			(hide yes)
			(effects
				(font
					(size 1.27 1.27)
				)
			)
		)
		(property "Value" "2R2010J-1-GP"
			(at 0.254 -8.0772 90)
			(unlocked yes)
			(layer "F.Fab")
			(hide yes)
			(effects
				(font
					(size 1.016 1.016)
					(thickness 0.1524)
				)
			)
		)
		(property "Device Type" "R2010H28"
			(at 0.254 -9.6774 90)
			(unlocked yes)
			(layer "F.Fab")
			(hide yes)
			(effects
				(font
					(size 1.016 1.016)
					(thickness 0.1524)
				)
			)
		)
		(duplicate_pad_numbers_are_jumpers no)
		(fp_line
			(start 1.651 -3.302)
			(end -1.651 -3.302)
			(stroke
				(width 0.1524)
				(type default)
			)
			(layer "F.SilkS")
		)
		(fp_line
			(start -1.651 -3.302)
			(end -1.651 3.302)
			(stroke
				(width 0.1524)
				(type default)
			)
			(layer "F.SilkS")
		)
		(fp_line
			(start 1.651 3.302)
			(end 1.651 -3.302)
			(stroke
				(width 0.1524)
				(type default)
			)
			(layer "F.SilkS")
		)
		(fp_line
			(start -1.651 3.302)
			(end 1.651 3.302)
			(stroke
				(width 0.1524)
				(type default)
			)
			(layer "F.SilkS")
		)
		(fp_rect
			(start -1.7272 -3.3782)
			(end 1.7272 3.3782)
			(stroke
				(width 0)
				(type default)
			)
			(fill no)
			(layer "F.CrtYd")
		)
		(fp_poly
			(pts
				(xy 1.7272 3.3782) (xy 1.7272 -3.3782) (xy -1.7272 -3.3782) (xy -1.7272 3.3782)
			)
			(stroke
				(width 0)
				(type default)
			)
			(fill no)
			(layer "F.Fab")
		)
		(pad "1" smd rect
			(at 0 -2.3495 90)
			(size 2.794 1.143)
			(layers "F.Cu" "F.Mask" "F.Paste")
			(net "5V_PRE_7")
		)
		(pad "2" smd rect
			(at 0 2.3495 90)
			(size 2.794 1.143)
			(layers "F.Cu" "F.Mask" "F.Paste")
			(net "P5V_HDD7")
		)
	)
	(footprint ""
		(layer "F.Cu")
		(at 73.431146 -6.632702)
		(property "Reference" "C338"
			(at 0 0 0)
			(layer "F.SilkS")
			(hide yes)
			(effects
				(font
					(size 1.27 1.27)
				)
			)
		)
		(property "Value" "SC1U25V3KX-1-GP"
			(at 0 -2.8194 0)
			(unlocked yes)
			(layer "F.Fab")
			(hide yes)
			(effects
				(font
					(size 1.016 1.016)
					(thickness 0.1524)
				)
			)
		)
		(property "Device Type" "C603H36"
			(at 0 -4.3434 0)
			(unlocked yes)
			(layer "F.Fab")
			(hide yes)
			(effects
				(font
					(size 1.016 1.016)
					(thickness 0.1524)
				)
			)
		)
		(duplicate_pad_numbers_are_jumpers no)
		(fp_line
			(start 0.508 0)
			(end -0.508 0)
			(stroke
				(width 0.2032)
				(type default)
			)
			(layer "F.SilkS")
		)
		(fp_rect
			(start -0.5842 1.3335)
			(end 0.5842 -1.3335)
			(stroke
				(width 0)
				(type default)
			)
			(fill no)
			(layer "F.CrtYd")
		)
		(fp_rect
			(start -0.5842 1.3335)
			(end 0.5842 -1.3335)
			(stroke
				(width 0)
				(type default)
			)
			(fill no)
			(layer "F.Fab")
		)
		(pad "1" smd custom
			(at 0 -0.762)
			(size 0.2159 0.2159)
			(layers "F.Cu" "F.Mask" "F.Paste")
			(net "P12V_HDD14")
			(options
				(clearance outline)
				(anchor circle)
			)
			(primitives
				(gr_poly
					(pts
						(arc
							(start -0.3302 -0.4318)
							(mid -0.402042 -0.402042)
							(end -0.4318 -0.3302)
						)
						(arc
							(start -0.4318 0.3302)
							(mid -0.402042 0.402042)
							(end -0.3302 0.4318)
						)
						(arc
							(start 0.3302 0.4318)
							(mid 0.402042 0.402042)
							(end 0.4318 0.3302)
						)
						(arc
							(start 0.4318 -0.3302)
							(mid 0.402042 -0.402042)
							(end 0.3302 -0.4318)
						)
					)
					(width 0)
					(fill yes)
				)
			)
		)
		(pad "2" smd custom
			(at 0 0.762)
			(size 0.2159 0.2159)
			(layers "F.Cu" "F.Mask" "F.Paste")
			(net "GND")
			(options
				(clearance outline)
				(anchor circle)
			)
			(primitives
				(gr_poly
					(pts
						(arc
							(start -0.3302 -0.4318)
							(mid -0.402042 -0.402042)
							(end -0.4318 -0.3302)
						)
						(arc
							(start -0.4318 0.3302)
							(mid -0.402042 0.402042)
							(end -0.3302 0.4318)
						)
						(arc
							(start 0.3302 0.4318)
							(mid 0.402042 0.402042)
							(end 0.4318 0.3302)
						)
						(arc
							(start 0.4318 -0.3302)
							(mid 0.402042 -0.402042)
							(end 0.3302 -0.4318)
						)
					)
					(width 0)
					(fill yes)
				)
			)
		)
	)
	(footprint ""
		(layer "F.Cu")
		(at 97.789746 -7.7597 90)
		(property "Reference" "R306"
			(at 0 0 90)
			(layer "F.SilkS")
			(hide yes)
			(effects
				(font
					(size 1.27 1.27)
				)
			)
		)
		(property "Value" "4K7R2J-2-GP"
			(at 0.064008 -3.993896 90)
			(unlocked yes)
			(layer "F.Fab")
			(hide yes)
			(effects
				(font
					(size 1.016 1.016)
					(thickness 0.1524)
				)
			)
		)
		(property "Device Type" "R402H16"
			(at 0.064008 -5.517896 90)
			(unlocked yes)
			(layer "F.Fab")
			(hide yes)
			(effects
				(font
					(size 1.016 1.016)
					(thickness 0.1524)
				)
			)
		)
		(duplicate_pad_numbers_are_jumpers no)
		(fp_line
			(start 0.508 -0.9398)
			(end -0.508 -0.9398)
			(stroke
				(width 0.1524)
				(type default)
			)
			(layer "F.SilkS")
		)
		(fp_line
			(start -0.508 -0.9398)
			(end -0.508 0.9398)
			(stroke
				(width 0.1524)
				(type default)
			)
			(layer "F.SilkS")
		)
		(fp_rect
			(start -0.508 0.9398)
			(end 0.508 -0.9398)
			(stroke
				(width 0)
				(type default)
			)
			(fill no)
			(layer "F.CrtYd")
		)
		(fp_rect
			(start -0.508 0.9398)
			(end 0.508 -0.9398)
			(stroke
				(width 0)
				(type default)
			)
			(fill no)
			(layer "F.Fab")
		)
		(pad "1" smd custom
			(at 0 -0.4445 90)
			(size 0.1397 0.1397)
			(layers "F.Cu" "F.Mask" "F.Paste")
			(net "P12V")
			(options
				(clearance outline)
				(anchor circle)
			)
			(primitives
				(gr_poly
					(pts
						(arc
							(start -0.1778 -0.2794)
							(mid -0.249642 -0.249642)
							(end -0.2794 -0.1778)
						)
						(arc
							(start -0.2794 0.1778)
							(mid -0.249642 0.249642)
							(end -0.1778 0.2794)
						)
						(arc
							(start 0.1778 0.2794)
							(mid 0.249642 0.249642)
							(end 0.2794 0.1778)
						)
						(arc
							(start 0.2794 -0.1778)
							(mid 0.249642 -0.249642)
							(end 0.1778 -0.2794)
						)
					)
					(width 0)
					(fill yes)
				)
			)
		)
		(pad "2" smd custom
			(at 0 0.4445 90)
			(size 0.1397 0.1397)
			(layers "F.Cu" "F.Mask" "F.Paste")
			(net "SW_HDD14_R")
			(options
				(clearance outline)
				(anchor circle)
			)
			(primitives
				(gr_poly
					(pts
						(arc
							(start -0.1778 -0.2794)
							(mid -0.249642 -0.249642)
							(end -0.2794 -0.1778)
						)
						(arc
							(start -0.2794 0.1778)
							(mid -0.249642 0.249642)
							(end -0.1778 0.2794)
						)
						(arc
							(start 0.1778 0.2794)
							(mid 0.249642 0.249642)
							(end 0.2794 0.1778)
						)
						(arc
							(start 0.2794 -0.1778)
							(mid 0.249642 -0.249642)
							(end 0.1778 -0.2794)
						)
					)
					(width 0)
					(fill yes)
				)
			)
		)
	)
	(footprint ""
		(layer "F.Cu")
		(at 48.208946 -40.9448 90)
		(property "Reference" "Q43"
			(at 0 0 90)
			(layer "F.SilkS")
			(hide yes)
			(effects
				(font
					(size 1.27 1.27)
				)
			)
		)
		(property "Value" "PMBS3904-1-GP"
			(at 0 -9.0932 90)
			(unlocked yes)
			(layer "F.Fab")
			(hide yes)
			(effects
				(font
					(size 1.016 1.016)
					(thickness 0.1524)
				)
			)
		)
		(property "Device Type" "SOT-23-10H44"
			(at 0 -10.6172 90)
			(unlocked yes)
			(layer "F.Fab")
			(hide yes)
			(effects
				(font
					(size 1.016 1.016)
					(thickness 0.1524)
				)
			)
		)
		(duplicate_pad_numbers_are_jumpers no)
		(fp_line
			(start 1.651 -1.778)
			(end -1.651 -1.778)
			(stroke
				(width 0.1524)
				(type default)
			)
			(layer "F.SilkS")
		)
		(fp_line
			(start -1.651 -1.778)
			(end -1.651 1.778)
			(stroke
				(width 0.1524)
				(type default)
			)
			(layer "F.SilkS")
		)
		(fp_line
			(start 1.651 1.778)
			(end 1.651 -1.778)
			(stroke
				(width 0.1524)
				(type default)
			)
			(layer "F.SilkS")
		)
		(fp_line
			(start -1.651 1.778)
			(end 1.651 1.778)
			(stroke
				(width 0.1524)
				(type default)
			)
			(layer "F.SilkS")
		)
		(fp_line
			(start -0.9906 1.86309)
			(end -0.701294 2.15265)
			(stroke
				(width 0.0127)
				(type default)
			)
			(layer "F.SilkS")
		)
		(fp_line
			(start -0.994156 1.8669)
			(end -0.987044 1.8669)
			(stroke
				(width 0.0127)
				(type default)
			)
			(layer "F.SilkS")
		)
		(fp_line
			(start -1.003808 1.876552)
			(end -0.977646 1.876552)
			(stroke
				(width 0.0127)
				(type default)
			)
			(layer "F.SilkS")
		)
		(fp_line
			(start -0.635 1.8796)
			(end -1.7526 1.8796)
			(stroke
				(width 0.3302)
				(type default)
			)
			(layer "F.SilkS")
		)
		(fp_line
			(start -1.7526 1.8796)
			(end -1.7526 0.9906)
			(stroke
				(width 0.3302)
				(type default)
			)
			(layer "F.SilkS")
		)
		(fp_line
			(start -1.013206 1.88595)
			(end -0.967994 1.88595)
			(stroke
				(width 0.0127)
				(type default)
			)
			(layer "F.SilkS")
		)
		(fp_line
			(start -1.022858 1.895602)
			(end -0.958596 1.895602)
			(stroke
				(width 0.0127)
				(type default)
			)
			(layer "F.SilkS")
		)
		(fp_line
			(start -1.032256 1.905)
			(end -0.948944 1.905)
			(stroke
				(width 0.0127)
				(type default)
			)
			(layer "F.SilkS")
		)
		(fp_line
			(start -1.041908 1.914652)
			(end -0.939546 1.914652)
			(stroke
				(width 0.0127)
				(type default)
			)
			(layer "F.SilkS")
		)
		(fp_line
			(start -1.051306 1.92405)
			(end -0.929894 1.92405)
			(stroke
				(width 0.0127)
				(type default)
			)
			(layer "F.SilkS")
		)
		(fp_line
			(start -1.060958 1.933702)
			(end -0.920496 1.933702)
			(stroke
				(width 0.0127)
				(type default)
			)
			(layer "F.SilkS")
		)
		(fp_line
			(start -1.070356 1.9431)
			(end -0.910844 1.9431)
			(stroke
				(width 0.0127)
				(type default)
			)
			(layer "F.SilkS")
		)
		(fp_line
			(start -1.080008 1.952752)
			(end -0.901446 1.952752)
			(stroke
				(width 0.0127)
				(type default)
			)
			(layer "F.SilkS")
		)
		(fp_line
			(start -1.089406 1.96215)
			(end -0.891794 1.96215)
			(stroke
				(width 0.0127)
				(type default)
			)
			(layer "F.SilkS")
		)
		(fp_line
			(start -1.099058 1.971802)
			(end -0.882396 1.971802)
			(stroke
				(width 0.0127)
				(type default)
			)
			(layer "F.SilkS")
		)
		(fp_line
			(start -1.108456 1.9812)
			(end -0.872744 1.9812)
			(stroke
				(width 0.0127)
				(type default)
			)
			(layer "F.SilkS")
		)
		(fp_line
			(start -1.118108 1.990852)
			(end -0.863346 1.990852)
			(stroke
				(width 0.0127)
				(type default)
			)
			(layer "F.SilkS")
		)
		(fp_line
			(start -1.127506 2.00025)
			(end -0.853694 2.00025)
			(stroke
				(width 0.0127)
				(type default)
			)
			(layer "F.SilkS")
		)
		(fp_line
			(start -1.137158 2.009902)
			(end -0.844296 2.009902)
			(stroke
				(width 0.0127)
				(type default)
			)
			(layer "F.SilkS")
		)
		(fp_line
			(start -1.146556 2.0193)
			(end -0.834644 2.0193)
			(stroke
				(width 0.0127)
				(type default)
			)
			(layer "F.SilkS")
		)
		(fp_line
			(start -1.156208 2.028952)
			(end -0.825246 2.028952)
			(stroke
				(width 0.0127)
				(type default)
			)
			(layer "F.SilkS")
		)
		(fp_line
			(start -1.165606 2.03835)
			(end -0.815594 2.03835)
			(stroke
				(width 0.0127)
				(type default)
			)
			(layer "F.SilkS")
		)
		(fp_line
			(start -1.175258 2.048002)
			(end -0.806196 2.048002)
			(stroke
				(width 0.0127)
				(type default)
			)
			(layer "F.SilkS")
		)
		(fp_line
			(start -1.184656 2.0574)
			(end -0.796544 2.0574)
			(stroke
				(width 0.0127)
				(type default)
			)
			(layer "F.SilkS")
		)
		(fp_line
			(start -1.194308 2.067052)
			(end -0.787146 2.067052)
			(stroke
				(width 0.0127)
				(type default)
			)
			(layer "F.SilkS")
		)
		(fp_line
			(start -1.203706 2.07645)
			(end -0.777494 2.07645)
			(stroke
				(width 0.0127)
				(type default)
			)
			(layer "F.SilkS")
		)
		(fp_line
			(start -1.213358 2.086102)
			(end -0.768096 2.086102)
			(stroke
				(width 0.0127)
				(type default)
			)
			(layer "F.SilkS")
		)
		(fp_line
			(start -1.222756 2.0955)
			(end -0.758444 2.0955)
			(stroke
				(width 0.0127)
				(type default)
			)
			(layer "F.SilkS")
		)
		(fp_line
			(start -1.232408 2.105152)
			(end -0.749046 2.105152)
			(stroke
				(width 0.0127)
				(type default)
			)
			(layer "F.SilkS")
		)
		(fp_line
			(start -1.241806 2.11455)
			(end -0.739394 2.11455)
			(stroke
				(width 0.0127)
				(type default)
			)
			(layer "F.SilkS")
		)
		(fp_line
			(start -1.251458 2.124202)
			(end -0.729996 2.124202)
			(stroke
				(width 0.0127)
				(type default)
			)
			(layer "F.SilkS")
		)
		(fp_line
			(start -1.260856 2.1336)
			(end -0.720344 2.1336)
			(stroke
				(width 0.0127)
				(type default)
			)
			(layer "F.SilkS")
		)
		(fp_line
			(start -0.719074 2.145538)
			(end -1.265936 2.14122)
			(stroke
				(width 0.0127)
				(type default)
			)
			(layer "F.SilkS")
		)
		(fp_line
			(start -1.279398 2.152142)
			(end -0.9906 1.86309)
			(stroke
				(width 0.0127)
				(type default)
			)
			(layer "F.SilkS")
		)
		(fp_line
			(start -0.71628 2.15265)
			(end -1.26492 2.15265)
			(stroke
				(width 0.0127)
				(type default)
			)
			(layer "F.SilkS")
		)
		(fp_line
			(start -1.279144 2.15265)
			(end -0.701294 2.15265)
			(stroke
				(width 0.0127)
				(type default)
			)
			(layer "F.SilkS")
		)
		(fp_poly
			(pts
				(xy -1.285748 2.159) (xy -1.285748 1.8796) (xy -1.778 1.8796) (xy -1.778 -1.8796) (xy 1.778 -1.8796)
				(xy 1.778 1.8796) (xy -0.694944 1.8796) (xy -0.694944 2.159)
			)
			(stroke
				(width 0)
				(type default)
			)
			(fill no)
			(layer "F.CrtYd")
		)
		(fp_poly
			(pts
				(xy -1.285748 2.159) (xy -1.285748 1.8796) (xy -1.778 1.8796) (xy -1.778 -1.8796) (xy 1.778 -1.8796)
				(xy 1.778 1.8796) (xy -0.694944 1.8796) (xy -0.694944 2.159)
			)
			(stroke
				(width 0)
				(type default)
			)
			(fill no)
			(layer "F.Fab")
		)
		(pad "1" smd rect
			(at -0.98425 0.9525 90)
			(size 0.762 1.143)
			(layers "F.Cu" "F.Mask" "F.Paste")
			(net "FLT_HDD9_B")
		)
		(pad "2" smd rect
			(at 0.98425 0.9525 90)
			(size 0.762 1.143)
			(layers "F.Cu" "F.Mask" "F.Paste")
			(net "GND")
		)
		(pad "3" smd rect
			(at 0 -0.9525 90)
			(size 0.762 1.143)
			(layers "F.Cu" "F.Mask" "F.Paste")
			(net "DRIVE_ACT_9")
		)
	)
	(footprint ""
		(layer "F.Cu")
		(at 205.74 -175.006)
		(property "Reference" "C367"
			(at 0 0 0)
			(layer "F.SilkS")
			(hide yes)
			(effects
				(font
					(size 1.27 1.27)
				)
			)
		)
		(property "Value" "SCD033U25V2KX-GP"
			(at 1.1811 -2.7051 0)
			(unlocked yes)
			(layer "F.Fab")
			(hide yes)
			(effects
				(font
					(size 1.016 1.016)
					(thickness 0.1524)
				)
			)
		)
		(property "Device Type" "C402H22"
			(at 1.1811 -4.2291 0)
			(unlocked yes)
			(layer "F.Fab")
			(hide yes)
			(effects
				(font
					(size 1.016 1.016)
					(thickness 0.1524)
				)
			)
		)
		(duplicate_pad_numbers_are_jumpers no)
		(fp_rect
			(start -0.4318 0.9525)
			(end 0.4318 -0.9525)
			(stroke
				(width 0)
				(type default)
			)
			(fill no)
			(layer "F.CrtYd")
		)
		(fp_rect
			(start -0.4318 0.9525)
			(end 0.4318 -0.9525)
			(stroke
				(width 0)
				(type default)
			)
			(fill no)
			(layer "F.Fab")
		)
		(pad "1" smd custom
			(at 0 -0.4445)
			(size 0.1524 0.1524)
			(layers "F.Cu" "F.Mask" "F.Paste")
			(net "SW_HDD3_P")
			(options
				(clearance outline)
				(anchor circle)
			)
			(primitives
				(gr_poly
					(pts
						(arc
							(start 0.3048 -0.2032)
							(mid 0.275042 -0.275042)
							(end 0.2032 -0.3048)
						)
						(arc
							(start -0.2032 -0.3048)
							(mid -0.275042 -0.275042)
							(end -0.3048 -0.2032)
						)
						(arc
							(start -0.3048 0.2032)
							(mid -0.275042 0.275042)
							(end -0.2032 0.3048)
						)
						(arc
							(start 0.2032 0.3048)
							(mid 0.275042 0.275042)
							(end 0.3048 0.2032)
						)
					)
					(width 0)
					(fill yes)
				)
			)
		)
		(pad "2" smd custom
			(at 0 0.4445)
			(size 0.1524 0.1524)
			(layers "F.Cu" "F.Mask" "F.Paste")
			(net "GND")
			(options
				(clearance outline)
				(anchor circle)
			)
			(primitives
				(gr_poly
					(pts
						(arc
							(start 0.3048 -0.2032)
							(mid 0.275042 -0.275042)
							(end 0.2032 -0.3048)
						)
						(arc
							(start -0.2032 -0.3048)
							(mid -0.275042 -0.275042)
							(end -0.3048 -0.2032)
						)
						(arc
							(start -0.3048 0.2032)
							(mid -0.275042 0.275042)
							(end -0.2032 0.3048)
						)
						(arc
							(start 0.2032 0.3048)
							(mid 0.275042 0.275042)
							(end 0.3048 0.2032)
						)
					)
					(width 0)
					(fill yes)
				)
			)
		)
	)
	(footprint ""
		(layer "F.Cu")
		(at 233.247946 -143.9926 90)
		(property "Reference" "Q37"
			(at 0 0 90)
			(layer "F.SilkS")
			(hide yes)
			(effects
				(font
					(size 1.27 1.27)
				)
			)
		)
		(property "Value" "PMBS3904-1-GP"
			(at 0 -9.0932 90)
			(unlocked yes)
			(layer "F.Fab")
			(hide yes)
			(effects
				(font
					(size 1.016 1.016)
					(thickness 0.1524)
				)
			)
		)
		(property "Device Type" "SOT-23-10H44"
			(at 0 -10.6172 90)
			(unlocked yes)
			(layer "F.Fab")
			(hide yes)
			(effects
				(font
					(size 1.016 1.016)
					(thickness 0.1524)
				)
			)
		)
		(duplicate_pad_numbers_are_jumpers no)
		(fp_line
			(start 1.651 -1.778)
			(end -1.651 -1.778)
			(stroke
				(width 0.1524)
				(type default)
			)
			(layer "F.SilkS")
		)
		(fp_line
			(start -1.651 -1.778)
			(end -1.651 1.778)
			(stroke
				(width 0.1524)
				(type default)
			)
			(layer "F.SilkS")
		)
		(fp_line
			(start 1.651 1.778)
			(end 1.651 -1.778)
			(stroke
				(width 0.1524)
				(type default)
			)
			(layer "F.SilkS")
		)
		(fp_line
			(start -1.651 1.778)
			(end 1.651 1.778)
			(stroke
				(width 0.1524)
				(type default)
			)
			(layer "F.SilkS")
		)
		(fp_line
			(start -0.9906 1.86309)
			(end -0.701294 2.15265)
			(stroke
				(width 0.0127)
				(type default)
			)
			(layer "F.SilkS")
		)
		(fp_line
			(start -0.994156 1.8669)
			(end -0.987044 1.8669)
			(stroke
				(width 0.0127)
				(type default)
			)
			(layer "F.SilkS")
		)
		(fp_line
			(start -1.003808 1.876552)
			(end -0.977646 1.876552)
			(stroke
				(width 0.0127)
				(type default)
			)
			(layer "F.SilkS")
		)
		(fp_line
			(start -0.635 1.8796)
			(end -1.7526 1.8796)
			(stroke
				(width 0.3302)
				(type default)
			)
			(layer "F.SilkS")
		)
		(fp_line
			(start -1.7526 1.8796)
			(end -1.7526 0.9906)
			(stroke
				(width 0.3302)
				(type default)
			)
			(layer "F.SilkS")
		)
		(fp_line
			(start -1.013206 1.88595)
			(end -0.967994 1.88595)
			(stroke
				(width 0.0127)
				(type default)
			)
			(layer "F.SilkS")
		)
		(fp_line
			(start -1.022858 1.895602)
			(end -0.958596 1.895602)
			(stroke
				(width 0.0127)
				(type default)
			)
			(layer "F.SilkS")
		)
		(fp_line
			(start -1.032256 1.905)
			(end -0.948944 1.905)
			(stroke
				(width 0.0127)
				(type default)
			)
			(layer "F.SilkS")
		)
		(fp_line
			(start -1.041908 1.914652)
			(end -0.939546 1.914652)
			(stroke
				(width 0.0127)
				(type default)
			)
			(layer "F.SilkS")
		)
		(fp_line
			(start -1.051306 1.92405)
			(end -0.929894 1.92405)
			(stroke
				(width 0.0127)
				(type default)
			)
			(layer "F.SilkS")
		)
		(fp_line
			(start -1.060958 1.933702)
			(end -0.920496 1.933702)
			(stroke
				(width 0.0127)
				(type default)
			)
			(layer "F.SilkS")
		)
		(fp_line
			(start -1.070356 1.9431)
			(end -0.910844 1.9431)
			(stroke
				(width 0.0127)
				(type default)
			)
			(layer "F.SilkS")
		)
		(fp_line
			(start -1.080008 1.952752)
			(end -0.901446 1.952752)
			(stroke
				(width 0.0127)
				(type default)
			)
			(layer "F.SilkS")
		)
		(fp_line
			(start -1.089406 1.96215)
			(end -0.891794 1.96215)
			(stroke
				(width 0.0127)
				(type default)
			)
			(layer "F.SilkS")
		)
		(fp_line
			(start -1.099058 1.971802)
			(end -0.882396 1.971802)
			(stroke
				(width 0.0127)
				(type default)
			)
			(layer "F.SilkS")
		)
		(fp_line
			(start -1.108456 1.9812)
			(end -0.872744 1.9812)
			(stroke
				(width 0.0127)
				(type default)
			)
			(layer "F.SilkS")
		)
		(fp_line
			(start -1.118108 1.990852)
			(end -0.863346 1.990852)
			(stroke
				(width 0.0127)
				(type default)
			)
			(layer "F.SilkS")
		)
		(fp_line
			(start -1.127506 2.00025)
			(end -0.853694 2.00025)
			(stroke
				(width 0.0127)
				(type default)
			)
			(layer "F.SilkS")
		)
		(fp_line
			(start -1.137158 2.009902)
			(end -0.844296 2.009902)
			(stroke
				(width 0.0127)
				(type default)
			)
			(layer "F.SilkS")
		)
		(fp_line
			(start -1.146556 2.0193)
			(end -0.834644 2.0193)
			(stroke
				(width 0.0127)
				(type default)
			)
			(layer "F.SilkS")
		)
		(fp_line
			(start -1.156208 2.028952)
			(end -0.825246 2.028952)
			(stroke
				(width 0.0127)
				(type default)
			)
			(layer "F.SilkS")
		)
		(fp_line
			(start -1.165606 2.03835)
			(end -0.815594 2.03835)
			(stroke
				(width 0.0127)
				(type default)
			)
			(layer "F.SilkS")
		)
		(fp_line
			(start -1.175258 2.048002)
			(end -0.806196 2.048002)
			(stroke
				(width 0.0127)
				(type default)
			)
			(layer "F.SilkS")
		)
		(fp_line
			(start -1.184656 2.0574)
			(end -0.796544 2.0574)
			(stroke
				(width 0.0127)
				(type default)
			)
			(layer "F.SilkS")
		)
		(fp_line
			(start -1.194308 2.067052)
			(end -0.787146 2.067052)
			(stroke
				(width 0.0127)
				(type default)
			)
			(layer "F.SilkS")
		)
		(fp_line
			(start -1.203706 2.07645)
			(end -0.777494 2.07645)
			(stroke
				(width 0.0127)
				(type default)
			)
			(layer "F.SilkS")
		)
		(fp_line
			(start -1.213358 2.086102)
			(end -0.768096 2.086102)
			(stroke
				(width 0.0127)
				(type default)
			)
			(layer "F.SilkS")
		)
		(fp_line
			(start -1.222756 2.0955)
			(end -0.758444 2.0955)
			(stroke
				(width 0.0127)
				(type default)
			)
			(layer "F.SilkS")
		)
		(fp_line
			(start -1.232408 2.105152)
			(end -0.749046 2.105152)
			(stroke
				(width 0.0127)
				(type default)
			)
			(layer "F.SilkS")
		)
		(fp_line
			(start -1.241806 2.11455)
			(end -0.739394 2.11455)
			(stroke
				(width 0.0127)
				(type default)
			)
			(layer "F.SilkS")
		)
		(fp_line
			(start -1.251458 2.124202)
			(end -0.729996 2.124202)
			(stroke
				(width 0.0127)
				(type default)
			)
			(layer "F.SilkS")
		)
		(fp_line
			(start -1.260856 2.1336)
			(end -0.720344 2.1336)
			(stroke
				(width 0.0127)
				(type default)
			)
			(layer "F.SilkS")
		)
		(fp_line
			(start -0.719074 2.145538)
			(end -1.265936 2.14122)
			(stroke
				(width 0.0127)
				(type default)
			)
			(layer "F.SilkS")
		)
		(fp_line
			(start -1.279398 2.152142)
			(end -0.9906 1.86309)
			(stroke
				(width 0.0127)
				(type default)
			)
			(layer "F.SilkS")
		)
		(fp_line
			(start -0.71628 2.15265)
			(end -1.26492 2.15265)
			(stroke
				(width 0.0127)
				(type default)
			)
			(layer "F.SilkS")
		)
		(fp_line
			(start -1.279144 2.15265)
			(end -0.701294 2.15265)
			(stroke
				(width 0.0127)
				(type default)
			)
			(layer "F.SilkS")
		)
		(fp_poly
			(pts
				(xy -1.285748 2.159) (xy -1.285748 1.8796) (xy -1.778 1.8796) (xy -1.778 -1.8796) (xy 1.778 -1.8796)
				(xy 1.778 1.8796) (xy -0.694944 1.8796) (xy -0.694944 2.159)
			)
			(stroke
				(width 0)
				(type default)
			)
			(fill no)
			(layer "F.CrtYd")
		)
		(fp_poly
			(pts
				(xy -1.285748 2.159) (xy -1.285748 1.8796) (xy -1.778 1.8796) (xy -1.778 -1.8796) (xy 1.778 -1.8796)
				(xy 1.778 1.8796) (xy -0.694944 1.8796) (xy -0.694944 2.159)
			)
			(stroke
				(width 0)
				(type default)
			)
			(fill no)
			(layer "F.Fab")
		)
		(pad "1" smd rect
			(at -0.98425 0.9525 90)
			(size 0.762 1.143)
			(layers "F.Cu" "F.Mask" "F.Paste")
			(net "FLT_HDD3_B")
		)
		(pad "2" smd rect
			(at 0.98425 0.9525 90)
			(size 0.762 1.143)
			(layers "F.Cu" "F.Mask" "F.Paste")
			(net "GND")
		)
		(pad "3" smd rect
			(at 0 -0.9525 90)
			(size 0.762 1.143)
			(layers "F.Cu" "F.Mask" "F.Paste")
			(net "DRIVE_ACT_3")
		)
	)
	(footprint ""
		(layer "F.Cu")
		(at 14.478 -182.753 90)
		(property "Reference" "TC2"
			(at 0 0 90)
			(layer "F.SilkS")
			(hide yes)
			(effects
				(font
					(size 1.27 1.27)
				)
			)
		)
		(property "Value" "ST15U25VDM-1-GP"
			(at 0 -9.6012 90)
			(unlocked yes)
			(layer "F.Fab")
			(hide yes)
			(effects
				(font
					(size 1.016 1.016)
					(thickness 0.1524)
				)
			)
		)
		(property "Device Type" "CT7343H79"
			(at 0 -11.1252 90)
			(unlocked yes)
			(layer "F.Fab")
			(hide yes)
			(effects
				(font
					(size 1.016 1.016)
					(thickness 0.1524)
				)
			)
		)
		(duplicate_pad_numbers_are_jumpers no)
		(fp_line
			(start 2.286 -4.8768)
			(end -2.286 -4.8768)
			(stroke
				(width 0.1524)
				(type default)
			)
			(layer "F.SilkS")
		)
		(fp_line
			(start -2.286 -4.8768)
			(end -2.286 -2.032)
			(stroke
				(width 0.1524)
				(type default)
			)
			(layer "F.SilkS")
		)
		(fp_line
			(start 2.1082 -4.699)
			(end -2.1082 -4.699)
			(stroke
				(width 0.508)
				(type default)
			)
			(layer "F.SilkS")
		)
		(fp_line
			(start 2.286 -2.032)
			(end 2.286 -4.8768)
			(stroke
				(width 0.1524)
				(type default)
			)
			(layer "F.SilkS")
		)
		(fp_line
			(start 2.286 2.032)
			(end 2.286 4.8768)
			(stroke
				(width 0.1524)
				(type default)
			)
			(layer "F.SilkS")
		)
		(fp_line
			(start 2.286 4.8768)
			(end -2.286 4.8768)
			(stroke
				(width 0.1524)
				(type default)
			)
			(layer "F.SilkS")
		)
		(fp_line
			(start -2.286 4.8768)
			(end -2.286 2.032)
			(stroke
				(width 0.1524)
				(type default)
			)
			(layer "F.SilkS")
		)
		(fp_rect
			(start -2.1463 3.6449)
			(end 2.1463 -3.6449)
			(stroke
				(width 0)
				(type default)
			)
			(fill no)
			(layer "F.CrtYd")
		)
		(fp_poly
			(pts
				(xy -2.54 4.953) (xy -2.54 4.2926) (xy -3.81 4.2926) (xy -3.81 -4.2926) (xy -2.54 -4.2926) (xy -2.54 -4.953)
				(xy 2.54 -4.953) (xy 2.54 -4.2926) (xy 3.81 -4.2926) (xy 3.81 -1.6256) (xy 2.1463 -1.6256) (xy 2.1463 -3.6449)
				(xy -2.1463 -3.6449) (xy -2.1463 3.6449) (xy 2.1463 3.6449) (xy 2.1463 -1.6129) (xy 3.81 -1.6129)
				(xy 3.81 4.2926) (xy 2.54 4.2926) (xy 2.54 4.953)
			)
			(stroke
				(width 0)
				(type default)
			)
			(fill no)
			(layer "F.CrtYd")
		)
		(fp_rect
			(start 2.54 4.2926)
			(end 3.81 -4.2926)
			(stroke
				(width 0)
				(type default)
			)
			(fill no)
			(layer "F.Fab")
		)
		(fp_rect
			(start -3.81 4.2926)
			(end -2.54 -4.2926)
			(stroke
				(width 0)
				(type default)
			)
			(fill no)
			(layer "F.Fab")
		)
		(fp_rect
			(start -2.54 4.953)
			(end 2.54 -4.953)
			(stroke
				(width 0)
				(type default)
			)
			(fill no)
			(layer "F.Fab")
		)
		(pad "1" smd rect
			(at 0 -3.1496 90)
			(size 2.413 2.286)
			(layers "F.Cu" "F.Mask" "F.Paste")
			(net "P12V")
		)
		(pad "2" smd rect
			(at 0 3.1496 90)
			(size 2.413 2.286)
			(layers "F.Cu" "F.Mask" "F.Paste")
			(net "GND")
		)
		(zone
			(layer "F.Cu")
			(hatch none 0.5)
			(connect_pads
				(clearance 0)
			)
			(min_thickness 0.25)
			(keepout
				(tracks allowed)
				(vias not_allowed)
				(pads allowed)
				(copperpour not_allowed)
				(footprints allowed)
			)
			(placement
				(enabled no)
				(sheetname "")
			)
			(fill
				(thermal_gap 0.5)
				(thermal_bridge_width 0.5)
				(island_removal_mode 0)
			)
			(polygon
				(pts
					(xy 12.7889 -184.2643) (xy 9.8806 -184.2643) (xy 9.8806 -181.2417) (xy 12.7762 -181.2417) (xy 13.1064 -181.2417)
					(xy 13.1064 -184.2643)
				)
			)
		)
		(zone
			(layer "F.Cu")
			(hatch none 0.5)
			(connect_pads
				(clearance 0)
			)
			(min_thickness 0.25)
			(keepout
				(tracks allowed)
				(vias not_allowed)
				(pads allowed)
				(copperpour not_allowed)
				(footprints allowed)
			)
			(placement
				(enabled no)
				(sheetname "")
			)
			(fill
				(thermal_gap 0.5)
				(thermal_bridge_width 0.5)
				(island_removal_mode 0)
			)
			(polygon
				(pts
					(xy 19.0754 -181.2417) (xy 19.0754 -184.2643) (xy 16.1798 -184.2643) (xy 15.8496 -184.2643) (xy 15.8496 -181.2417)
					(xy 16.1798 -181.2417)
				)
			)
		)
	)
	(footprint ""
		(layer "F.Cu")
		(at 26.161746 -7.3787)
		(property "Reference" "TP39"
			(at 0 0 0)
			(layer "F.SilkS")
			(hide yes)
			(effects
				(font
					(size 1.27 1.27)
				)
			)
		)
		(property "Value" "TPAD32-GP"
			(at 0 -3.166364 0)
			(unlocked yes)
			(layer "F.Fab")
			(hide yes)
			(effects
				(font
					(size 1.016 1.016)
					(thickness 0.1524)
				)
			)
		)
		(property "Device Type" "TPAD32"
			(at 0 -4.690618 0)
			(unlocked yes)
			(layer "F.Fab")
			(hide yes)
			(effects
				(font
					(size 1.016 1.016)
					(thickness 0.1524)
				)
			)
		)
		(duplicate_pad_numbers_are_jumpers no)
		(fp_poly
			(pts
				(arc
					(start 0.4064 0)
					(mid -0.4064 0)
					(end 0.4064 0)
				)
			)
			(stroke
				(width 0)
				(type default)
			)
			(fill no)
			(layer "F.CrtYd")
		)
		(fp_poly
			(pts
				(arc
					(start 0.7112 0)
					(mid -0.7112 0)
					(end 0.7112 0)
				)
			)
			(stroke
				(width 0)
				(type default)
			)
			(fill no)
			(layer "F.Fab")
		)
		(pad "1" smd circle
			(at 0 0)
			(size 0.8128 0.8128)
			(layers "F.Cu" "F.Mask" "F.Paste")
			(net "ACT_HDD14")
		)
	)
	(footprint ""
		(layer "F.Cu")
		(at 83.692746 -394.6017 -90)
		(property "Reference" "R449"
			(at 0 0 270)
			(layer "F.SilkS")
			(hide yes)
			(effects
				(font
					(size 1.27 1.27)
				)
			)
		)
		(property "Value" "4K7R2J-2-GP"
			(at 0.064008 -3.993896 270)
			(unlocked yes)
			(layer "F.Fab")
			(hide yes)
			(effects
				(font
					(size 1.016 1.016)
					(thickness 0.1524)
				)
			)
		)
		(property "Device Type" "R402H16"
			(at 0.064008 -5.517896 270)
			(unlocked yes)
			(layer "F.Fab")
			(hide yes)
			(effects
				(font
					(size 1.016 1.016)
					(thickness 0.1524)
				)
			)
		)
		(duplicate_pad_numbers_are_jumpers no)
		(fp_line
			(start -0.508 -0.9398)
			(end -0.508 0.9398)
			(stroke
				(width 0.1524)
				(type default)
			)
			(layer "F.SilkS")
		)
		(fp_line
			(start 0.508 -0.9398)
			(end -0.508 -0.9398)
			(stroke
				(width 0.1524)
				(type default)
			)
			(layer "F.SilkS")
		)
		(fp_rect
			(start -0.508 0.9398)
			(end 0.508 -0.9398)
			(stroke
				(width 0)
				(type default)
			)
			(fill no)
			(layer "F.CrtYd")
		)
		(fp_rect
			(start -0.508 0.9398)
			(end 0.508 -0.9398)
			(stroke
				(width 0)
				(type default)
			)
			(fill no)
			(layer "F.Fab")
		)
		(pad "1" smd custom
			(at 0 -0.4445 270)
			(size 0.1397 0.1397)
			(layers "F.Cu" "F.Mask" "F.Paste")
			(net "P3V3")
			(options
				(clearance outline)
				(anchor circle)
			)
			(primitives
				(gr_poly
					(pts
						(arc
							(start -0.1778 -0.2794)
							(mid -0.249642 -0.249642)
							(end -0.2794 -0.1778)
						)
						(arc
							(start -0.2794 0.1778)
							(mid -0.249642 0.249642)
							(end -0.1778 0.2794)
						)
						(arc
							(start 0.1778 0.2794)
							(mid 0.249642 0.249642)
							(end 0.2794 0.1778)
						)
						(arc
							(start 0.2794 -0.1778)
							(mid 0.249642 -0.249642)
							(end 0.1778 -0.2794)
						)
					)
					(width 0)
					(fill yes)
				)
			)
		)
		(pad "2" smd custom
			(at 0 0.4445 270)
			(size 0.1397 0.1397)
			(layers "F.Cu" "F.Mask" "F.Paste")
			(net "SAS_EXP_B_PWR6")
			(options
				(clearance outline)
				(anchor circle)
			)
			(primitives
				(gr_poly
					(pts
						(arc
							(start -0.1778 -0.2794)
							(mid -0.249642 -0.249642)
							(end -0.2794 -0.1778)
						)
						(arc
							(start -0.2794 0.1778)
							(mid -0.249642 0.249642)
							(end -0.1778 0.2794)
						)
						(arc
							(start 0.1778 0.2794)
							(mid 0.249642 0.249642)
							(end 0.2794 0.1778)
						)
						(arc
							(start 0.2794 -0.1778)
							(mid 0.249642 -0.249642)
							(end 0.1778 -0.2794)
						)
					)
					(width 0)
					(fill yes)
				)
			)
		)
	)
	(footprint ""
		(layer "F.Cu")
		(at 102.234746 -12.9667 90)
		(property "Reference" "R309"
			(at 0 0 90)
			(layer "F.SilkS")
			(hide yes)
			(effects
				(font
					(size 1.27 1.27)
				)
			)
		)
		(property "Value" "0R2J-2-GP"
			(at 0.064008 -3.993896 90)
			(unlocked yes)
			(layer "F.Fab")
			(hide yes)
			(effects
				(font
					(size 1.016 1.016)
					(thickness 0.1524)
				)
			)
		)
		(property "Device Type" "R402H16"
			(at 0.064008 -5.517896 90)
			(unlocked yes)
			(layer "F.Fab")
			(hide yes)
			(effects
				(font
					(size 1.016 1.016)
					(thickness 0.1524)
				)
			)
		)
		(duplicate_pad_numbers_are_jumpers no)
		(fp_line
			(start 0.508 -0.9398)
			(end -0.508 -0.9398)
			(stroke
				(width 0.1524)
				(type default)
			)
			(layer "F.SilkS")
		)
		(fp_line
			(start -0.508 -0.9398)
			(end -0.508 0.9398)
			(stroke
				(width 0.1524)
				(type default)
			)
			(layer "F.SilkS")
		)
		(fp_rect
			(start -0.508 0.9398)
			(end 0.508 -0.9398)
			(stroke
				(width 0)
				(type default)
			)
			(fill no)
			(layer "F.CrtYd")
		)
		(fp_rect
			(start -0.508 0.9398)
			(end 0.508 -0.9398)
			(stroke
				(width 0)
				(type default)
			)
			(fill no)
			(layer "F.Fab")
		)
		(pad "1" smd custom
			(at 0 -0.4445 90)
			(size 0.1397 0.1397)
			(layers "F.Cu" "F.Mask" "F.Paste")
			(net "DRIVE_PWR14")
			(options
				(clearance outline)
				(anchor circle)
			)
			(primitives
				(gr_poly
					(pts
						(arc
							(start -0.1778 -0.2794)
							(mid -0.249642 -0.249642)
							(end -0.2794 -0.1778)
						)
						(arc
							(start -0.2794 0.1778)
							(mid -0.249642 0.249642)
							(end -0.1778 0.2794)
						)
						(arc
							(start 0.1778 0.2794)
							(mid 0.249642 0.249642)
							(end 0.2794 0.1778)
						)
						(arc
							(start 0.2794 -0.1778)
							(mid 0.249642 -0.249642)
							(end 0.1778 -0.2794)
						)
					)
					(width 0)
					(fill yes)
				)
			)
		)
		(pad "2" smd custom
			(at 0 0.4445 90)
			(size 0.1397 0.1397)
			(layers "F.Cu" "F.Mask" "F.Paste")
			(net "SW_PWR_HDD14")
			(options
				(clearance outline)
				(anchor circle)
			)
			(primitives
				(gr_poly
					(pts
						(arc
							(start -0.1778 -0.2794)
							(mid -0.249642 -0.249642)
							(end -0.2794 -0.1778)
						)
						(arc
							(start -0.2794 0.1778)
							(mid -0.249642 0.249642)
							(end -0.1778 0.2794)
						)
						(arc
							(start 0.1778 0.2794)
							(mid 0.249642 0.249642)
							(end 0.2794 0.1778)
						)
						(arc
							(start 0.2794 -0.1778)
							(mid 0.249642 -0.249642)
							(end 0.1778 -0.2794)
						)
					)
					(width 0)
					(fill yes)
				)
			)
		)
	)
	(footprint ""
		(layer "F.Cu")
		(at 162.572446 -455.837036)
		(property "Reference" "R482"
			(at 0 0 0)
			(layer "F.SilkS")
			(hide yes)
			(effects
				(font
					(size 1.27 1.27)
				)
			)
		)
		(property "Value" "10KR2F-2-GP"
			(at 0.064008 -3.993896 0)
			(unlocked yes)
			(layer "F.Fab")
			(hide yes)
			(effects
				(font
					(size 1.016 1.016)
					(thickness 0.1524)
				)
			)
		)
		(property "Device Type" "R402H16"
			(at 0.064008 -5.517896 0)
			(unlocked yes)
			(layer "F.Fab")
			(hide yes)
			(effects
				(font
					(size 1.016 1.016)
					(thickness 0.1524)
				)
			)
		)
		(duplicate_pad_numbers_are_jumpers no)
		(fp_line
			(start -0.508 -0.9398)
			(end -0.508 0.9398)
			(stroke
				(width 0.1524)
				(type default)
			)
			(layer "F.SilkS")
		)
		(fp_line
			(start 0.508 -0.9398)
			(end -0.508 -0.9398)
			(stroke
				(width 0.1524)
				(type default)
			)
			(layer "F.SilkS")
		)
		(fp_rect
			(start -0.508 0.9398)
			(end 0.508 -0.9398)
			(stroke
				(width 0)
				(type default)
			)
			(fill no)
			(layer "F.CrtYd")
		)
		(fp_rect
			(start -0.508 0.9398)
			(end 0.508 -0.9398)
			(stroke
				(width 0)
				(type default)
			)
			(fill no)
			(layer "F.Fab")
		)
		(pad "1" smd custom
			(at 0 -0.4445)
			(size 0.1397 0.1397)
			(layers "F.Cu" "F.Mask" "F.Paste")
			(net "P5VB_DIV")
			(options
				(clearance outline)
				(anchor circle)
			)
			(primitives
				(gr_poly
					(pts
						(arc
							(start -0.1778 -0.2794)
							(mid -0.249642 -0.249642)
							(end -0.2794 -0.1778)
						)
						(arc
							(start -0.2794 0.1778)
							(mid -0.249642 0.249642)
							(end -0.1778 0.2794)
						)
						(arc
							(start 0.1778 0.2794)
							(mid 0.249642 0.249642)
							(end 0.2794 0.1778)
						)
						(arc
							(start 0.2794 -0.1778)
							(mid 0.249642 -0.249642)
							(end 0.1778 -0.2794)
						)
					)
					(width 0)
					(fill yes)
				)
			)
		)
		(pad "2" smd custom
			(at 0 0.4445)
			(size 0.1397 0.1397)
			(layers "F.Cu" "F.Mask" "F.Paste")
			(net "GND")
			(options
				(clearance outline)
				(anchor circle)
			)
			(primitives
				(gr_poly
					(pts
						(arc
							(start -0.1778 -0.2794)
							(mid -0.249642 -0.249642)
							(end -0.2794 -0.1778)
						)
						(arc
							(start -0.2794 0.1778)
							(mid -0.249642 0.249642)
							(end -0.1778 0.2794)
						)
						(arc
							(start 0.1778 0.2794)
							(mid 0.249642 0.249642)
							(end 0.2794 0.1778)
						)
						(arc
							(start 0.2794 -0.1778)
							(mid 0.249642 -0.249642)
							(end 0.1778 -0.2794)
						)
					)
					(width 0)
					(fill yes)
				)
			)
		)
	)
	(footprint ""
		(layer "F.Cu")
		(at 43.179746 -209.197702 180)
		(property "Reference" "U39"
			(at 0 0 180)
			(layer "F.SilkS")
			(hide yes)
			(effects
				(font
					(size 1.27 1.27)
				)
			)
		)
		(property "Value" "74LVC1G08GW-1-GP"
			(at -2.3368 -8.6868 180)
			(unlocked yes)
			(layer "F.Fab")
			(hide yes)
			(effects
				(font
					(size 1.016 1.016)
					(thickness 0.1524)
				)
			)
		)
		(property "Device Type" "SC70-5H44"
			(at -2.3114 -10.414 180)
			(unlocked yes)
			(layer "F.Fab")
			(hide yes)
			(effects
				(font
					(size 1.016 1.016)
					(thickness 0.1524)
				)
			)
		)
		(duplicate_pad_numbers_are_jumpers no)
		(fp_line
			(start 1.3843 -1.8034)
			(end 1.3843 -1.1176)
			(stroke
				(width 0.3302)
				(type default)
			)
			(layer "F.SilkS")
		)
		(fp_line
			(start 1.27 1.7018)
			(end -1.27 1.7018)
			(stroke
				(width 0.1524)
				(type default)
			)
			(layer "F.SilkS")
		)
		(fp_line
			(start 1.27 -1.7018)
			(end 1.27 1.7018)
			(stroke
				(width 0.1524)
				(type default)
			)
			(layer "F.SilkS")
		)
		(fp_line
			(start 0.6604 -1.8034)
			(end 1.3843 -1.8034)
			(stroke
				(width 0.3302)
				(type default)
			)
			(layer "F.SilkS")
		)
		(fp_line
			(start -1.27 1.7018)
			(end -1.27 -1.7018)
			(stroke
				(width 0.1524)
				(type default)
			)
			(layer "F.SilkS")
		)
		(fp_line
			(start -1.27 -1.7018)
			(end 1.27 -1.7018)
			(stroke
				(width 0.1524)
				(type default)
			)
			(layer "F.SilkS")
		)
		(fp_rect
			(start -1.524 1.9558)
			(end 1.524 -1.9558)
			(stroke
				(width 0)
				(type default)
			)
			(fill no)
			(layer "F.CrtYd")
		)
		(fp_poly
			(pts
				(xy -1.524 -1.9558) (xy 1.524 -1.9558) (xy 1.524 1.9558) (xy -1.524 1.9558)
			)
			(stroke
				(width 0)
				(type default)
			)
			(fill no)
			(layer "F.Fab")
		)
		(pad "1" smd rect
			(at 0.65024 -0.8255 180)
			(size 0.4064 1.2192)
			(layers "F.Cu" "F.Mask" "F.Paste")
			(net "SAS_EXP_B_PWR12")
		)
		(pad "2" smd rect
			(at 0 -0.8255 180)
			(size 0.4064 1.2192)
			(layers "F.Cu" "F.Mask" "F.Paste")
			(net "SAS_EXP_A_PWR12")
		)
		(pad "3" smd rect
			(at -0.65024 -0.8255 180)
			(size 0.4064 1.2192)
			(layers "F.Cu" "F.Mask" "F.Paste")
			(net "GND")
		)
		(pad "4" smd rect
			(at -0.65024 0.8255 180)
			(size 0.4064 1.2192)
			(layers "F.Cu" "F.Mask" "F.Paste")
			(net "DRIVE_PWR12")
		)
		(pad "5" smd rect
			(at 0.65024 0.8255 180)
			(size 0.4064 1.2192)
			(layers "F.Cu" "F.Mask" "F.Paste")
			(net "P3V3")
		)
	)
	(footprint ""
		(layer "F.Cu")
		(at 245.9228 -423.037 -90)
		(property "Reference" "C356"
			(at 0 0 270)
			(layer "F.SilkS")
			(hide yes)
			(effects
				(font
					(size 1.27 1.27)
				)
			)
		)
		(property "Value" "SC220P50V3JN-GP"
			(at 0 -2.8194 270)
			(unlocked yes)
			(layer "F.Fab")
			(hide yes)
			(effects
				(font
					(size 1.016 1.016)
					(thickness 0.1524)
				)
			)
		)
		(property "Device Type" "C603H36"
			(at 0 -4.3434 270)
			(unlocked yes)
			(layer "F.Fab")
			(hide yes)
			(effects
				(font
					(size 1.016 1.016)
					(thickness 0.1524)
				)
			)
		)
		(duplicate_pad_numbers_are_jumpers no)
		(fp_line
			(start 0.508 0)
			(end -0.508 0)
			(stroke
				(width 0.2032)
				(type default)
			)
			(layer "F.SilkS")
		)
		(fp_rect
			(start -0.5842 1.3335)
			(end 0.5842 -1.3335)
			(stroke
				(width 0)
				(type default)
			)
			(fill no)
			(layer "F.CrtYd")
		)
		(fp_rect
			(start -0.5842 1.3335)
			(end 0.5842 -1.3335)
			(stroke
				(width 0)
				(type default)
			)
			(fill no)
			(layer "F.Fab")
		)
		(pad "1" smd custom
			(at 0 -0.762 270)
			(size 0.2159 0.2159)
			(layers "F.Cu" "F.Mask" "F.Paste")
			(net "I2C_C_SCL")
			(options
				(clearance outline)
				(anchor circle)
			)
			(primitives
				(gr_poly
					(pts
						(arc
							(start -0.3302 -0.4318)
							(mid -0.402042 -0.402042)
							(end -0.4318 -0.3302)
						)
						(arc
							(start -0.4318 0.3302)
							(mid -0.402042 0.402042)
							(end -0.3302 0.4318)
						)
						(arc
							(start 0.3302 0.4318)
							(mid 0.402042 0.402042)
							(end 0.4318 0.3302)
						)
						(arc
							(start 0.4318 -0.3302)
							(mid 0.402042 -0.402042)
							(end 0.3302 -0.4318)
						)
					)
					(width 0)
					(fill yes)
				)
			)
		)
		(pad "2" smd custom
			(at 0 0.762 270)
			(size 0.2159 0.2159)
			(layers "F.Cu" "F.Mask" "F.Paste")
			(net "GND")
			(options
				(clearance outline)
				(anchor circle)
			)
			(primitives
				(gr_poly
					(pts
						(arc
							(start -0.3302 -0.4318)
							(mid -0.402042 -0.402042)
							(end -0.4318 -0.3302)
						)
						(arc
							(start -0.4318 0.3302)
							(mid -0.402042 0.402042)
							(end -0.3302 0.4318)
						)
						(arc
							(start 0.3302 0.4318)
							(mid 0.402042 0.402042)
							(end 0.4318 0.3302)
						)
						(arc
							(start 0.4318 -0.3302)
							(mid 0.402042 -0.402042)
							(end 0.3302 -0.4318)
						)
					)
					(width 0)
					(fill yes)
				)
			)
		)
	)
	(footprint ""
		(layer "F.Cu")
		(at 192.278 -294.259 90)
		(property "Reference" "R550"
			(at 0 0 90)
			(layer "F.SilkS")
			(hide yes)
			(effects
				(font
					(size 1.27 1.27)
				)
			)
		)
		(property "Value" "200KR2F-L-GP"
			(at 0.064008 -3.993896 90)
			(unlocked yes)
			(layer "F.Fab")
			(hide yes)
			(effects
				(font
					(size 1.016 1.016)
					(thickness 0.1524)
				)
			)
		)
		(property "Device Type" "R402H16"
			(at 0.064008 -5.517896 90)
			(unlocked yes)
			(layer "F.Fab")
			(hide yes)
			(effects
				(font
					(size 1.016 1.016)
					(thickness 0.1524)
				)
			)
		)
		(duplicate_pad_numbers_are_jumpers no)
		(fp_line
			(start 0.508 -0.9398)
			(end -0.508 -0.9398)
			(stroke
				(width 0.1524)
				(type default)
			)
			(layer "F.SilkS")
		)
		(fp_line
			(start -0.508 -0.9398)
			(end -0.508 0.9398)
			(stroke
				(width 0.1524)
				(type default)
			)
			(layer "F.SilkS")
		)
		(fp_rect
			(start -0.508 0.9398)
			(end 0.508 -0.9398)
			(stroke
				(width 0)
				(type default)
			)
			(fill no)
			(layer "F.CrtYd")
		)
		(fp_rect
			(start -0.508 0.9398)
			(end 0.508 -0.9398)
			(stroke
				(width 0)
				(type default)
			)
			(fill no)
			(layer "F.Fab")
		)
		(pad "1" smd custom
			(at 0 -0.4445 90)
			(size 0.1397 0.1397)
			(layers "F.Cu" "F.Mask" "F.Paste")
			(net "SW_HDD2_R")
			(options
				(clearance outline)
				(anchor circle)
			)
			(primitives
				(gr_poly
					(pts
						(arc
							(start -0.1778 -0.2794)
							(mid -0.249642 -0.249642)
							(end -0.2794 -0.1778)
						)
						(arc
							(start -0.2794 0.1778)
							(mid -0.249642 0.249642)
							(end -0.1778 0.2794)
						)
						(arc
							(start 0.1778 0.2794)
							(mid 0.249642 0.249642)
							(end 0.2794 0.1778)
						)
						(arc
							(start 0.2794 -0.1778)
							(mid 0.249642 -0.249642)
							(end 0.1778 -0.2794)
						)
					)
					(width 0)
					(fill yes)
				)
			)
		)
		(pad "2" smd custom
			(at 0 0.4445 90)
			(size 0.1397 0.1397)
			(layers "F.Cu" "F.Mask" "F.Paste")
			(net "SW_HDD2_N")
			(options
				(clearance outline)
				(anchor circle)
			)
			(primitives
				(gr_poly
					(pts
						(arc
							(start -0.1778 -0.2794)
							(mid -0.249642 -0.249642)
							(end -0.2794 -0.1778)
						)
						(arc
							(start -0.2794 0.1778)
							(mid -0.249642 0.249642)
							(end -0.1778 0.2794)
						)
						(arc
							(start 0.1778 0.2794)
							(mid 0.249642 0.249642)
							(end 0.2794 0.1778)
						)
						(arc
							(start 0.2794 -0.1778)
							(mid 0.249642 -0.249642)
							(end 0.1778 -0.2794)
						)
					)
					(width 0)
					(fill yes)
				)
			)
		)
	)
	(footprint ""
		(layer "F.Cu")
		(at 258.899914 -409.949904 90)
		(property "Reference" "CN7"
			(at 0 0 90)
			(layer "F.SilkS")
			(hide yes)
			(effects
				(font
					(size 1.27 1.27)
				)
			)
		)
		(property "Value" "AMP-CONN60-5-GP"
			(at -32.935418 -14.620748 90)
			(unlocked yes)
			(layer "F.Fab")
			(hide yes)
			(effects
				(font
					(size 1.016 1.016)
					(thickness 0.1524)
				)
			)
		)
		(property "Device Type" "GPCE54362413HR"
			(at -32.935418 -16.144748 90)
			(unlocked yes)
			(layer "F.Fab")
			(hide yes)
			(effects
				(font
					(size 1.016 1.016)
					(thickness 0.1524)
				)
			)
		)
		(duplicate_pad_numbers_are_jumpers no)
		(fp_line
			(start -0.5334 -10.7696)
			(end -46.0502 -10.7696)
			(stroke
				(width 0.1524)
				(type default)
			)
			(layer "F.SilkS")
		)
		(fp_line
			(start -46.0502 -10.7696)
			(end -46.0502 -4.0132)
			(stroke
				(width 0.1524)
				(type default)
			)
			(layer "F.SilkS")
		)
		(fp_line
			(start 0.7874 -8.3058)
			(end -0.5334 -8.3058)
			(stroke
				(width 0.1524)
				(type default)
			)
			(layer "F.SilkS")
		)
		(fp_line
			(start -0.5334 -8.3058)
			(end -0.5334 -10.7696)
			(stroke
				(width 0.1524)
				(type default)
			)
			(layer "F.SilkS")
		)
		(fp_line
			(start 0.534924 -7.504938)
			(end 0.534924 -0.249936)
			(stroke
				(width 0.1524)
				(type default)
			)
			(layer "F.SilkS")
		)
		(fp_line
			(start 2.0066 -7.3533)
			(end 1.6256 -7.3533)
			(stroke
				(width 0.3302)
				(type default)
			)
			(layer "F.SilkS")
		)
		(fp_line
			(start 16.4465 -7.2644)
			(end 0.7874 -7.2644)
			(stroke
				(width 0.1524)
				(type default)
			)
			(layer "F.SilkS")
		)
		(fp_line
			(start 0.7874 -7.2644)
			(end 0.7874 -8.3058)
			(stroke
				(width 0.1524)
				(type default)
			)
			(layer "F.SilkS")
		)
		(fp_line
			(start 24.384 -4.0132)
			(end 16.4465 -4.0132)
			(stroke
				(width 0.1524)
				(type default)
			)
			(layer "F.SilkS")
		)
		(fp_line
			(start 16.4465 -4.0132)
			(end 16.4465 -7.2644)
			(stroke
				(width 0.1524)
				(type default)
			)
			(layer "F.SilkS")
		)
		(fp_line
			(start -46.0502 -4.0132)
			(end -54.2798 -4.0132)
			(stroke
				(width 0.1524)
				(type default)
			)
			(layer "F.SilkS")
		)
		(fp_line
			(start -54.2798 -4.0132)
			(end -54.2798 3.599942)
			(stroke
				(width 0.1524)
				(type default)
			)
			(layer "F.SilkS")
		)
		(fp_line
			(start 0.534924 -0.249936)
			(end 0.78486 0)
			(stroke
				(width 0.1524)
				(type default)
			)
			(layer "F.SilkS")
		)
		(fp_line
			(start -0.534924 -0.249936)
			(end -0.534924 -7.504938)
			(stroke
				(width 0.1524)
				(type default)
			)
			(layer "F.SilkS")
		)
		(fp_line
			(start 0.78486 0)
			(end 15.88008 0)
			(stroke
				(width 0.1524)
				(type default)
			)
			(layer "F.SilkS")
		)
		(fp_line
			(start -0.78486 0)
			(end -0.534924 -0.249936)
			(stroke
				(width 0.1524)
				(type default)
			)
			(layer "F.SilkS")
		)
		(fp_line
			(start -45.779944 0)
			(end -0.78486 0)
			(stroke
				(width 0.1524)
				(type default)
			)
			(layer "F.SilkS")
		)
		(fp_line
			(start 17.130014 1.249934)
			(end 17.130014 2.599944)
			(stroke
				(width 0.1524)
				(type default)
			)
			(layer "F.SilkS")
		)
		(fp_line
			(start 17.130014 2.599944)
			(end 18.130012 3.599942)
			(stroke
				(width 0.1524)
				(type default)
			)
			(layer "F.SilkS")
		)
		(fp_line
			(start -47.029878 2.599944)
			(end -47.029878 1.249934)
			(stroke
				(width 0.1524)
				(type default)
			)
			(layer "F.SilkS")
		)
		(fp_line
			(start 24.384 3.599942)
			(end 24.384 -4.0132)
			(stroke
				(width 0.1524)
				(type default)
			)
			(layer "F.SilkS")
		)
		(fp_line
			(start 18.130012 3.599942)
			(end 24.384 3.599942)
			(stroke
				(width 0.1524)
				(type default)
			)
			(layer "F.SilkS")
		)
		(fp_line
			(start -48.029876 3.599942)
			(end -47.029878 2.599944)
			(stroke
				(width 0.1524)
				(type default)
			)
			(layer "F.SilkS")
		)
		(fp_line
			(start -54.2798 3.599942)
			(end -48.029876 3.599942)
			(stroke
				(width 0.1524)
				(type default)
			)
			(layer "F.SilkS")
		)
		(fp_arc
			(start -0.534924 -7.504938)
			(mid 0 -8.039862)
			(end 0.534924 -7.504938)
			(stroke
				(width 0.1524)
				(type default)
			)
			(layer "F.SilkS")
		)
		(fp_arc
			(start 15.88008 0)
			(mid 16.763917 0.366097)
			(end 17.130014 1.249934)
			(stroke
				(width 0.1524)
				(type default)
			)
			(layer "F.SilkS")
		)
		(fp_arc
			(start -47.029878 1.249934)
			(mid -46.663781 0.366097)
			(end -45.779944 0)
			(stroke
				(width 0.1524)
				(type default)
			)
			(layer "F.SilkS")
		)
		(fp_poly
			(pts
				(xy 1.8288 -7.3406) (xy 1.3208 -7.8486) (xy 2.3368 -7.8486)
			)
			(stroke
				(width 0)
				(type default)
			)
			(fill yes)
			(layer "F.SilkS")
		)
		(fp_poly
			(pts
				(xy -5.144516 -7.006082) (xy -5.144516 -0.503936) (xy -0.775716 -0.503936) (xy -0.775716 -7.006082)
			)
			(stroke
				(width 0)
				(type default)
			)
			(fill yes)
			(layer "F.Paste")
		)
		(fp_poly
			(pts
				(xy -10.345166 -0.503682) (xy -5.855716 -0.503682) (xy -5.855716 -7.006082) (xy -10.345166 -7.006082)
			)
			(stroke
				(width 0)
				(type default)
			)
			(fill yes)
			(layer "F.Paste")
		)
		(fp_poly
			(pts
				(xy -15.304516 -0.503682) (xy -10.815066 -0.503682) (xy -10.815066 -7.006082) (xy -15.304516 -7.006082)
			)
			(stroke
				(width 0)
				(type default)
			)
			(fill yes)
			(layer "F.Paste")
		)
		(fp_poly
			(pts
				(xy -20.505166 -0.503682) (xy -16.015716 -0.503682) (xy -16.015716 -7.006082) (xy -20.505166 -7.006082)
			)
			(stroke
				(width 0)
				(type default)
			)
			(fill yes)
			(layer "F.Paste")
		)
		(fp_poly
			(pts
				(xy -25.464516 -0.503682) (xy -20.975066 -0.503682) (xy -20.975066 -7.006082) (xy -25.464516 -7.006082)
			)
			(stroke
				(width 0)
				(type default)
			)
			(fill yes)
			(layer "F.Paste")
		)
		(fp_poly
			(pts
				(xy -30.665166 -0.503682) (xy -26.175716 -0.503682) (xy -26.175716 -7.006082) (xy -30.665166 -7.006082)
			)
			(stroke
				(width 0)
				(type default)
			)
			(fill yes)
			(layer "F.Paste")
		)
		(fp_poly
			(pts
				(xy -35.624516 -0.503682) (xy -31.135066 -0.503682) (xy -31.135066 -7.006082) (xy -35.624516 -7.006082)
			)
			(stroke
				(width 0)
				(type default)
			)
			(fill yes)
			(layer "F.Paste")
		)
		(fp_poly
			(pts
				(xy -40.825166 -0.503682) (xy -36.335716 -0.503682) (xy -36.335716 -7.006082) (xy -40.825166 -7.006082)
			)
			(stroke
				(width 0)
				(type default)
			)
			(fill yes)
			(layer "F.Paste")
		)
		(fp_poly
			(pts
				(xy -45.784516 -0.503682) (xy -41.295066 -0.503682) (xy -41.295066 -7.006082) (xy -45.784516 -7.006082)
			)
			(stroke
				(width 0)
				(type default)
			)
			(fill yes)
			(layer "F.Paste")
		)
		(fp_poly
			(pts
				(xy -5.144516 -0.503936) (xy -0.775716 -0.503936) (xy -0.775716 -7.006082) (xy -5.144516 -7.006082)
			)
			(stroke
				(width 0)
				(type default)
			)
			(fill yes)
			(layer "B.Paste")
		)
		(fp_poly
			(pts
				(xy -10.345166 -0.503682) (xy -5.855716 -0.503682) (xy -5.855716 -7.006082) (xy -10.345166 -7.006082)
			)
			(stroke
				(width 0)
				(type default)
			)
			(fill yes)
			(layer "B.Paste")
		)
		(fp_poly
			(pts
				(xy -15.304516 -0.503682) (xy -10.815066 -0.503682) (xy -10.815066 -7.006082) (xy -15.304516 -7.006082)
			)
			(stroke
				(width 0)
				(type default)
			)
			(fill yes)
			(layer "B.Paste")
		)
		(fp_poly
			(pts
				(xy -20.505166 -0.503682) (xy -16.015716 -0.503682) (xy -16.015716 -7.006082) (xy -20.505166 -7.006082)
			)
			(stroke
				(width 0)
				(type default)
			)
			(fill yes)
			(layer "B.Paste")
		)
		(fp_poly
			(pts
				(xy -25.464516 -0.503682) (xy -20.975066 -0.503682) (xy -20.975066 -7.006082) (xy -25.464516 -7.006082)
			)
			(stroke
				(width 0)
				(type default)
			)
			(fill yes)
			(layer "B.Paste")
		)
		(fp_poly
			(pts
				(xy -30.665166 -0.503682) (xy -26.175716 -0.503682) (xy -26.175716 -7.006082) (xy -30.665166 -7.006082)
			)
			(stroke
				(width 0)
				(type default)
			)
			(fill yes)
			(layer "B.Paste")
		)
		(fp_poly
			(pts
				(xy -35.624516 -0.503682) (xy -31.135066 -0.503682) (xy -31.135066 -7.006082) (xy -35.624516 -7.006082)
			)
			(stroke
				(width 0)
				(type default)
			)
			(fill yes)
			(layer "B.Paste")
		)
		(fp_poly
			(pts
				(xy -40.825166 -0.503682) (xy -36.335716 -0.503682) (xy -36.335716 -7.006082) (xy -40.825166 -7.006082)
			)
			(stroke
				(width 0)
				(type default)
			)
			(fill yes)
			(layer "B.Paste")
		)
		(fp_poly
			(pts
				(xy -45.784516 -0.503682) (xy -41.295066 -0.503682) (xy -41.295066 -7.006082) (xy -45.784516 -7.006082)
			)
			(stroke
				(width 0)
				(type default)
			)
			(fill yes)
			(layer "B.Paste")
		)
		(fp_poly
			(pts
				(xy -48.9204 15.24) (xy -48.9204 3.7338) (xy -54.0258 3.7338) (xy -54.0258 -3.7592) (xy -45.4025 -3.7592)
				(xy -45.4025 -7.0104) (xy 15.9893 -7.0104) (xy 15.9893 -3.7592) (xy 24.13 -3.7592) (xy 24.13 3.7338)
				(xy 20.1676 3.7338) (xy 20.1676 15.24)
			)
			(stroke
				(width 0)
				(type default)
			)
			(fill no)
			(layer "B.CrtYd")
		)
		(fp_poly
			(pts
				(xy -49.4284 15.748) (xy -49.4284 4.2418) (xy -54.5338 4.2418) (xy -54.5338 -4.2672) (xy -46.3042 -4.2672)
				(xy -46.3042 -11.0236) (xy -0.2794 -11.0236) (xy -0.2794 -8.5598) (xy 1.0414 -8.5598) (xy 1.0414 -7.5184)
				(xy 16.7005 -7.5184) (xy 16.7005 -4.2672) (xy 24.638 -4.2672) (xy 24.638 4.2418) (xy 20.6756 4.2418)
				(xy 20.6756 15.748) (xy -14.94282 15.748) (xy -14.94282 15.24) (xy 20.1676 15.24) (xy 20.1676 3.7338)
				(xy 24.13 3.7338) (xy 24.13 -3.7592) (xy 15.9893 -3.7592) (xy 15.9893 -7.0104) (xy -45.4025 -7.0104)
				(xy -45.4025 -3.7592) (xy -54.0258 -3.7592) (xy -54.0258 3.7338) (xy -48.9204 3.7338) (xy -48.9204 15.24)
				(xy -14.9479 15.24) (xy -14.9479 15.748)
			)
			(stroke
				(width 0)
				(type default)
			)
			(fill no)
			(layer "B.CrtYd")
		)
		(fp_poly
			(pts
				(xy -48.9204 15.24) (xy -48.9204 3.7338) (xy -54.0258 3.7338) (xy -54.0258 -3.7592) (xy -45.4025 -3.7592)
				(xy -45.4025 -7.0104) (xy 15.9893 -7.0104) (xy 15.9893 -3.7592) (xy 24.13 -3.7592) (xy 24.13 3.7338)
				(xy 20.1676 3.7338) (xy 20.1676 15.24)
			)
			(stroke
				(width 0)
				(type default)
			)
			(fill no)
			(layer "F.CrtYd")
		)
		(fp_poly
			(pts
				(xy -49.4284 15.748) (xy -49.4284 4.2418) (xy -54.5338 4.2418) (xy -54.5338 -4.2672) (xy -46.3042 -4.2672)
				(xy -46.3042 -11.0236) (xy -0.2794 -11.0236) (xy -0.2794 -8.5598) (xy 1.0414 -8.5598) (xy 1.0414 -7.5184)
				(xy 16.7005 -7.5184) (xy 16.7005 -4.2672) (xy 24.638 -4.2672) (xy 24.638 4.2418) (xy 20.6756 4.2418)
				(xy 20.6756 15.748) (xy -14.94282 15.748) (xy -14.94282 15.24) (xy 20.1676 15.24) (xy 20.1676 3.7338)
				(xy 24.13 3.7338) (xy 24.13 -3.7592) (xy 15.9893 -3.7592) (xy 15.9893 -7.0104) (xy -45.4025 -7.0104)
				(xy -45.4025 -3.7592) (xy -54.0258 -3.7592) (xy -54.0258 3.7338) (xy -48.9204 3.7338) (xy -48.9204 15.24)
				(xy -14.9479 15.24) (xy -14.9479 15.748)
			)
			(stroke
				(width 0)
				(type default)
			)
			(fill no)
			(layer "F.CrtYd")
		)
		(fp_poly
			(pts
				(xy -49.4284 15.748) (xy -49.4284 4.2418) (xy -54.5338 4.2418) (xy -54.5338 -4.2672) (xy -46.3042 -4.2672)
				(xy -46.3042 -11.0236) (xy -0.2794 -11.0236) (xy -0.2794 -8.5598) (xy 1.0414 -8.5598) (xy 1.0414 -7.5184)
				(xy 16.7005 -7.5184) (xy 16.7005 -4.2672) (xy 24.638 -4.2672) (xy 24.638 4.2418) (xy 20.6756 4.2418)
				(xy 20.6756 15.748)
			)
			(stroke
				(width 0)
				(type default)
			)
			(fill no)
			(layer "B.Fab")
		)
		(fp_poly
			(pts
				(xy -49.4284 15.748) (xy -49.4284 4.2418) (xy -54.5338 4.2418) (xy -54.5338 -4.2672) (xy -46.3042 -4.2672)
				(xy -46.3042 -11.0236) (xy -0.2794 -11.0236) (xy -0.2794 -8.5598) (xy 1.0414 -8.5598) (xy 1.0414 -7.5184)
				(xy 16.7005 -7.5184) (xy 16.7005 -4.2672) (xy 24.638 -4.2672) (xy 24.638 4.2418) (xy 20.6756 4.2418)
				(xy 20.6756 15.748)
			)
			(stroke
				(width 0)
				(type default)
			)
			(fill no)
			(layer "F.Fab")
		)
		(fp_text user "Slit"
			(at -17.4117 4.567936 90)
			(unlocked yes)
			(layer "F.SilkS")
			(effects
				(font
					(size 1.016 1.016)
					(thickness 0.1524)
				)
				(justify left)
			)
		)
		(fp_text user "02 Do not mirror"
			(at -25.019 6.993636 90)
			(unlocked yes)
			(layer "F.Fab")
			(effects
				(font
					(size 1.016 1.016)
					(thickness 0.1524)
				)
				(justify left)
			)
		)
		(pad "" np_thru_hole circle
			(at -50.279808 0 90)
			(size 0.254 0.254)
			(drill 3.7084)
			(layers "*.Cu" "*.Mask")
			(clearance 2.0828)
			(thermal_gap 2.0828)
		)
		(pad "" np_thru_hole circle
			(at 20.379944 0 90)
			(size 0.254 0.254)
			(drill 3.7084)
			(layers "*.Cu" "*.Mask")
			(clearance 2.0828)
			(thermal_gap 2.0828)
		)
		(pad "P1" smd rect
			(at -42.164 -8.377682 90)
			(size 0.0254 0.0254)
			(layers "F.Cu" "F.Mask" "F.Paste")
			(net "P12V")
		)
		(pad "P2" smd custom
			(at -41.060116 -8.377682 90)
			(size 2.3622 2.3622)
			(layers "F.Cu" "F.Mask" "F.Paste")
			(net "P12V")
			(options
				(clearance outline)
				(anchor circle)
			)
			(primitives
				(gr_poly
					(pts
						(xy -4.7244 5.0038) (xy -4.7244 -5.0038) (xy 4.7244 -5.0038) (xy 4.7244 5.0038) (xy 0.23495 5.0038)
						(xy 0.23495 -1.4986) (xy -0.23495 -1.4986) (xy -0.23495 5.0038)
					)
					(width 0)
					(fill yes)
				)
			)
		)
		(pad "P3" smd rect
			(at -39.878 -8.377682 90)
			(size 0.0254 0.0254)
			(layers "F.Cu" "F.Mask" "F.Paste")
			(net "P12V")
		)
		(pad "P4" smd rect
			(at -38.862 -8.377682 90)
			(size 0.0254 0.0254)
			(layers "F.Cu" "F.Mask" "F.Paste")
			(net "P12V")
		)
		(pad "P5" smd rect
			(at -32.004 -8.377682 90)
			(size 0.0254 0.0254)
			(layers "F.Cu" "F.Mask" "F.Paste")
			(net "P12V")
		)
		(pad "P6" smd custom
			(at -30.900116 -8.377682 90)
			(size 2.3622 2.3622)
			(layers "F.Cu" "F.Mask" "F.Paste")
			(net "P12V")
			(options
				(clearance outline)
				(anchor circle)
			)
			(primitives
				(gr_poly
					(pts
						(xy -4.7244 5.0038) (xy -4.7244 -5.0038) (xy 4.7244 -5.0038) (xy 4.7244 5.0038) (xy 0.23495 5.0038)
						(xy 0.23495 -1.4986) (xy -0.23495 -1.4986) (xy -0.23495 5.0038)
					)
					(width 0)
					(fill yes)
				)
			)
		)
		(pad "P7" smd rect
			(at -29.718 -8.377682 90)
			(size 0.0254 0.0254)
			(layers "F.Cu" "F.Mask" "F.Paste")
			(net "P12V")
		)
		(pad "P8" smd rect
			(at -28.702 -8.377682 90)
			(size 0.0254 0.0254)
			(layers "F.Cu" "F.Mask" "F.Paste")
			(net "P12V")
		)
		(pad "P9" smd rect
			(at -22.098 -8.377682 90)
			(size 0.0254 0.0254)
			(layers "F.Cu" "F.Mask" "F.Paste")
			(net "GND")
		)
		(pad "P10" smd custom
			(at -20.740116 -8.377682 90)
			(size 2.3622 2.3622)
			(layers "F.Cu" "F.Mask" "F.Paste")
			(net "GND")
			(options
				(clearance outline)
				(anchor circle)
			)
			(primitives
				(gr_poly
					(pts
						(xy -4.7244 5.0038) (xy -4.7244 -5.0038) (xy 4.7244 -5.0038) (xy 4.7244 5.0038) (xy 0.23495 5.0038)
						(xy 0.23495 -1.4986) (xy -0.23495 -1.4986) (xy -0.23495 5.0038)
					)
					(width 0)
					(fill yes)
				)
			)
		)
		(pad "P11" smd rect
			(at -19.558 -8.377682 90)
			(size 0.0254 0.0254)
			(layers "F.Cu" "F.Mask" "F.Paste")
			(net "GND")
		)
		(pad "P12" smd rect
			(at -18.542 -8.377682 90)
			(size 0.0254 0.0254)
			(layers "F.Cu" "F.Mask" "F.Paste")
			(net "GND")
		)
		(pad "P13" smd rect
			(at -11.938 -8.377682 90)
			(size 0.0254 0.0254)
			(layers "F.Cu" "F.Mask" "F.Paste")
			(net "GND")
		)
		(pad "P14" smd custom
			(at -10.580116 -8.377682 90)
			(size 2.3622 2.3622)
			(layers "F.Cu" "F.Mask" "F.Paste")
			(net "GND")
			(options
				(clearance outline)
				(anchor circle)
			)
			(primitives
				(gr_poly
					(pts
						(xy -4.7244 5.0038) (xy -4.7244 -5.0038) (xy 4.7244 -5.0038) (xy 4.7244 5.0038) (xy 0.23495 5.0038)
						(xy 0.23495 -1.4986) (xy -0.23495 -1.4986) (xy -0.23495 5.0038)
					)
					(width 0)
					(fill yes)
				)
			)
		)
		(pad "P15" smd rect
			(at -9.144 -8.377682 90)
			(size 0.0254 0.0254)
			(layers "F.Cu" "F.Mask" "F.Paste")
			(net "GND")
		)
		(pad "P16" smd rect
			(at -7.874 -8.377682 90)
			(size 0.0254 0.0254)
			(layers "F.Cu" "F.Mask" "F.Paste")
			(net "GND")
		)
		(pad "P17" smd rect
			(at -2.960116 -5.126736 90)
			(size 4.3688 10.0076)
			(drill
				(offset 0 -0.381)
			)
			(layers "F.Cu" "F.Mask" "F.Paste")
			(net "GND")
		)
		(pad "P18" smd rect
			(at -2.032 -5.126736 90)
			(size 0.0254 0.0254)
			(layers "F.Cu" "F.Mask" "F.Paste")
			(net "GND")
		)
		(pad "P19" smd rect
			(at -2.032 -5.507736 90)
			(size 0.0254 0.0254)
			(layers "F.Cu" "F.Mask" "F.Paste")
			(net "GND")
		)
		(pad "P20" smd rect
			(at -2.960116 -5.507736 90)
			(size 4.3688 10.0076)
			(layers "F.Cu" "F.Mask" "F.Paste")
			(net "GND")
		)
		(pad "P21" smd rect
			(at -7.874 -8.758682 90)
			(size 0.0254 0.0254)
			(layers "F.Cu" "F.Mask" "F.Paste")
			(net "GND")
		)
		(pad "P22" smd rect
			(at -9.144 -8.758682 90)
			(size 0.0254 0.0254)
			(layers "F.Cu" "F.Mask" "F.Paste")
			(net "GND")
		)
		(pad "P23" smd custom
			(at -10.580116 -8.758682 90)
			(size 2.3622 2.3622)
			(layers "F.Cu" "F.Mask" "F.Paste")
			(net "GND")
			(options
				(clearance outline)
				(anchor circle)
			)
			(primitives
				(gr_poly
					(pts
						(xy -4.7244 5.0038) (xy -4.7244 -5.0038) (xy 4.7244 -5.0038) (xy 4.7244 5.0038) (xy 0.23495 5.0038)
						(xy 0.23495 -1.4986) (xy -0.23495 -1.4986) (xy -0.23495 5.0038)
					)
					(width 0)
					(fill yes)
				)
			)
		)
		(pad "P24" smd rect
			(at -11.938 -8.758682 90)
			(size 0.0254 0.0254)
			(layers "F.Cu" "F.Mask" "F.Paste")
			(net "GND")
		)
		(pad "P25" smd rect
			(at -18.542 -8.758682 90)
			(size 0.0254 0.0254)
			(layers "F.Cu" "F.Mask" "F.Paste")
			(net "GND")
		)
		(pad "P26" smd rect
			(at -19.558 -8.758682 90)
			(size 0.0254 0.0254)
			(layers "F.Cu" "F.Mask" "F.Paste")
			(net "GND")
		)
		(pad "P27" smd custom
			(at -20.740116 -8.758682 90)
			(size 2.3622 2.3622)
			(layers "F.Cu" "F.Mask" "F.Paste")
			(net "GND")
			(options
				(clearance outline)
				(anchor circle)
			)
			(primitives
				(gr_poly
					(pts
						(xy -4.7244 5.0038) (xy -4.7244 -5.0038) (xy 4.7244 -5.0038) (xy 4.7244 5.0038) (xy 0.23495 5.0038)
						(xy 0.23495 -1.4986) (xy -0.23495 -1.4986) (xy -0.23495 5.0038)
					)
					(width 0)
					(fill yes)
				)
			)
		)
		(pad "P28" smd rect
			(at -22.098 -8.758682 90)
			(size 0.0254 0.0254)
			(layers "F.Cu" "F.Mask" "F.Paste")
			(net "GND")
		)
		(pad "P29" smd rect
			(at -28.702 -8.758682 90)
			(size 0.0254 0.0254)
			(layers "F.Cu" "F.Mask" "F.Paste")
			(net "P12V")
		)
		(pad "P30" smd rect
			(at -29.718 -8.758682 90)
			(size 0.0254 0.0254)
			(layers "F.Cu" "F.Mask" "F.Paste")
			(net "P12V")
		)
		(pad "P31" smd custom
			(at -30.900116 -8.758682 90)
			(size 2.3622 2.3622)
			(layers "F.Cu" "F.Mask" "F.Paste")
			(net "P12V")
			(options
				(clearance outline)
				(anchor circle)
			)
			(primitives
				(gr_poly
					(pts
						(xy -4.7244 5.0038) (xy -4.7244 -5.0038) (xy 4.7244 -5.0038) (xy 4.7244 5.0038) (xy 0.23495 5.0038)
						(xy 0.23495 -1.4986) (xy -0.23495 -1.4986) (xy -0.23495 5.0038)
					)
					(width 0)
					(fill yes)
				)
			)
		)
		(pad "P32" smd rect
			(at -32.004 -8.758682 90)
			(size 0.0254 0.0254)
			(layers "F.Cu" "F.Mask" "F.Paste")
			(net "P12V")
		)
		(pad "P33" smd rect
			(at -38.862 -8.758682 90)
			(size 0.0254 0.0254)
			(layers "F.Cu" "F.Mask" "F.Paste")
			(net "P12V")
		)
		(pad "P34" smd rect
			(at -39.878 -8.758682 90)
			(size 0.0254 0.0254)
			(layers "F.Cu" "F.Mask" "F.Paste")
			(net "P12V")
		)
		(pad "P35" smd custom
			(at -41.060116 -8.758682 90)
			(size 2.3622 2.3622)
			(layers "F.Cu" "F.Mask" "F.Paste")
			(net "P12V")
			(options
				(clearance outline)
				(anchor circle)
			)
			(primitives
				(gr_poly
					(pts
						(xy -4.7244 5.0038) (xy -4.7244 -5.0038) (xy 4.7244 -5.0038) (xy 4.7244 5.0038) (xy 0.23495 5.0038)
						(xy 0.23495 -1.4986) (xy -0.23495 -1.4986) (xy -0.23495 5.0038)
					)
					(width 0)
					(fill yes)
				)
			)
		)
		(pad "P36" smd rect
			(at -42.164 -8.758682 90)
			(size 0.0254 0.0254)
			(layers "F.Cu" "F.Mask" "F.Paste")
			(net "P12V")
		)
		(pad "S1" smd rect
			(at 1.810004 -3.805936 90)
			(size 0.8128 5.842)
			(drill
				(offset 0 0.381)
			)
			(layers "F.Cu" "F.Mask" "F.Paste")
			(net "GND")
		)
		(pad "S2" smd rect
			(at 3.080004 -3.805936 90)
			(size 0.8128 5.842)
			(drill
				(offset 0 0.381)
			)
			(layers "F.Cu" "F.Mask" "F.Paste")
			(net "P3V3")
		)
		(pad "S3" smd rect
			(at 4.350004 -3.805936 90)
			(size 0.8128 5.842)
			(drill
				(offset 0 0.381)
			)
			(layers "F.Cu" "F.Mask" "F.Paste")
			(net "P3V3")
		)
		(pad "S4" smd rect
			(at 5.620004 -3.805936 90)
			(size 0.8128 5.842)
			(drill
				(offset 0 0.381)
			)
			(layers "F.Cu" "F.Mask" "F.Paste")
			(net "PEER_TRAY_PRESENT")
		)
		(pad "S5" smd rect
			(at 6.890004 -3.805936 90)
			(size 0.8128 5.842)
			(drill
				(offset 0 0.381)
			)
			(layers "F.Cu" "F.Mask" "F.Paste")
			(net "PWM_EXP_B")
		)
		(pad "S6" smd rect
			(at 8.160004 -3.805936 90)
			(size 0.8128 5.842)
			(drill
				(offset 0 0.381)
			)
			(layers "F.Cu" "F.Mask" "F.Paste")
			(net "SELF_TRAY_PRESENT")
		)
		(pad "S7" smd rect
			(at 9.430004 -3.805936 90)
			(size 0.8128 5.842)
			(drill
				(offset 0 0.381)
			)
			(layers "F.Cu" "F.Mask" "F.Paste")
			(net "PWM_EXP_A")
		)
		(pad "S8" smd rect
			(at 10.700004 -3.805936 90)
			(size 0.8128 5.842)
			(drill
				(offset 0 0.381)
			)
			(layers "F.Cu" "F.Mask" "F.Paste")
			(net "GND")
		)
		(pad "S9" smd rect
			(at 11.970004 -3.805936 90)
			(size 0.8128 5.842)
			(drill
				(offset 0 0.381)
			)
			(layers "F.Cu" "F.Mask" "F.Paste")
			(net "I2C_C_SDA")
		)
		(pad "S10" smd rect
			(at 13.240004 -3.805936 90)
			(size 0.8128 5.842)
			(drill
				(offset 0 0.381)
			)
			(layers "F.Cu" "F.Mask" "F.Paste")
			(net "GND")
		)
		(pad "S11" smd rect
			(at 14.510004 -3.805936 90)
			(size 0.8128 5.842)
			(drill
				(offset 0 0.381)
			)
			(layers "F.Cu" "F.Mask" "F.Paste")
			(net "I2C_C_SCL")
		)
		(pad "S12" smd rect
			(at 15.780004 -3.805936 90)
			(size 0.8128 5.842)
			(drill
				(offset 0 0.381)
			)
			(layers "F.Cu" "F.Mask" "F.Paste")
			(net "GND")
		)
		(pad "S13" smd rect
			(at 15.780004 -3.424936 90)
			(size 0.8128 5.842)
			(layers "F.Cu" "F.Mask" "F.Paste")
			(net "GND")
		)
		(pad "S14" smd rect
			(at 14.510004 -3.424936 90)
			(size 0.8128 5.842)
			(layers "F.Cu" "F.Mask" "F.Paste")
			(net "SELF_1A&2A_HB")
		)
		(pad "S15" smd rect
			(at 13.240004 -3.424936 90)
			(size 0.8128 5.842)
			(layers "F.Cu" "F.Mask" "F.Paste")
			(net "SELF_1B&2B_HB")
		)
		(pad "S16" smd rect
			(at 11.970004 -3.424936 90)
			(size 0.8128 5.842)
			(layers "F.Cu" "F.Mask" "F.Paste")
			(net "TRAY_ID")
		)
		(pad "S17" smd rect
			(at 10.700004 -3.424936 90)
			(size 0.8128 5.842)
			(layers "F.Cu" "F.Mask" "F.Paste")
			(net "FCB_HW_REV")
		)
		(pad "S18" smd rect
			(at 9.430004 -3.424936 90)
			(size 0.8128 5.842)
			(layers "F.Cu" "F.Mask" "F.Paste")
			(net "SD_LATCH_RELEASE")
		)
		(pad "S19" smd rect
			(at 8.160004 -3.424936 90)
			(size 0.8128 5.842)
			(layers "F.Cu" "F.Mask" "F.Paste")
			(net "GND")
		)
		(pad "S20" smd rect
			(at 6.890004 -3.424936 90)
			(size 0.8128 5.842)
			(layers "F.Cu" "F.Mask" "F.Paste")
			(net "PEER_1A&2A_HB")
		)
		(pad "S21" smd rect
			(at 5.620004 -3.424936 90)
			(size 0.8128 5.842)
			(layers "F.Cu" "F.Mask" "F.Paste")
			(net "PEER_1B&2B_HB")
		)
		(pad "S22" smd rect
			(at 4.350004 -3.424936 90)
			(size 0.8128 5.842)
			(layers "F.Cu" "F.Mask" "F.Paste")
			(net "GND")
		)
		(pad "S23" smd rect
			(at 3.080004 -3.424936 90)
			(size 0.8128 5.842)
			(layers "F.Cu" "F.Mask" "F.Paste")
			(net "GND")
		)
		(pad "S24" smd rect
			(at 1.810004 -3.424936 90)
			(size 0.8128 5.842)
			(layers "F.Cu" "F.Mask" "F.Paste")
			(net "P5VA")
		)
		(zone
			(layers "F.Cu" "B.Cu" "In1.Cu" "In2.Cu" "In3.Cu" "In4.Cu" "In5.Cu" "In6.Cu")
			(hatch none 0.5)
			(connect_pads
				(clearance 0)
			)
			(min_thickness 0.25)
			(keepout
				(tracks not_allowed)
				(vias allowed)
				(pads allowed)
				(copperpour not_allowed)
				(footprints allowed)
			)
			(placement
				(enabled no)
				(sheetname "")
			)
			(fill
				(thermal_gap 0.5)
				(thermal_bridge_width 0.5)
				(island_removal_mode 0)
			)
			(polygon
				(pts
					(arc
						(start 261.058914 -430.329848)
						(mid 256.740914 -430.329848)
						(end 261.058914 -430.329848)
					)
				)
			)
		)
		(zone
			(layers "F.Cu" "B.Cu" "In1.Cu" "In2.Cu" "In3.Cu" "In4.Cu" "In5.Cu" "In6.Cu")
			(hatch none 0.5)
			(connect_pads
				(clearance 0)
			)
			(min_thickness 0.25)
			(keepout
				(tracks not_allowed)
				(vias allowed)
				(pads allowed)
				(copperpour not_allowed)
				(footprints allowed)
			)
			(placement
				(enabled no)
				(sheetname "")
			)
			(fill
				(thermal_gap 0.5)
				(thermal_bridge_width 0.5)
				(island_removal_mode 0)
			)
			(polygon
				(pts
					(arc
						(start 261.058914 -359.670096)
						(mid 256.740914 -359.670096)
						(end 261.058914 -359.670096)
					)
				)
			)
		)
	)
	(footprint ""
		(layer "F.Cu")
		(at 17.500092 -232.32999 -90)
		(property "Reference" "SKT13"
			(at 0 0 270)
			(layer "F.SilkS")
			(hide yes)
			(effects
				(font
					(size 1.27 1.27)
				)
			)
		)
		(property "Value" "SKT-SATA14P-15P-12-GP"
			(at -22.6187 8.1788 270)
			(unlocked yes)
			(layer "F.Fab")
			(hide yes)
			(effects
				(font
					(size 1.016 1.016)
					(thickness 0.1524)
				)
			)
		)
		(property "Device Type" "87945-1001"
			(at -22.6187 6.6548 270)
			(unlocked yes)
			(layer "F.Fab")
			(hide yes)
			(effects
				(font
					(size 1.016 1.016)
					(thickness 0.1524)
				)
			)
		)
		(duplicate_pad_numbers_are_jumpers no)
		(fp_line
			(start -20.4724 9.652)
			(end -20.4724 2.3114)
			(stroke
				(width 0.1524)
				(type default)
			)
			(layer "F.SilkS")
		)
		(fp_line
			(start -17.8435 9.652)
			(end -20.4724 9.652)
			(stroke
				(width 0.1524)
				(type default)
			)
			(layer "F.SilkS")
		)
		(fp_line
			(start 17.8435 9.652)
			(end 17.8435 7.9502)
			(stroke
				(width 0.1524)
				(type default)
			)
			(layer "F.SilkS")
		)
		(fp_line
			(start 20.4724 9.652)
			(end 17.8435 9.652)
			(stroke
				(width 0.1524)
				(type default)
			)
			(layer "F.SilkS")
		)
		(fp_line
			(start -17.8435 7.9502)
			(end -17.8435 9.652)
			(stroke
				(width 0.1524)
				(type default)
			)
			(layer "F.SilkS")
		)
		(fp_line
			(start 17.8435 7.9502)
			(end -17.8435 7.9502)
			(stroke
				(width 0.1524)
				(type default)
			)
			(layer "F.SilkS")
		)
		(fp_line
			(start -23.7617 2.3114)
			(end -23.7617 -2.3114)
			(stroke
				(width 0.1524)
				(type default)
			)
			(layer "F.SilkS")
		)
		(fp_line
			(start -20.4724 2.3114)
			(end -23.7617 2.3114)
			(stroke
				(width 0.1524)
				(type default)
			)
			(layer "F.SilkS")
		)
		(fp_line
			(start 20.4724 2.3114)
			(end 20.4724 9.652)
			(stroke
				(width 0.1524)
				(type default)
			)
			(layer "F.SilkS")
		)
		(fp_line
			(start 23.7617 2.3114)
			(end 20.4724 2.3114)
			(stroke
				(width 0.1524)
				(type default)
			)
			(layer "F.SilkS")
		)
		(fp_line
			(start -23.117556 0.5461)
			(end -23.117556 -0.5461)
			(stroke
				(width 0.3048)
				(type default)
			)
			(layer "F.SilkS")
		)
		(fp_line
			(start 20.882356 0.5461)
			(end 20.882356 -0.5461)
			(stroke
				(width 0.3048)
				(type default)
			)
			(layer "F.SilkS")
		)
		(fp_line
			(start -20.882356 -0.5461)
			(end -20.882356 0.5461)
			(stroke
				(width 0.3048)
				(type default)
			)
			(layer "F.SilkS")
		)
		(fp_line
			(start 23.117556 -0.5461)
			(end 23.117556 0.5461)
			(stroke
				(width 0.3048)
				(type default)
			)
			(layer "F.SilkS")
		)
		(fp_line
			(start -23.7617 -2.3114)
			(end -20.4724 -2.3114)
			(stroke
				(width 0.1524)
				(type default)
			)
			(layer "F.SilkS")
		)
		(fp_line
			(start -20.4724 -2.3114)
			(end -20.4724 -5.7658)
			(stroke
				(width 0.1524)
				(type default)
			)
			(layer "F.SilkS")
		)
		(fp_line
			(start 20.4724 -2.3114)
			(end 23.7617 -2.3114)
			(stroke
				(width 0.1524)
				(type default)
			)
			(layer "F.SilkS")
		)
		(fp_line
			(start 23.7617 -2.3114)
			(end 23.7617 2.3114)
			(stroke
				(width 0.1524)
				(type default)
			)
			(layer "F.SilkS")
		)
		(fp_line
			(start -20.4724 -5.7658)
			(end 20.4724 -5.7658)
			(stroke
				(width 0.1524)
				(type default)
			)
			(layer "F.SilkS")
		)
		(fp_line
			(start 20.4724 -5.7658)
			(end 20.4724 -2.3114)
			(stroke
				(width 0.1524)
				(type default)
			)
			(layer "F.SilkS")
		)
		(fp_line
			(start -15.3924 -5.8547)
			(end -16.3576 -5.8547)
			(stroke
				(width 0.3302)
				(type default)
			)
			(layer "F.SilkS")
		)
		(fp_arc
			(start -20.882356 0.5461)
			(mid -21.999956 1.6637)
			(end -23.117556 0.5461)
			(stroke
				(width 0.3048)
				(type default)
			)
			(layer "F.SilkS")
		)
		(fp_arc
			(start 23.117556 0.5461)
			(mid 21.999956 1.6637)
			(end 20.882356 0.5461)
			(stroke
				(width 0.3048)
				(type default)
			)
			(layer "F.SilkS")
		)
		(fp_arc
			(start -23.117556 -0.5461)
			(mid -21.999956 -1.6637)
			(end -20.882356 -0.5461)
			(stroke
				(width 0.3048)
				(type default)
			)
			(layer "F.SilkS")
		)
		(fp_arc
			(start 20.882356 -0.5461)
			(mid 21.999956 -1.6637)
			(end 23.117556 -0.5461)
			(stroke
				(width 0.3048)
				(type default)
			)
			(layer "F.SilkS")
		)
		(fp_poly
			(pts
				(xy -15.87119 -5.838698) (xy -15.23619 -6.473698) (xy -16.50619 -6.473698)
			)
			(stroke
				(width 0)
				(type default)
			)
			(fill yes)
			(layer "F.SilkS")
		)
		(fp_poly
			(pts
				(xy -20.2184 -5.5118) (xy 20.2184 -5.5118) (xy 20.2184 -2.0574) (xy 23.5077 -2.0574) (xy 23.5077 2.0574)
				(xy 20.2184 2.0574) (xy 20.2184 9.398) (xy 18.0975 9.398) (xy 18.0975 7.6962) (xy -18.0975 7.6962)
				(xy -18.0975 9.398) (xy -20.2184 9.398) (xy -20.2184 2.0574) (xy -23.5077 2.0574) (xy -23.5077 -2.0574)
				(xy -20.2184 -2.0574)
			)
			(stroke
				(width 0)
				(type default)
			)
			(fill no)
			(layer "F.CrtYd")
		)
		(fp_poly
			(pts
				(xy -20.2184 -5.5118) (xy -20.2184 -6.0198) (xy -20.7264 -6.0198) (xy -20.7264 -2.5654) (xy -24.0157 -2.5654)
				(xy -24.0157 2.5654) (xy -20.7264 2.5654) (xy -20.7264 9.906) (xy -17.5895 9.906) (xy -17.5895 8.2042)
				(xy 17.5895 8.2042) (xy 17.5895 9.906) (xy 20.7264 9.906) (xy 20.7264 2.5654) (xy 24.0157 2.5654)
				(xy 24.0157 -2.5654) (xy 20.7264 -2.5654) (xy 20.7264 -6.0198) (xy -20.21586 -6.0198) (xy -20.21586 -5.5118)
				(xy 20.2184 -5.5118) (xy 20.2184 -2.0574) (xy 23.5077 -2.0574) (xy 23.5077 2.0574) (xy 20.2184 2.0574)
				(xy 20.2184 9.398) (xy 18.0975 9.398) (xy 18.0975 7.6962) (xy -18.0975 7.6962) (xy -18.0975 9.398)
				(xy -20.2184 9.398) (xy -20.2184 2.0574) (xy -23.5077 2.0574) (xy -23.5077 -2.0574) (xy -20.2184 -2.0574)
			)
			(stroke
				(width 0)
				(type default)
			)
			(fill no)
			(layer "F.CrtYd")
		)
		(fp_poly
			(pts
				(xy -20.7264 -6.0198) (xy -20.7264 -2.5654) (xy -24.0157 -2.5654) (xy -24.0157 2.5654) (xy -20.7264 2.5654)
				(xy -20.7264 9.906) (xy -17.5895 9.906) (xy -17.5895 8.2042) (xy 17.5895 8.2042) (xy 17.5895 9.906)
				(xy 20.7264 9.906) (xy 20.7264 2.5654) (xy 24.0157 2.5654) (xy 24.0157 -2.5654) (xy 20.7264 -2.5654)
				(xy 20.7264 -6.0198)
			)
			(stroke
				(width 0)
				(type default)
			)
			(fill no)
			(layer "F.Fab")
		)
		(pad "" np_thru_hole circle
			(at -18.999962 -2.350008 270)
			(size 0.254 0.254)
			(drill 1.8542)
			(layers "*.Cu" "*.Mask")
			(clearance 1.1557)
			(thermal_gap 1.1557)
		)
		(pad "" np_thru_hole circle
			(at 18.999962 -2.350008 270)
			(size 0.254 0.254)
			(drill 1.8542)
			(layers "*.Cu" "*.Mask")
			(clearance 1.1557)
			(thermal_gap 1.1557)
		)
		(pad "H1" thru_hole oval
			(at -21.999956 0 270)
			(size 1.524 2.6162)
			(drill oval 0.8128 1.905)
			(layers "*.Cu" "*.Mask")
			(remove_unused_layers no)
			(net "GND")
			(clearance 0.1524)
			(thermal_gap 0.1524)
		)
		(pad "H2" thru_hole oval
			(at 21.999956 0 270)
			(size 1.524 2.6162)
			(drill oval 0.8128 1.905)
			(layers "*.Cu" "*.Mask")
			(remove_unused_layers no)
			(net "GND")
			(clearance 0.1524)
			(thermal_gap 0.1524)
		)
		(pad "P1" smd rect
			(at -1.89992 -4.249928 270)
			(size 0.6604 2.3876)
			(layers "F.Cu" "F.Mask" "F.Paste")
			(net "Net_55")
		)
		(pad "P2" smd rect
			(at -0.62992 -4.249928 270)
			(size 0.6604 2.3876)
			(layers "F.Cu" "F.Mask" "F.Paste")
			(net "Net_54")
		)
		(pad "P3" smd rect
			(at 0.64008 -4.249928 270)
			(size 0.6604 2.3876)
			(layers "F.Cu" "F.Mask" "F.Paste")
			(net "Net_53")
		)
		(pad "P4" smd rect
			(at 1.91008 -4.249928 270)
			(size 0.6604 2.3876)
			(layers "F.Cu" "F.Mask" "F.Paste")
			(net "GND")
		)
		(pad "P5" smd rect
			(at 3.18008 -4.249928 270)
			(size 0.6604 2.3876)
			(layers "F.Cu" "F.Mask" "F.Paste")
			(net "HDD_PRSNT_NET12")
		)
		(pad "P6" smd rect
			(at 4.45008 -4.249928 270)
			(size 0.6604 2.3876)
			(layers "F.Cu" "F.Mask" "F.Paste")
			(net "GND")
		)
		(pad "P7" smd rect
			(at 5.72008 -4.249928 270)
			(size 0.6604 2.3876)
			(layers "F.Cu" "F.Mask" "F.Paste")
			(net "5V_PRE_12")
		)
		(pad "P8" smd rect
			(at 6.99008 -4.249928 270)
			(size 0.6604 2.3876)
			(layers "F.Cu" "F.Mask" "F.Paste")
			(net "P5V_HDD12")
		)
		(pad "P9" smd rect
			(at 8.26008 -4.249928 270)
			(size 0.6604 2.3876)
			(layers "F.Cu" "F.Mask" "F.Paste")
			(net "P5V_HDD12")
		)
		(pad "P10" smd rect
			(at 9.53008 -4.249928 270)
			(size 0.6604 2.3876)
			(layers "F.Cu" "F.Mask" "F.Paste")
			(net "GND")
		)
		(pad "P11" smd rect
			(at 10.80008 -4.249928 270)
			(size 0.6604 2.3876)
			(layers "F.Cu" "F.Mask" "F.Paste")
			(net "ACT_HDD12")
		)
		(pad "P12" smd rect
			(at 12.07008 -4.249928 270)
			(size 0.6604 2.3876)
			(layers "F.Cu" "F.Mask" "F.Paste")
			(net "GND")
		)
		(pad "P13" smd rect
			(at 13.34008 -4.249928 270)
			(size 0.6604 2.3876)
			(layers "F.Cu" "F.Mask" "F.Paste")
			(net "12V_PRE_12")
		)
		(pad "P14" smd rect
			(at 14.61008 -4.249928 270)
			(size 0.6604 2.3876)
			(layers "F.Cu" "F.Mask" "F.Paste")
			(net "P12V_HDD12")
		)
		(pad "P15" smd rect
			(at 15.88008 -4.249928 270)
			(size 0.6604 2.3876)
			(layers "F.Cu" "F.Mask" "F.Paste")
			(net "P12V_HDD12")
		)
		(pad "S1" smd rect
			(at -15.86992 -4.249928 270)
			(size 0.6604 2.3876)
			(layers "F.Cu" "F.Mask" "F.Paste")
			(net "GND")
		)
		(pad "S2" smd rect
			(at -14.59992 -4.249928 270)
			(size 0.6604 2.3876)
			(layers "F.Cu" "F.Mask" "F.Paste")
			(net "SAS2X28_A_HDD12_TX_+")
		)
		(pad "S3" smd rect
			(at -13.32992 -4.249928 270)
			(size 0.6604 2.3876)
			(layers "F.Cu" "F.Mask" "F.Paste")
			(net "SAS2X28_A_HDD12_TX_-")
		)
		(pad "S4" smd rect
			(at -12.05992 -4.249928 270)
			(size 0.6604 2.3876)
			(layers "F.Cu" "F.Mask" "F.Paste")
			(net "GND")
		)
		(pad "S5" smd rect
			(at -10.78992 -4.249928 270)
			(size 0.6604 2.3876)
			(layers "F.Cu" "F.Mask" "F.Paste")
			(net "SAS2X28_DRIVE_RX_N_A12")
		)
		(pad "S6" smd rect
			(at -9.51992 -4.249928 270)
			(size 0.6604 2.3876)
			(layers "F.Cu" "F.Mask" "F.Paste")
			(net "SAS2X28_DRIVE_RX_P_A12")
		)
		(pad "S7" smd rect
			(at -8.24992 -4.249928 270)
			(size 0.6604 2.3876)
			(layers "F.Cu" "F.Mask" "F.Paste")
			(net "GND")
		)
		(pad "S8" smd rect
			(at -7.480046 -2.100072 270)
			(size 0.508 1.905)
			(layers "F.Cu" "F.Mask" "F.Paste")
			(net "GND")
		)
		(pad "S9" smd rect
			(at -6.679946 -2.100072 270)
			(size 0.508 1.905)
			(layers "F.Cu" "F.Mask" "F.Paste")
			(net "SAS2X28_B_HDD12_TX_+")
		)
		(pad "S10" smd rect
			(at -5.8801 -2.100072 270)
			(size 0.508 1.905)
			(layers "F.Cu" "F.Mask" "F.Paste")
			(net "SAS2X28_B_HDD12_TX_-")
		)
		(pad "S11" smd rect
			(at -5.08 -2.100072 270)
			(size 0.508 1.905)
			(layers "F.Cu" "F.Mask" "F.Paste")
			(net "GND")
		)
		(pad "S12" smd rect
			(at -4.2799 -2.100072 270)
			(size 0.508 1.905)
			(layers "F.Cu" "F.Mask" "F.Paste")
			(net "SAS2X28_DRIVE_RX_N_B12")
		)
		(pad "S13" smd rect
			(at -3.480054 -2.100072 270)
			(size 0.508 1.905)
			(layers "F.Cu" "F.Mask" "F.Paste")
			(net "SAS2X28_DRIVE_RX_P_B12")
		)
		(pad "S14" smd rect
			(at -2.679954 -2.100072 270)
			(size 0.508 1.905)
			(layers "F.Cu" "F.Mask" "F.Paste")
			(net "GND")
		)
		(zone
			(layers "F.Cu" "B.Cu" "In1.Cu" "In2.Cu" "In3.Cu" "In4.Cu" "In5.Cu" "In6.Cu")
			(hatch none 0.5)
			(connect_pads
				(clearance 0)
			)
			(min_thickness 0.25)
			(keepout
				(tracks not_allowed)
				(vias allowed)
				(pads allowed)
				(copperpour not_allowed)
				(footprints allowed)
			)
			(placement
				(enabled no)
				(sheetname "")
			)
			(fill
				(thermal_gap 0.5)
				(thermal_bridge_width 0.5)
				(island_removal_mode 0)
			)
			(polygon
				(pts
					(arc
						(start 21.082 -251.329952)
						(mid 18.6182 -251.329952)
						(end 21.082 -251.329952)
					)
				)
			)
		)
		(zone
			(layers "F.Cu" "B.Cu" "In1.Cu" "In2.Cu" "In3.Cu" "In4.Cu" "In5.Cu" "In6.Cu")
			(hatch none 0.5)
			(connect_pads
				(clearance 0)
			)
			(min_thickness 0.25)
			(keepout
				(tracks not_allowed)
				(vias allowed)
				(pads allowed)
				(copperpour not_allowed)
				(footprints allowed)
			)
			(placement
				(enabled no)
				(sheetname "")
			)
			(fill
				(thermal_gap 0.5)
				(thermal_bridge_width 0.5)
				(island_removal_mode 0)
			)
			(polygon
				(pts
					(arc
						(start 21.082 -213.330028)
						(mid 18.6182 -213.330028)
						(end 21.082 -213.330028)
					)
				)
			)
		)
	)
	(footprint ""
		(layer "F.Cu")
		(at 30.226 -288.29 180)
		(property "Reference" "R556"
			(at 0 0 180)
			(layer "F.SilkS")
			(hide yes)
			(effects
				(font
					(size 1.27 1.27)
				)
			)
		)
		(property "Value" "200KR2F-L-GP"
			(at 0.064008 -3.993896 180)
			(unlocked yes)
			(layer "F.Fab")
			(hide yes)
			(effects
				(font
					(size 1.016 1.016)
					(thickness 0.1524)
				)
			)
		)
		(property "Device Type" "R402H16"
			(at 0.064008 -5.517896 180)
			(unlocked yes)
			(layer "F.Fab")
			(hide yes)
			(effects
				(font
					(size 1.016 1.016)
					(thickness 0.1524)
				)
			)
		)
		(duplicate_pad_numbers_are_jumpers no)
		(fp_line
			(start 0.508 -0.9398)
			(end -0.508 -0.9398)
			(stroke
				(width 0.1524)
				(type default)
			)
			(layer "F.SilkS")
		)
		(fp_line
			(start -0.508 -0.9398)
			(end -0.508 0.9398)
			(stroke
				(width 0.1524)
				(type default)
			)
			(layer "F.SilkS")
		)
		(fp_rect
			(start -0.508 0.9398)
			(end 0.508 -0.9398)
			(stroke
				(width 0)
				(type default)
			)
			(fill no)
			(layer "F.CrtYd")
		)
		(fp_rect
			(start -0.508 0.9398)
			(end 0.508 -0.9398)
			(stroke
				(width 0)
				(type default)
			)
			(fill no)
			(layer "F.Fab")
		)
		(pad "1" smd custom
			(at 0 -0.4445 180)
			(size 0.1397 0.1397)
			(layers "F.Cu" "F.Mask" "F.Paste")
			(net "SW_HDD7_R")
			(options
				(clearance outline)
				(anchor circle)
			)
			(primitives
				(gr_poly
					(pts
						(arc
							(start -0.1778 -0.2794)
							(mid -0.249642 -0.249642)
							(end -0.2794 -0.1778)
						)
						(arc
							(start -0.2794 0.1778)
							(mid -0.249642 0.249642)
							(end -0.1778 0.2794)
						)
						(arc
							(start 0.1778 0.2794)
							(mid 0.249642 0.249642)
							(end 0.2794 0.1778)
						)
						(arc
							(start 0.2794 -0.1778)
							(mid 0.249642 -0.249642)
							(end 0.1778 -0.2794)
						)
					)
					(width 0)
					(fill yes)
				)
			)
		)
		(pad "2" smd custom
			(at 0 0.4445 180)
			(size 0.1397 0.1397)
			(layers "F.Cu" "F.Mask" "F.Paste")
			(net "SW_HDD7_N")
			(options
				(clearance outline)
				(anchor circle)
			)
			(primitives
				(gr_poly
					(pts
						(arc
							(start -0.1778 -0.2794)
							(mid -0.249642 -0.249642)
							(end -0.2794 -0.1778)
						)
						(arc
							(start -0.2794 0.1778)
							(mid -0.249642 0.249642)
							(end -0.1778 0.2794)
						)
						(arc
							(start 0.1778 0.2794)
							(mid 0.249642 0.249642)
							(end 0.2794 0.1778)
						)
						(arc
							(start 0.2794 -0.1778)
							(mid 0.249642 -0.249642)
							(end 0.1778 -0.2794)
						)
					)
					(width 0)
					(fill yes)
				)
			)
		)
	)
	(footprint ""
		(layer "F.Cu")
		(at 21.971 -278.765 -90)
		(property "Reference" "C219"
			(at 0 0 270)
			(layer "F.SilkS")
			(hide yes)
			(effects
				(font
					(size 1.27 1.27)
				)
			)
		)
		(property "Value" "SCD1U10V2KX-5GP"
			(at 1.1811 -2.7051 270)
			(unlocked yes)
			(layer "F.Fab")
			(hide yes)
			(effects
				(font
					(size 1.016 1.016)
					(thickness 0.1524)
				)
			)
		)
		(property "Device Type" "C402H22"
			(at 1.1811 -4.2291 270)
			(unlocked yes)
			(layer "F.Fab")
			(hide yes)
			(effects
				(font
					(size 1.016 1.016)
					(thickness 0.1524)
				)
			)
		)
		(duplicate_pad_numbers_are_jumpers no)
		(fp_rect
			(start -0.4318 0.9525)
			(end 0.4318 -0.9525)
			(stroke
				(width 0)
				(type default)
			)
			(fill no)
			(layer "F.CrtYd")
		)
		(fp_rect
			(start -0.4318 0.9525)
			(end 0.4318 -0.9525)
			(stroke
				(width 0)
				(type default)
			)
			(fill no)
			(layer "F.Fab")
		)
		(pad "1" smd custom
			(at 0 -0.4445 270)
			(size 0.1524 0.1524)
			(layers "F.Cu" "F.Mask" "F.Paste")
			(net "P3V3")
			(options
				(clearance outline)
				(anchor circle)
			)
			(primitives
				(gr_poly
					(pts
						(arc
							(start 0.3048 -0.2032)
							(mid 0.275042 -0.275042)
							(end 0.2032 -0.3048)
						)
						(arc
							(start -0.2032 -0.3048)
							(mid -0.275042 -0.275042)
							(end -0.3048 -0.2032)
						)
						(arc
							(start -0.3048 0.2032)
							(mid -0.275042 0.275042)
							(end -0.2032 0.3048)
						)
						(arc
							(start 0.2032 0.3048)
							(mid 0.275042 0.275042)
							(end 0.3048 0.2032)
						)
					)
					(width 0)
					(fill yes)
				)
			)
		)
		(pad "2" smd custom
			(at 0 0.4445 270)
			(size 0.1524 0.1524)
			(layers "F.Cu" "F.Mask" "F.Paste")
			(net "GND")
			(options
				(clearance outline)
				(anchor circle)
			)
			(primitives
				(gr_poly
					(pts
						(arc
							(start 0.3048 -0.2032)
							(mid 0.275042 -0.275042)
							(end 0.2032 -0.3048)
						)
						(arc
							(start -0.2032 -0.3048)
							(mid -0.275042 -0.275042)
							(end -0.3048 -0.2032)
						)
						(arc
							(start -0.3048 0.2032)
							(mid -0.275042 0.275042)
							(end -0.2032 0.3048)
						)
						(arc
							(start 0.2032 0.3048)
							(mid 0.275042 0.275042)
							(end 0.3048 0.2032)
						)
					)
					(width 0)
					(fill yes)
				)
			)
		)
	)
	(footprint ""
		(layer "F.Cu")
		(at 56.9722 -285.6738 180)
		(property "Reference" "C221"
			(at 0 0 180)
			(layer "F.SilkS")
			(hide yes)
			(effects
				(font
					(size 1.27 1.27)
				)
			)
		)
		(property "Value" "SC10U16V6KX-2GP"
			(at -0.0762 -5.1308 180)
			(unlocked yes)
			(layer "F.Fab")
			(hide yes)
			(effects
				(font
					(size 1.016 1.016)
					(thickness 0.1524)
				)
			)
		)
		(property "Device Type" "C1206H71"
			(at -0.127 -6.6548 180)
			(unlocked yes)
			(layer "F.Fab")
			(hide yes)
			(effects
				(font
					(size 1.016 1.016)
					(thickness 0.1524)
				)
			)
		)
		(duplicate_pad_numbers_are_jumpers no)
		(fp_line
			(start 1.016 2.2352)
			(end -1.016 2.2352)
			(stroke
				(width 0.1524)
				(type default)
			)
			(layer "F.SilkS")
		)
		(fp_line
			(start 1.016 0.8382)
			(end 1.016 2.2352)
			(stroke
				(width 0.1524)
				(type default)
			)
			(layer "F.SilkS")
		)
		(fp_line
			(start 1.016 -2.2352)
			(end 1.016 -0.8382)
			(stroke
				(width 0.1524)
				(type default)
			)
			(layer "F.SilkS")
		)
		(fp_line
			(start -1.016 2.2352)
			(end -1.016 0.8382)
			(stroke
				(width 0.1524)
				(type default)
			)
			(layer "F.SilkS")
		)
		(fp_line
			(start -1.016 -0.8382)
			(end -1.016 -2.2352)
			(stroke
				(width 0.1524)
				(type default)
			)
			(layer "F.SilkS")
		)
		(fp_line
			(start -1.016 -2.2352)
			(end 1.016 -2.2352)
			(stroke
				(width 0.1524)
				(type default)
			)
			(layer "F.SilkS")
		)
		(fp_rect
			(start -1.0922 2.3114)
			(end 1.0922 -2.3114)
			(stroke
				(width 0)
				(type default)
			)
			(fill no)
			(layer "F.CrtYd")
		)
		(fp_poly
			(pts
				(xy 1.0922 -2.3114) (xy 1.0922 2.3114) (xy -1.0922 2.3114) (xy -1.0922 -2.3114)
			)
			(stroke
				(width 0)
				(type default)
			)
			(fill no)
			(layer "F.Fab")
		)
		(pad "1" smd rect
			(at 0 -1.397 180)
			(size 1.651 1.27)
			(layers "F.Cu" "F.Mask" "F.Paste")
			(net "P5V_HDD7")
		)
		(pad "2" smd rect
			(at 0 1.397 180)
			(size 1.651 1.27)
			(layers "F.Cu" "F.Mask" "F.Paste")
			(net "GND")
		)
	)
	(footprint ""
		(layer "F.Cu")
		(at 29.400246 -432.463702 -90)
		(property "Reference" "R246"
			(at 0 0 270)
			(layer "F.SilkS")
			(hide yes)
			(effects
				(font
					(size 1.27 1.27)
				)
			)
		)
		(property "Value" "4K7R2J-2-GP"
			(at 0.064008 -3.993896 270)
			(unlocked yes)
			(layer "F.Fab")
			(hide yes)
			(effects
				(font
					(size 1.016 1.016)
					(thickness 0.1524)
				)
			)
		)
		(property "Device Type" "R402H16"
			(at 0.064008 -5.517896 270)
			(unlocked yes)
			(layer "F.Fab")
			(hide yes)
			(effects
				(font
					(size 1.016 1.016)
					(thickness 0.1524)
				)
			)
		)
		(duplicate_pad_numbers_are_jumpers no)
		(fp_line
			(start -0.508 -0.9398)
			(end -0.508 0.9398)
			(stroke
				(width 0.1524)
				(type default)
			)
			(layer "F.SilkS")
		)
		(fp_line
			(start 0.508 -0.9398)
			(end -0.508 -0.9398)
			(stroke
				(width 0.1524)
				(type default)
			)
			(layer "F.SilkS")
		)
		(fp_rect
			(start -0.508 0.9398)
			(end 0.508 -0.9398)
			(stroke
				(width 0)
				(type default)
			)
			(fill no)
			(layer "F.CrtYd")
		)
		(fp_rect
			(start -0.508 0.9398)
			(end 0.508 -0.9398)
			(stroke
				(width 0)
				(type default)
			)
			(fill no)
			(layer "F.Fab")
		)
		(pad "1" smd custom
			(at 0 -0.4445 270)
			(size 0.1397 0.1397)
			(layers "F.Cu" "F.Mask" "F.Paste")
			(net "P3V3")
			(options
				(clearance outline)
				(anchor circle)
			)
			(primitives
				(gr_poly
					(pts
						(arc
							(start -0.1778 -0.2794)
							(mid -0.249642 -0.249642)
							(end -0.2794 -0.1778)
						)
						(arc
							(start -0.2794 0.1778)
							(mid -0.249642 0.249642)
							(end -0.1778 0.2794)
						)
						(arc
							(start 0.1778 0.2794)
							(mid 0.249642 0.249642)
							(end 0.2794 0.1778)
						)
						(arc
							(start 0.2794 -0.1778)
							(mid 0.249642 -0.249642)
							(end 0.1778 -0.2794)
						)
					)
					(width 0)
					(fill yes)
				)
			)
		)
		(pad "2" smd custom
			(at 0 0.4445 270)
			(size 0.1397 0.1397)
			(layers "F.Cu" "F.Mask" "F.Paste")
			(net "HDD_PRSNT_NET10")
			(options
				(clearance outline)
				(anchor circle)
			)
			(primitives
				(gr_poly
					(pts
						(arc
							(start -0.1778 -0.2794)
							(mid -0.249642 -0.249642)
							(end -0.2794 -0.1778)
						)
						(arc
							(start -0.2794 0.1778)
							(mid -0.249642 0.249642)
							(end -0.1778 0.2794)
						)
						(arc
							(start 0.1778 0.2794)
							(mid 0.249642 0.249642)
							(end 0.2794 0.1778)
						)
						(arc
							(start 0.2794 -0.1778)
							(mid 0.249642 -0.249642)
							(end 0.1778 -0.2794)
						)
					)
					(width 0)
					(fill yes)
				)
			)
		)
	)
	(footprint ""
		(layer "F.Cu")
		(at 234.753912 -41.763696 90)
		(property "Reference" "R160"
			(at 0 0 90)
			(layer "F.SilkS")
			(hide yes)
			(effects
				(font
					(size 1.27 1.27)
				)
			)
		)
		(property "Value" "0R2J-2-GP"
			(at 0.064008 -3.993896 90)
			(unlocked yes)
			(layer "F.Fab")
			(hide yes)
			(effects
				(font
					(size 1.016 1.016)
					(thickness 0.1524)
				)
			)
		)
		(property "Device Type" "R402H16"
			(at 0.064008 -5.517896 90)
			(unlocked yes)
			(layer "F.Fab")
			(hide yes)
			(effects
				(font
					(size 1.016 1.016)
					(thickness 0.1524)
				)
			)
		)
		(duplicate_pad_numbers_are_jumpers no)
		(fp_line
			(start 0.508 -0.9398)
			(end -0.508 -0.9398)
			(stroke
				(width 0.1524)
				(type default)
			)
			(layer "F.SilkS")
		)
		(fp_line
			(start -0.508 -0.9398)
			(end -0.508 0.9398)
			(stroke
				(width 0.1524)
				(type default)
			)
			(layer "F.SilkS")
		)
		(fp_rect
			(start -0.508 0.9398)
			(end 0.508 -0.9398)
			(stroke
				(width 0)
				(type default)
			)
			(fill no)
			(layer "F.CrtYd")
		)
		(fp_rect
			(start -0.508 0.9398)
			(end 0.508 -0.9398)
			(stroke
				(width 0)
				(type default)
			)
			(fill no)
			(layer "F.Fab")
		)
		(pad "1" smd custom
			(at 0 -0.4445 90)
			(size 0.1397 0.1397)
			(layers "F.Cu" "F.Mask" "F.Paste")
			(net "FLT_NET_HDD4")
			(options
				(clearance outline)
				(anchor circle)
			)
			(primitives
				(gr_poly
					(pts
						(arc
							(start -0.1778 -0.2794)
							(mid -0.249642 -0.249642)
							(end -0.2794 -0.1778)
						)
						(arc
							(start -0.2794 0.1778)
							(mid -0.249642 0.249642)
							(end -0.1778 0.2794)
						)
						(arc
							(start 0.1778 0.2794)
							(mid 0.249642 0.249642)
							(end 0.2794 0.1778)
						)
						(arc
							(start 0.2794 -0.1778)
							(mid 0.249642 -0.249642)
							(end 0.1778 -0.2794)
						)
					)
					(width 0)
					(fill yes)
				)
			)
		)
		(pad "2" smd custom
			(at 0 0.4445 90)
			(size 0.1397 0.1397)
			(layers "F.Cu" "F.Mask" "F.Paste")
			(net "FLT_HDD4_DRIVE")
			(options
				(clearance outline)
				(anchor circle)
			)
			(primitives
				(gr_poly
					(pts
						(arc
							(start -0.1778 -0.2794)
							(mid -0.249642 -0.249642)
							(end -0.2794 -0.1778)
						)
						(arc
							(start -0.2794 0.1778)
							(mid -0.249642 0.249642)
							(end -0.1778 0.2794)
						)
						(arc
							(start 0.1778 0.2794)
							(mid 0.249642 0.249642)
							(end 0.2794 0.1778)
						)
						(arc
							(start 0.2794 -0.1778)
							(mid 0.249642 -0.249642)
							(end 0.1778 -0.2794)
						)
					)
					(width 0)
					(fill yes)
				)
			)
		)
	)
	(footprint ""
		(layer "F.Cu")
		(at 60.3885 -275.74875 -90)
		(property "Reference" "Q61"
			(at 0 0 270)
			(layer "F.SilkS")
			(hide yes)
			(effects
				(font
					(size 1.27 1.27)
				)
			)
		)
		(property "Value" "2N7002-11-GP"
			(at 0.127 -8.9662 270)
			(unlocked yes)
			(layer "F.Fab")
			(hide yes)
			(effects
				(font
					(size 1.016 1.016)
					(thickness 0.1524)
				)
			)
		)
		(property "Device Type" "SOT23DGS2D4H44"
			(at 0.127 -10.4902 270)
			(unlocked yes)
			(layer "F.Fab")
			(hide yes)
			(effects
				(font
					(size 1.016 1.016)
					(thickness 0.1524)
				)
			)
		)
		(duplicate_pad_numbers_are_jumpers no)
		(fp_line
			(start -1.651 1.778)
			(end 1.651 1.778)
			(stroke
				(width 0.1524)
				(type default)
			)
			(layer "F.SilkS")
		)
		(fp_line
			(start 1.651 1.778)
			(end 1.651 -1.778)
			(stroke
				(width 0.1524)
				(type default)
			)
			(layer "F.SilkS")
		)
		(fp_line
			(start -1.651 -1.778)
			(end -1.651 1.778)
			(stroke
				(width 0.1524)
				(type default)
			)
			(layer "F.SilkS")
		)
		(fp_line
			(start 1.651 -1.778)
			(end -1.651 -1.778)
			(stroke
				(width 0.1524)
				(type default)
			)
			(layer "F.SilkS")
		)
		(fp_poly
			(pts
				(xy -1.778 1.8796) (xy -1.778 -1.8796) (xy 1.778 -1.8796) (xy 1.778 1.8796)
			)
			(stroke
				(width 0)
				(type default)
			)
			(fill no)
			(layer "F.CrtYd")
		)
		(fp_poly
			(pts
				(xy -1.778 1.8796) (xy -1.778 -1.8796) (xy 1.778 -1.8796) (xy 1.778 1.8796)
			)
			(stroke
				(width 0)
				(type default)
			)
			(fill no)
			(layer "F.Fab")
		)
		(pad "D" smd custom
			(at 0 -0.9525 270)
			(size 0.1905 0.1905)
			(layers "F.Cu" "F.Mask" "F.Paste")
			(net "HDD7_LED_G")
			(options
				(clearance outline)
				(anchor circle)
			)
			(primitives
				(gr_poly
					(pts
						(arc
							(start -0.1778 0.5715)
							(mid -0.321484 0.511984)
							(end -0.381 0.3683)
						)
						(arc
							(start -0.381 -0.3683)
							(mid -0.321484 -0.511984)
							(end -0.1778 -0.5715)
						)
						(arc
							(start 0.1778 -0.5715)
							(mid 0.321484 -0.511984)
							(end 0.381 -0.3683)
						)
						(arc
							(start 0.381 0.3683)
							(mid 0.321484 0.511984)
							(end 0.1778 0.5715)
						)
					)
					(width 0)
					(fill yes)
				)
			)
		)
		(pad "G" smd custom
			(at -0.98425 0.9525 270)
			(size 0.1905 0.1905)
			(layers "F.Cu" "F.Mask" "F.Paste")
			(net "HDD7_LED_B")
			(options
				(clearance outline)
				(anchor circle)
			)
			(primitives
				(gr_poly
					(pts
						(arc
							(start -0.1778 0.5715)
							(mid -0.321484 0.511984)
							(end -0.381 0.3683)
						)
						(arc
							(start -0.381 -0.3683)
							(mid -0.321484 -0.511984)
							(end -0.1778 -0.5715)
						)
						(arc
							(start 0.1778 -0.5715)
							(mid 0.321484 -0.511984)
							(end 0.381 -0.3683)
						)
						(arc
							(start 0.381 0.3683)
							(mid 0.321484 0.511984)
							(end 0.1778 0.5715)
						)
					)
					(width 0)
					(fill yes)
				)
			)
		)
		(pad "S" smd custom
			(at 0.98425 0.9525 270)
			(size 0.1905 0.1905)
			(layers "F.Cu" "F.Mask" "F.Paste")
			(net "GND")
			(options
				(clearance outline)
				(anchor circle)
			)
			(primitives
				(gr_poly
					(pts
						(arc
							(start -0.1778 0.5715)
							(mid -0.321484 0.511984)
							(end -0.381 0.3683)
						)
						(arc
							(start -0.381 -0.3683)
							(mid -0.321484 -0.511984)
							(end -0.1778 -0.5715)
						)
						(arc
							(start 0.1778 -0.5715)
							(mid 0.321484 -0.511984)
							(end 0.381 -0.3683)
						)
						(arc
							(start 0.381 0.3683)
							(mid 0.321484 0.511984)
							(end 0.1778 0.5715)
						)
					)
					(width 0)
					(fill yes)
				)
			)
		)
	)
	(footprint ""
		(layer "F.Cu")
		(at 35.813746 -116.487702)
		(property "Reference" "C320"
			(at 0 0 0)
			(layer "F.SilkS")
			(hide yes)
			(effects
				(font
					(size 1.27 1.27)
				)
			)
		)
		(property "Value" "SC10U25V6KX-1GP"
			(at -0.0762 -5.1308 0)
			(unlocked yes)
			(layer "F.Fab")
			(hide yes)
			(effects
				(font
					(size 1.016 1.016)
					(thickness 0.1524)
				)
			)
		)
		(property "Device Type" "C1206H71"
			(at -0.127 -6.6548 0)
			(unlocked yes)
			(layer "F.Fab")
			(hide yes)
			(effects
				(font
					(size 1.016 1.016)
					(thickness 0.1524)
				)
			)
		)
		(duplicate_pad_numbers_are_jumpers no)
		(fp_line
			(start -1.016 -2.2352)
			(end 1.016 -2.2352)
			(stroke
				(width 0.1524)
				(type default)
			)
			(layer "F.SilkS")
		)
		(fp_line
			(start -1.016 -0.8382)
			(end -1.016 -2.2352)
			(stroke
				(width 0.1524)
				(type default)
			)
			(layer "F.SilkS")
		)
		(fp_line
			(start -1.016 2.2352)
			(end -1.016 0.8382)
			(stroke
				(width 0.1524)
				(type default)
			)
			(layer "F.SilkS")
		)
		(fp_line
			(start 1.016 -2.2352)
			(end 1.016 -0.8382)
			(stroke
				(width 0.1524)
				(type default)
			)
			(layer "F.SilkS")
		)
		(fp_line
			(start 1.016 0.8382)
			(end 1.016 2.2352)
			(stroke
				(width 0.1524)
				(type default)
			)
			(layer "F.SilkS")
		)
		(fp_line
			(start 1.016 2.2352)
			(end -1.016 2.2352)
			(stroke
				(width 0.1524)
				(type default)
			)
			(layer "F.SilkS")
		)
		(fp_rect
			(start -1.0922 2.3114)
			(end 1.0922 -2.3114)
			(stroke
				(width 0)
				(type default)
			)
			(fill no)
			(layer "F.CrtYd")
		)
		(fp_poly
			(pts
				(xy 1.0922 -2.3114) (xy 1.0922 2.3114) (xy -1.0922 2.3114) (xy -1.0922 -2.3114)
			)
			(stroke
				(width 0)
				(type default)
			)
			(fill no)
			(layer "F.Fab")
		)
		(pad "1" smd rect
			(at 0 -1.397)
			(size 1.651 1.27)
			(layers "F.Cu" "F.Mask" "F.Paste")
			(net "P12V_HDD13")
		)
		(pad "2" smd rect
			(at 0 1.397)
			(size 1.651 1.27)
			(layers "F.Cu" "F.Mask" "F.Paste")
			(net "GND")
		)
	)
	(footprint ""
		(layer "F.Cu")
		(at 56.514746 -234.343702)
		(property "Reference" "Q25"
			(at 0 0 0)
			(layer "F.SilkS")
			(hide yes)
			(effects
				(font
					(size 1.27 1.27)
				)
			)
		)
		(property "Value" "AO4406AL-GP"
			(at -3.707384 -1.5367 0)
			(unlocked yes)
			(layer "F.Fab")
			(hide yes)
			(effects
				(font
					(size 1.016 1.016)
					(thickness 0.1524)
				)
			)
		)
		(property "Device Type" "SOIC8H69"
			(at -3.707384 -3.0607 0)
			(unlocked yes)
			(layer "F.Fab")
			(hide yes)
			(effects
				(font
					(size 1.016 1.016)
					(thickness 0.1524)
				)
			)
		)
		(duplicate_pad_numbers_are_jumpers no)
		(fp_line
			(start -2.7432 -1.4224)
			(end -2.7432 1.4224)
			(stroke
				(width 0.1524)
				(type default)
			)
			(layer "F.SilkS")
		)
		(fp_line
			(start -2.7432 1.4224)
			(end -2.6416 1.4224)
			(stroke
				(width 0.1524)
				(type default)
			)
			(layer "F.SilkS")
		)
		(fp_line
			(start -2.7432 1.4224)
			(end 2.1336 1.4224)
			(stroke
				(width 0.1524)
				(type default)
			)
			(layer "F.SilkS")
		)
		(fp_line
			(start -2.7178 -0.508)
			(end -2.1844 -0.0508)
			(stroke
				(width 0.1524)
				(type default)
			)
			(layer "F.SilkS")
		)
		(fp_line
			(start -2.6289 3.4417)
			(end -2.6289 1.4732)
			(stroke
				(width 0.381)
				(type default)
			)
			(layer "F.SilkS")
		)
		(fp_line
			(start -2.1844 -0.0508)
			(end -2.7178 0.508)
			(stroke
				(width 0.1524)
				(type default)
			)
			(layer "F.SilkS")
		)
		(fp_line
			(start 2.1336 -1.4224)
			(end -2.7432 -1.4224)
			(stroke
				(width 0.1524)
				(type default)
			)
			(layer "F.SilkS")
		)
		(fp_line
			(start 2.1336 1.4224)
			(end 2.1336 -1.4224)
			(stroke
				(width 0.1524)
				(type default)
			)
			(layer "F.SilkS")
		)
		(fp_poly
			(pts
				(xy -2.2098 -1.4224) (xy -2.2098 1.4224) (xy 2.2098 1.4224) (xy 2.2098 -1.4224)
			)
			(stroke
				(width 0)
				(type default)
			)
			(fill yes)
			(layer "F.SilkS")
		)
		(fp_rect
			(start -2.450084 2.999994)
			(end 2.450084 -2.999994)
			(stroke
				(width 0)
				(type default)
			)
			(fill no)
			(layer "F.CrtYd")
		)
		(fp_poly
			(pts
				(xy -2.8194 3.6322) (xy -2.8194 -3.6322) (xy 2.8194 -3.6322) (xy 2.8194 1.18364) (xy 2.450084 1.18364)
				(xy 2.450084 -2.999994) (xy -2.450084 -2.999994) (xy -2.450084 2.999994) (xy 2.450084 2.999994)
				(xy 2.450084 1.18618) (xy 2.8194 1.18618) (xy 2.8194 3.6322)
			)
			(stroke
				(width 0)
				(type default)
			)
			(fill no)
			(layer "F.CrtYd")
		)
		(fp_rect
			(start -2.8194 3.6322)
			(end 2.8194 -3.6322)
			(stroke
				(width 0)
				(type default)
			)
			(fill no)
			(layer "F.Fab")
		)
		(pad "1" smd rect
			(at -1.905 2.54)
			(size 0.635 1.651)
			(layers "F.Cu" "F.Mask" "F.Paste")
			(net "P5V_HDD12")
		)
		(pad "2" smd rect
			(at -0.635 2.54)
			(size 0.635 1.651)
			(layers "F.Cu" "F.Mask" "F.Paste")
			(net "P5V_HDD12")
		)
		(pad "3" smd rect
			(at 0.635 2.54)
			(size 0.635 1.651)
			(layers "F.Cu" "F.Mask" "F.Paste")
			(net "P5V_HDD12")
		)
		(pad "4" smd rect
			(at 1.905 2.54)
			(size 0.635 1.651)
			(layers "F.Cu" "F.Mask" "F.Paste")
			(net "SW_HDD12_P")
		)
		(pad "5" smd rect
			(at 1.905 -2.54)
			(size 0.635 1.651)
			(layers "F.Cu" "F.Mask" "F.Paste")
			(net "P5VC")
		)
		(pad "6" smd rect
			(at 0.635 -2.54)
			(size 0.635 1.651)
			(layers "F.Cu" "F.Mask" "F.Paste")
			(net "P5VC")
		)
		(pad "7" smd rect
			(at -0.635 -2.54)
			(size 0.635 1.651)
			(layers "F.Cu" "F.Mask" "F.Paste")
			(net "P5VC")
		)
		(pad "8" smd rect
			(at -1.905 -2.54)
			(size 0.635 1.651)
			(layers "F.Cu" "F.Mask" "F.Paste")
			(net "P5VC")
		)
	)
	(footprint ""
		(layer "F.Cu")
		(at 36.83 -135.9662)
		(property "Reference" "Q73"
			(at 0 0 0)
			(layer "F.SilkS")
			(hide yes)
			(effects
				(font
					(size 1.27 1.27)
				)
			)
		)
		(property "Value" "2N7002-11-GP"
			(at 0.127 -8.9662 0)
			(unlocked yes)
			(layer "F.Fab")
			(hide yes)
			(effects
				(font
					(size 1.016 1.016)
					(thickness 0.1524)
				)
			)
		)
		(property "Device Type" "SOT23DGS2D4H44"
			(at 0.127 -10.4902 0)
			(unlocked yes)
			(layer "F.Fab")
			(hide yes)
			(effects
				(font
					(size 1.016 1.016)
					(thickness 0.1524)
				)
			)
		)
		(duplicate_pad_numbers_are_jumpers no)
		(fp_line
			(start -1.651 -1.778)
			(end -1.651 1.778)
			(stroke
				(width 0.1524)
				(type default)
			)
			(layer "F.SilkS")
		)
		(fp_line
			(start -1.651 1.778)
			(end 1.651 1.778)
			(stroke
				(width 0.1524)
				(type default)
			)
			(layer "F.SilkS")
		)
		(fp_line
			(start 1.651 -1.778)
			(end -1.651 -1.778)
			(stroke
				(width 0.1524)
				(type default)
			)
			(layer "F.SilkS")
		)
		(fp_line
			(start 1.651 1.778)
			(end 1.651 -1.778)
			(stroke
				(width 0.1524)
				(type default)
			)
			(layer "F.SilkS")
		)
		(fp_poly
			(pts
				(xy -1.778 1.8796) (xy -1.778 -1.8796) (xy 1.778 -1.8796) (xy 1.778 1.8796)
			)
			(stroke
				(width 0)
				(type default)
			)
			(fill no)
			(layer "F.CrtYd")
		)
		(fp_poly
			(pts
				(xy -1.778 1.8796) (xy -1.778 -1.8796) (xy 1.778 -1.8796) (xy 1.778 1.8796)
			)
			(stroke
				(width 0)
				(type default)
			)
			(fill no)
			(layer "F.Fab")
		)
		(pad "D" smd custom
			(at 0 -0.9525)
			(size 0.1905 0.1905)
			(layers "F.Cu" "F.Mask" "F.Paste")
			(net "HDD13_LED_G")
			(options
				(clearance outline)
				(anchor circle)
			)
			(primitives
				(gr_poly
					(pts
						(arc
							(start -0.1778 0.5715)
							(mid -0.321484 0.511984)
							(end -0.381 0.3683)
						)
						(arc
							(start -0.381 -0.3683)
							(mid -0.321484 -0.511984)
							(end -0.1778 -0.5715)
						)
						(arc
							(start 0.1778 -0.5715)
							(mid 0.321484 -0.511984)
							(end 0.381 -0.3683)
						)
						(arc
							(start 0.381 0.3683)
							(mid 0.321484 0.511984)
							(end 0.1778 0.5715)
						)
					)
					(width 0)
					(fill yes)
				)
			)
		)
		(pad "G" smd custom
			(at -0.98425 0.9525)
			(size 0.1905 0.1905)
			(layers "F.Cu" "F.Mask" "F.Paste")
			(net "HDD13_LED_B")
			(options
				(clearance outline)
				(anchor circle)
			)
			(primitives
				(gr_poly
					(pts
						(arc
							(start -0.1778 0.5715)
							(mid -0.321484 0.511984)
							(end -0.381 0.3683)
						)
						(arc
							(start -0.381 -0.3683)
							(mid -0.321484 -0.511984)
							(end -0.1778 -0.5715)
						)
						(arc
							(start 0.1778 -0.5715)
							(mid 0.321484 -0.511984)
							(end 0.381 -0.3683)
						)
						(arc
							(start 0.381 0.3683)
							(mid 0.321484 0.511984)
							(end 0.1778 0.5715)
						)
					)
					(width 0)
					(fill yes)
				)
			)
		)
		(pad "S" smd custom
			(at 0.98425 0.9525)
			(size 0.1905 0.1905)
			(layers "F.Cu" "F.Mask" "F.Paste")
			(net "GND")
			(options
				(clearance outline)
				(anchor circle)
			)
			(primitives
				(gr_poly
					(pts
						(arc
							(start -0.1778 0.5715)
							(mid -0.321484 0.511984)
							(end -0.381 0.3683)
						)
						(arc
							(start -0.381 -0.3683)
							(mid -0.321484 -0.511984)
							(end -0.1778 -0.5715)
						)
						(arc
							(start 0.1778 -0.5715)
							(mid 0.321484 -0.511984)
							(end 0.381 -0.3683)
						)
						(arc
							(start 0.381 0.3683)
							(mid 0.321484 0.511984)
							(end 0.1778 0.5715)
						)
					)
					(width 0)
					(fill yes)
				)
			)
		)
	)
	(footprint ""
		(layer "F.Cu")
		(at 21.082 -256.159 -90)
		(property "Reference" "R269"
			(at 0 0 270)
			(layer "F.SilkS")
			(hide yes)
			(effects
				(font
					(size 1.27 1.27)
				)
			)
		)
		(property "Value" "402R2F-GP"
			(at 0.064008 -3.993896 270)
			(unlocked yes)
			(layer "F.Fab")
			(hide yes)
			(effects
				(font
					(size 1.016 1.016)
					(thickness 0.1524)
				)
			)
		)
		(property "Device Type" "R402H16"
			(at 0.064008 -5.517896 270)
			(unlocked yes)
			(layer "F.Fab")
			(hide yes)
			(effects
				(font
					(size 1.016 1.016)
					(thickness 0.1524)
				)
			)
		)
		(duplicate_pad_numbers_are_jumpers no)
		(fp_line
			(start -0.508 -0.9398)
			(end -0.508 0.9398)
			(stroke
				(width 0.1524)
				(type default)
			)
			(layer "F.SilkS")
		)
		(fp_line
			(start 0.508 -0.9398)
			(end -0.508 -0.9398)
			(stroke
				(width 0.1524)
				(type default)
			)
			(layer "F.SilkS")
		)
		(fp_rect
			(start -0.508 0.9398)
			(end 0.508 -0.9398)
			(stroke
				(width 0)
				(type default)
			)
			(fill no)
			(layer "F.CrtYd")
		)
		(fp_rect
			(start -0.508 0.9398)
			(end 0.508 -0.9398)
			(stroke
				(width 0)
				(type default)
			)
			(fill no)
			(layer "F.Fab")
		)
		(pad "1" smd custom
			(at 0 -0.4445 270)
			(size 0.1397 0.1397)
			(layers "F.Cu" "F.Mask" "F.Paste")
			(net "P5VC_HDD12_LED")
			(options
				(clearance outline)
				(anchor circle)
			)
			(primitives
				(gr_poly
					(pts
						(arc
							(start -0.1778 -0.2794)
							(mid -0.249642 -0.249642)
							(end -0.2794 -0.1778)
						)
						(arc
							(start -0.2794 0.1778)
							(mid -0.249642 0.249642)
							(end -0.1778 0.2794)
						)
						(arc
							(start 0.1778 0.2794)
							(mid 0.249642 0.249642)
							(end 0.2794 0.1778)
						)
						(arc
							(start 0.2794 -0.1778)
							(mid 0.249642 -0.249642)
							(end 0.1778 -0.2794)
						)
					)
					(width 0)
					(fill yes)
				)
			)
		)
		(pad "2" smd custom
			(at 0 0.4445 270)
			(size 0.1397 0.1397)
			(layers "F.Cu" "F.Mask" "F.Paste")
			(net "DRV_ACT_12")
			(options
				(clearance outline)
				(anchor circle)
			)
			(primitives
				(gr_poly
					(pts
						(arc
							(start -0.1778 -0.2794)
							(mid -0.249642 -0.249642)
							(end -0.2794 -0.1778)
						)
						(arc
							(start -0.2794 0.1778)
							(mid -0.249642 0.249642)
							(end -0.1778 0.2794)
						)
						(arc
							(start 0.1778 0.2794)
							(mid 0.249642 0.249642)
							(end 0.2794 0.1778)
						)
						(arc
							(start 0.2794 -0.1778)
							(mid 0.249642 -0.249642)
							(end 0.1778 -0.2794)
						)
					)
					(width 0)
					(fill yes)
				)
			)
		)
	)
	(footprint ""
		(layer "F.Cu")
		(at 46.7106 -234.188)
		(property "Reference" "Q71"
			(at 0 0 0)
			(layer "F.SilkS")
			(hide yes)
			(effects
				(font
					(size 1.27 1.27)
				)
			)
		)
		(property "Value" "2N7002-11-GP"
			(at 0.127 -8.9662 0)
			(unlocked yes)
			(layer "F.Fab")
			(hide yes)
			(effects
				(font
					(size 1.016 1.016)
					(thickness 0.1524)
				)
			)
		)
		(property "Device Type" "SOT23DGS2D4H44"
			(at 0.127 -10.4902 0)
			(unlocked yes)
			(layer "F.Fab")
			(hide yes)
			(effects
				(font
					(size 1.016 1.016)
					(thickness 0.1524)
				)
			)
		)
		(duplicate_pad_numbers_are_jumpers no)
		(fp_line
			(start -1.651 -1.778)
			(end -1.651 1.778)
			(stroke
				(width 0.1524)
				(type default)
			)
			(layer "F.SilkS")
		)
		(fp_line
			(start -1.651 1.778)
			(end 1.651 1.778)
			(stroke
				(width 0.1524)
				(type default)
			)
			(layer "F.SilkS")
		)
		(fp_line
			(start 1.651 -1.778)
			(end -1.651 -1.778)
			(stroke
				(width 0.1524)
				(type default)
			)
			(layer "F.SilkS")
		)
		(fp_line
			(start 1.651 1.778)
			(end 1.651 -1.778)
			(stroke
				(width 0.1524)
				(type default)
			)
			(layer "F.SilkS")
		)
		(fp_poly
			(pts
				(xy -1.778 1.8796) (xy -1.778 -1.8796) (xy 1.778 -1.8796) (xy 1.778 1.8796)
			)
			(stroke
				(width 0)
				(type default)
			)
			(fill no)
			(layer "F.CrtYd")
		)
		(fp_poly
			(pts
				(xy -1.778 1.8796) (xy -1.778 -1.8796) (xy 1.778 -1.8796) (xy 1.778 1.8796)
			)
			(stroke
				(width 0)
				(type default)
			)
			(fill no)
			(layer "F.Fab")
		)
		(pad "D" smd custom
			(at 0 -0.9525)
			(size 0.1905 0.1905)
			(layers "F.Cu" "F.Mask" "F.Paste")
			(net "HDD12_LED_G")
			(options
				(clearance outline)
				(anchor circle)
			)
			(primitives
				(gr_poly
					(pts
						(arc
							(start -0.1778 0.5715)
							(mid -0.321484 0.511984)
							(end -0.381 0.3683)
						)
						(arc
							(start -0.381 -0.3683)
							(mid -0.321484 -0.511984)
							(end -0.1778 -0.5715)
						)
						(arc
							(start 0.1778 -0.5715)
							(mid 0.321484 -0.511984)
							(end 0.381 -0.3683)
						)
						(arc
							(start 0.381 0.3683)
							(mid 0.321484 0.511984)
							(end 0.1778 0.5715)
						)
					)
					(width 0)
					(fill yes)
				)
			)
		)
		(pad "G" smd custom
			(at -0.98425 0.9525)
			(size 0.1905 0.1905)
			(layers "F.Cu" "F.Mask" "F.Paste")
			(net "HDD12_LED_B")
			(options
				(clearance outline)
				(anchor circle)
			)
			(primitives
				(gr_poly
					(pts
						(arc
							(start -0.1778 0.5715)
							(mid -0.321484 0.511984)
							(end -0.381 0.3683)
						)
						(arc
							(start -0.381 -0.3683)
							(mid -0.321484 -0.511984)
							(end -0.1778 -0.5715)
						)
						(arc
							(start 0.1778 -0.5715)
							(mid 0.321484 -0.511984)
							(end 0.381 -0.3683)
						)
						(arc
							(start 0.381 0.3683)
							(mid 0.321484 0.511984)
							(end 0.1778 0.5715)
						)
					)
					(width 0)
					(fill yes)
				)
			)
		)
		(pad "S" smd custom
			(at 0.98425 0.9525)
			(size 0.1905 0.1905)
			(layers "F.Cu" "F.Mask" "F.Paste")
			(net "GND")
			(options
				(clearance outline)
				(anchor circle)
			)
			(primitives
				(gr_poly
					(pts
						(arc
							(start -0.1778 0.5715)
							(mid -0.321484 0.511984)
							(end -0.381 0.3683)
						)
						(arc
							(start -0.381 -0.3683)
							(mid -0.321484 -0.511984)
							(end -0.1778 -0.5715)
						)
						(arc
							(start 0.1778 -0.5715)
							(mid 0.321484 -0.511984)
							(end 0.381 -0.3683)
						)
						(arc
							(start 0.381 0.3683)
							(mid 0.321484 0.511984)
							(end 0.1778 0.5715)
						)
					)
					(width 0)
					(fill yes)
				)
			)
		)
	)
	(footprint ""
		(layer "F.Cu")
		(at 14.097 -187.706 90)
		(property "Reference" "C351"
			(at 0 0 90)
			(layer "F.SilkS")
			(hide yes)
			(effects
				(font
					(size 1.27 1.27)
				)
			)
		)
		(property "Value" "SC10U25V5KX-GP"
			(at -0.0762 -6.1214 90)
			(unlocked yes)
			(layer "F.Fab")
			(hide yes)
			(effects
				(font
					(size 1.016 1.016)
					(thickness 0.1524)
				)
			)
		)
		(property "Device Type" "C805H56"
			(at -0.0762 -8.1534 90)
			(unlocked yes)
			(layer "F.Fab")
			(hide yes)
			(effects
				(font
					(size 1.016 1.016)
					(thickness 0.1524)
				)
			)
		)
		(duplicate_pad_numbers_are_jumpers no)
		(fp_line
			(start 0.635 0)
			(end -0.635 0)
			(stroke
				(width 0.508)
				(type default)
			)
			(layer "F.SilkS")
		)
		(fp_rect
			(start -0.9652 1.778)
			(end 0.9652 -1.778)
			(stroke
				(width 0)
				(type default)
			)
			(fill no)
			(layer "F.CrtYd")
		)
		(fp_poly
			(pts
				(xy -0.9652 -1.778) (xy 0.9652 -1.778) (xy 0.9652 1.778) (xy -0.9652 1.778)
			)
			(stroke
				(width 0)
				(type default)
			)
			(fill no)
			(layer "F.Fab")
		)
		(pad "1" smd rect
			(at 0 -0.9652 90)
			(size 1.397 1.143)
			(layers "F.Cu" "F.Mask" "F.Paste")
			(net "P12V")
		)
		(pad "2" smd rect
			(at 0 0.9652 90)
			(size 1.397 1.143)
			(layers "F.Cu" "F.Mask" "F.Paste")
			(net "GND")
		)
	)
	(footprint ""
		(layer "F.Cu")
		(at 57.911746 -176.1617 -90)
		(property "Reference" "R217"
			(at 0 0 270)
			(layer "F.SilkS")
			(hide yes)
			(effects
				(font
					(size 1.27 1.27)
				)
			)
		)
		(property "Value" "4K7R2J-2-GP"
			(at 0.064008 -3.993896 270)
			(unlocked yes)
			(layer "F.Fab")
			(hide yes)
			(effects
				(font
					(size 1.016 1.016)
					(thickness 0.1524)
				)
			)
		)
		(property "Device Type" "R402H16"
			(at 0.064008 -5.517896 270)
			(unlocked yes)
			(layer "F.Fab")
			(hide yes)
			(effects
				(font
					(size 1.016 1.016)
					(thickness 0.1524)
				)
			)
		)
		(duplicate_pad_numbers_are_jumpers no)
		(fp_line
			(start -0.508 -0.9398)
			(end -0.508 0.9398)
			(stroke
				(width 0.1524)
				(type default)
			)
			(layer "F.SilkS")
		)
		(fp_line
			(start 0.508 -0.9398)
			(end -0.508 -0.9398)
			(stroke
				(width 0.1524)
				(type default)
			)
			(layer "F.SilkS")
		)
		(fp_rect
			(start -0.508 0.9398)
			(end 0.508 -0.9398)
			(stroke
				(width 0)
				(type default)
			)
			(fill no)
			(layer "F.CrtYd")
		)
		(fp_rect
			(start -0.508 0.9398)
			(end 0.508 -0.9398)
			(stroke
				(width 0)
				(type default)
			)
			(fill no)
			(layer "F.Fab")
		)
		(pad "1" smd custom
			(at 0 -0.4445 270)
			(size 0.1397 0.1397)
			(layers "F.Cu" "F.Mask" "F.Paste")
			(net "P3V3")
			(options
				(clearance outline)
				(anchor circle)
			)
			(primitives
				(gr_poly
					(pts
						(arc
							(start -0.1778 -0.2794)
							(mid -0.249642 -0.249642)
							(end -0.2794 -0.1778)
						)
						(arc
							(start -0.2794 0.1778)
							(mid -0.249642 0.249642)
							(end -0.1778 0.2794)
						)
						(arc
							(start 0.1778 0.2794)
							(mid 0.249642 0.249642)
							(end 0.2794 0.1778)
						)
						(arc
							(start 0.2794 -0.1778)
							(mid 0.249642 -0.249642)
							(end 0.1778 -0.2794)
						)
					)
					(width 0)
					(fill yes)
				)
			)
		)
		(pad "2" smd custom
			(at 0 0.4445 270)
			(size 0.1397 0.1397)
			(layers "F.Cu" "F.Mask" "F.Paste")
			(net "HDD_PRSNT_NET8")
			(options
				(clearance outline)
				(anchor circle)
			)
			(primitives
				(gr_poly
					(pts
						(arc
							(start -0.1778 -0.2794)
							(mid -0.249642 -0.249642)
							(end -0.2794 -0.1778)
						)
						(arc
							(start -0.2794 0.1778)
							(mid -0.249642 0.249642)
							(end -0.1778 0.2794)
						)
						(arc
							(start 0.1778 0.2794)
							(mid 0.249642 0.249642)
							(end 0.2794 0.1778)
						)
						(arc
							(start 0.2794 -0.1778)
							(mid 0.249642 -0.249642)
							(end 0.1778 -0.2794)
						)
					)
					(width 0)
					(fill yes)
				)
			)
		)
	)
	(footprint ""
		(layer "F.Cu")
		(at 75.057 -84.074 180)
		(property "Reference" "C245"
			(at 0 0 180)
			(layer "F.SilkS")
			(hide yes)
			(effects
				(font
					(size 1.27 1.27)
				)
			)
		)
		(property "Value" "SCD1U10V2KX-5GP"
			(at 1.1811 -2.7051 180)
			(unlocked yes)
			(layer "F.Fab")
			(hide yes)
			(effects
				(font
					(size 1.016 1.016)
					(thickness 0.1524)
				)
			)
		)
		(property "Device Type" "C402H22"
			(at 1.1811 -4.2291 180)
			(unlocked yes)
			(layer "F.Fab")
			(hide yes)
			(effects
				(font
					(size 1.016 1.016)
					(thickness 0.1524)
				)
			)
		)
		(duplicate_pad_numbers_are_jumpers no)
		(fp_rect
			(start -0.4318 0.9525)
			(end 0.4318 -0.9525)
			(stroke
				(width 0)
				(type default)
			)
			(fill no)
			(layer "F.CrtYd")
		)
		(fp_rect
			(start -0.4318 0.9525)
			(end 0.4318 -0.9525)
			(stroke
				(width 0)
				(type default)
			)
			(fill no)
			(layer "F.Fab")
		)
		(pad "1" smd custom
			(at 0 -0.4445 180)
			(size 0.1524 0.1524)
			(layers "F.Cu" "F.Mask" "F.Paste")
			(net "P3V3")
			(options
				(clearance outline)
				(anchor circle)
			)
			(primitives
				(gr_poly
					(pts
						(arc
							(start 0.3048 -0.2032)
							(mid 0.275042 -0.275042)
							(end 0.2032 -0.3048)
						)
						(arc
							(start -0.2032 -0.3048)
							(mid -0.275042 -0.275042)
							(end -0.3048 -0.2032)
						)
						(arc
							(start -0.3048 0.2032)
							(mid -0.275042 0.275042)
							(end -0.2032 0.3048)
						)
						(arc
							(start 0.2032 0.3048)
							(mid 0.275042 0.275042)
							(end 0.3048 0.2032)
						)
					)
					(width 0)
					(fill yes)
				)
			)
		)
		(pad "2" smd custom
			(at 0 0.4445 180)
			(size 0.1524 0.1524)
			(layers "F.Cu" "F.Mask" "F.Paste")
			(net "GND")
			(options
				(clearance outline)
				(anchor circle)
			)
			(primitives
				(gr_poly
					(pts
						(arc
							(start 0.3048 -0.2032)
							(mid 0.275042 -0.275042)
							(end 0.2032 -0.3048)
						)
						(arc
							(start -0.2032 -0.3048)
							(mid -0.275042 -0.275042)
							(end -0.3048 -0.2032)
						)
						(arc
							(start -0.3048 0.2032)
							(mid -0.275042 0.275042)
							(end -0.2032 0.3048)
						)
						(arc
							(start 0.2032 0.3048)
							(mid 0.275042 0.275042)
							(end 0.3048 0.2032)
						)
					)
					(width 0)
					(fill yes)
				)
			)
		)
	)
	(footprint ""
		(layer "F.Cu")
		(at 10.159746 -467.8807 90)
		(property "Reference" "R392"
			(at 0 0 90)
			(layer "F.SilkS")
			(hide yes)
			(effects
				(font
					(size 1.27 1.27)
				)
			)
		)
		(property "Value" "0R2J-2-GP"
			(at 0.064008 -3.993896 90)
			(unlocked yes)
			(layer "F.Fab")
			(hide yes)
			(effects
				(font
					(size 1.016 1.016)
					(thickness 0.1524)
				)
			)
		)
		(property "Device Type" "R402H16"
			(at 0.064008 -5.517896 90)
			(unlocked yes)
			(layer "F.Fab")
			(hide yes)
			(effects
				(font
					(size 1.016 1.016)
					(thickness 0.1524)
				)
			)
		)
		(duplicate_pad_numbers_are_jumpers no)
		(fp_line
			(start 0.508 -0.9398)
			(end -0.508 -0.9398)
			(stroke
				(width 0.1524)
				(type default)
			)
			(layer "F.SilkS")
		)
		(fp_line
			(start -0.508 -0.9398)
			(end -0.508 0.9398)
			(stroke
				(width 0.1524)
				(type default)
			)
			(layer "F.SilkS")
		)
		(fp_rect
			(start -0.508 0.9398)
			(end 0.508 -0.9398)
			(stroke
				(width 0)
				(type default)
			)
			(fill no)
			(layer "F.CrtYd")
		)
		(fp_rect
			(start -0.508 0.9398)
			(end 0.508 -0.9398)
			(stroke
				(width 0)
				(type default)
			)
			(fill no)
			(layer "F.Fab")
		)
		(pad "1" smd custom
			(at 0 -0.4445 90)
			(size 0.1397 0.1397)
			(layers "F.Cu" "F.Mask" "F.Paste")
			(net "EXP_A_PRNST_TX")
			(options
				(clearance outline)
				(anchor circle)
			)
			(primitives
				(gr_poly
					(pts
						(arc
							(start -0.1778 -0.2794)
							(mid -0.249642 -0.249642)
							(end -0.2794 -0.1778)
						)
						(arc
							(start -0.2794 0.1778)
							(mid -0.249642 0.249642)
							(end -0.1778 0.2794)
						)
						(arc
							(start 0.1778 0.2794)
							(mid 0.249642 0.249642)
							(end 0.2794 0.1778)
						)
						(arc
							(start 0.2794 -0.1778)
							(mid 0.249642 -0.249642)
							(end 0.1778 -0.2794)
						)
					)
					(width 0)
					(fill yes)
				)
			)
		)
		(pad "2" smd custom
			(at 0 0.4445 90)
			(size 0.1397 0.1397)
			(layers "F.Cu" "F.Mask" "F.Paste")
			(net "EXP_A_PRNST_RX")
			(options
				(clearance outline)
				(anchor circle)
			)
			(primitives
				(gr_poly
					(pts
						(arc
							(start -0.1778 -0.2794)
							(mid -0.249642 -0.249642)
							(end -0.2794 -0.1778)
						)
						(arc
							(start -0.2794 0.1778)
							(mid -0.249642 0.249642)
							(end -0.1778 0.2794)
						)
						(arc
							(start 0.1778 0.2794)
							(mid 0.249642 0.249642)
							(end 0.2794 0.1778)
						)
						(arc
							(start 0.2794 -0.1778)
							(mid 0.249642 -0.249642)
							(end 0.1778 -0.2794)
						)
					)
					(width 0)
					(fill yes)
				)
			)
		)
	)
	(footprint ""
		(layer "F.Cu")
		(at 85.343746 -16.0147 90)
		(property "Reference" "R474"
			(at 0 0 90)
			(layer "F.SilkS")
			(hide yes)
			(effects
				(font
					(size 1.27 1.27)
				)
			)
		)
		(property "Value" "4K7R2J-2-GP"
			(at 0.064008 -3.993896 90)
			(unlocked yes)
			(layer "F.Fab")
			(hide yes)
			(effects
				(font
					(size 1.016 1.016)
					(thickness 0.1524)
				)
			)
		)
		(property "Device Type" "R402H16"
			(at 0.064008 -5.517896 90)
			(unlocked yes)
			(layer "F.Fab")
			(hide yes)
			(effects
				(font
					(size 1.016 1.016)
					(thickness 0.1524)
				)
			)
		)
		(duplicate_pad_numbers_are_jumpers no)
		(fp_line
			(start 0.508 -0.9398)
			(end -0.508 -0.9398)
			(stroke
				(width 0.1524)
				(type default)
			)
			(layer "F.SilkS")
		)
		(fp_line
			(start -0.508 -0.9398)
			(end -0.508 0.9398)
			(stroke
				(width 0.1524)
				(type default)
			)
			(layer "F.SilkS")
		)
		(fp_rect
			(start -0.508 0.9398)
			(end 0.508 -0.9398)
			(stroke
				(width 0)
				(type default)
			)
			(fill no)
			(layer "F.CrtYd")
		)
		(fp_rect
			(start -0.508 0.9398)
			(end 0.508 -0.9398)
			(stroke
				(width 0)
				(type default)
			)
			(fill no)
			(layer "F.Fab")
		)
		(pad "1" smd custom
			(at 0 -0.4445 90)
			(size 0.1397 0.1397)
			(layers "F.Cu" "F.Mask" "F.Paste")
			(net "P3V3")
			(options
				(clearance outline)
				(anchor circle)
			)
			(primitives
				(gr_poly
					(pts
						(arc
							(start -0.1778 -0.2794)
							(mid -0.249642 -0.249642)
							(end -0.2794 -0.1778)
						)
						(arc
							(start -0.2794 0.1778)
							(mid -0.249642 0.249642)
							(end -0.1778 0.2794)
						)
						(arc
							(start 0.1778 0.2794)
							(mid 0.249642 0.249642)
							(end 0.2794 0.1778)
						)
						(arc
							(start 0.2794 -0.1778)
							(mid 0.249642 -0.249642)
							(end 0.1778 -0.2794)
						)
					)
					(width 0)
					(fill yes)
				)
			)
		)
		(pad "2" smd custom
			(at 0 0.4445 90)
			(size 0.1397 0.1397)
			(layers "F.Cu" "F.Mask" "F.Paste")
			(net "SAS2X28_A_HDD14_FLT")
			(options
				(clearance outline)
				(anchor circle)
			)
			(primitives
				(gr_poly
					(pts
						(arc
							(start -0.1778 -0.2794)
							(mid -0.249642 -0.249642)
							(end -0.2794 -0.1778)
						)
						(arc
							(start -0.2794 0.1778)
							(mid -0.249642 0.249642)
							(end -0.1778 0.2794)
						)
						(arc
							(start 0.1778 0.2794)
							(mid 0.249642 0.249642)
							(end 0.2794 0.1778)
						)
						(arc
							(start 0.2794 -0.1778)
							(mid 0.249642 -0.249642)
							(end 0.1778 -0.2794)
						)
					)
					(width 0)
					(fill yes)
				)
			)
		)
	)
	(footprint ""
		(layer "F.Cu")
		(at 214.841582 -276.197568 90)
		(property "Reference" "R133"
			(at 0 0 90)
			(layer "F.SilkS")
			(hide yes)
			(effects
				(font
					(size 1.27 1.27)
				)
			)
		)
		(property "Value" "4K7R2J-2-GP"
			(at 0.064008 -3.993896 90)
			(unlocked yes)
			(layer "F.Fab")
			(hide yes)
			(effects
				(font
					(size 1.016 1.016)
					(thickness 0.1524)
				)
			)
		)
		(property "Device Type" "R402H16"
			(at 0.064008 -5.517896 90)
			(unlocked yes)
			(layer "F.Fab")
			(hide yes)
			(effects
				(font
					(size 1.016 1.016)
					(thickness 0.1524)
				)
			)
		)
		(duplicate_pad_numbers_are_jumpers no)
		(fp_line
			(start 0.508 -0.9398)
			(end -0.508 -0.9398)
			(stroke
				(width 0.1524)
				(type default)
			)
			(layer "F.SilkS")
		)
		(fp_line
			(start -0.508 -0.9398)
			(end -0.508 0.9398)
			(stroke
				(width 0.1524)
				(type default)
			)
			(layer "F.SilkS")
		)
		(fp_rect
			(start -0.508 0.9398)
			(end 0.508 -0.9398)
			(stroke
				(width 0)
				(type default)
			)
			(fill no)
			(layer "F.CrtYd")
		)
		(fp_rect
			(start -0.508 0.9398)
			(end 0.508 -0.9398)
			(stroke
				(width 0)
				(type default)
			)
			(fill no)
			(layer "F.Fab")
		)
		(pad "1" smd custom
			(at 0 -0.4445 90)
			(size 0.1397 0.1397)
			(layers "F.Cu" "F.Mask" "F.Paste")
			(net "P3V3")
			(options
				(clearance outline)
				(anchor circle)
			)
			(primitives
				(gr_poly
					(pts
						(arc
							(start -0.1778 -0.2794)
							(mid -0.249642 -0.249642)
							(end -0.2794 -0.1778)
						)
						(arc
							(start -0.2794 0.1778)
							(mid -0.249642 0.249642)
							(end -0.1778 0.2794)
						)
						(arc
							(start 0.1778 0.2794)
							(mid 0.249642 0.249642)
							(end 0.2794 0.1778)
						)
						(arc
							(start 0.2794 -0.1778)
							(mid 0.249642 -0.249642)
							(end 0.1778 -0.2794)
						)
					)
					(width 0)
					(fill yes)
				)
			)
		)
		(pad "2" smd custom
			(at 0 0.4445 90)
			(size 0.1397 0.1397)
			(layers "F.Cu" "F.Mask" "F.Paste")
			(net "HDD_PRSNT_NET2")
			(options
				(clearance outline)
				(anchor circle)
			)
			(primitives
				(gr_poly
					(pts
						(arc
							(start -0.1778 -0.2794)
							(mid -0.249642 -0.249642)
							(end -0.2794 -0.1778)
						)
						(arc
							(start -0.2794 0.1778)
							(mid -0.249642 0.249642)
							(end -0.1778 0.2794)
						)
						(arc
							(start 0.1778 0.2794)
							(mid 0.249642 0.249642)
							(end 0.2794 0.1778)
						)
						(arc
							(start 0.2794 -0.1778)
							(mid 0.249642 -0.249642)
							(end 0.1778 -0.2794)
						)
					)
					(width 0)
					(fill yes)
				)
			)
		)
	)
	(footprint ""
		(layer "F.Cu")
		(at 55.9562 -497.6114 180)
		(property "Reference" "C192"
			(at 0 0 180)
			(layer "F.SilkS")
			(hide yes)
			(effects
				(font
					(size 1.27 1.27)
				)
			)
		)
		(property "Value" "SC10U25V6KX-1GP"
			(at -0.0762 -5.1308 180)
			(unlocked yes)
			(layer "F.Fab")
			(hide yes)
			(effects
				(font
					(size 1.016 1.016)
					(thickness 0.1524)
				)
			)
		)
		(property "Device Type" "C1206H71"
			(at -0.127 -6.6548 180)
			(unlocked yes)
			(layer "F.Fab")
			(hide yes)
			(effects
				(font
					(size 1.016 1.016)
					(thickness 0.1524)
				)
			)
		)
		(duplicate_pad_numbers_are_jumpers no)
		(fp_line
			(start 1.016 2.2352)
			(end -1.016 2.2352)
			(stroke
				(width 0.1524)
				(type default)
			)
			(layer "F.SilkS")
		)
		(fp_line
			(start 1.016 0.8382)
			(end 1.016 2.2352)
			(stroke
				(width 0.1524)
				(type default)
			)
			(layer "F.SilkS")
		)
		(fp_line
			(start 1.016 -2.2352)
			(end 1.016 -0.8382)
			(stroke
				(width 0.1524)
				(type default)
			)
			(layer "F.SilkS")
		)
		(fp_line
			(start -1.016 2.2352)
			(end -1.016 0.8382)
			(stroke
				(width 0.1524)
				(type default)
			)
			(layer "F.SilkS")
		)
		(fp_line
			(start -1.016 -0.8382)
			(end -1.016 -2.2352)
			(stroke
				(width 0.1524)
				(type default)
			)
			(layer "F.SilkS")
		)
		(fp_line
			(start -1.016 -2.2352)
			(end 1.016 -2.2352)
			(stroke
				(width 0.1524)
				(type default)
			)
			(layer "F.SilkS")
		)
		(fp_rect
			(start -1.0922 2.3114)
			(end 1.0922 -2.3114)
			(stroke
				(width 0)
				(type default)
			)
			(fill no)
			(layer "F.CrtYd")
		)
		(fp_poly
			(pts
				(xy 1.0922 -2.3114) (xy 1.0922 2.3114) (xy -1.0922 2.3114) (xy -1.0922 -2.3114)
			)
			(stroke
				(width 0)
				(type default)
			)
			(fill no)
			(layer "F.Fab")
		)
		(pad "1" smd rect
			(at 0 -1.397 180)
			(size 1.651 1.27)
			(layers "F.Cu" "F.Mask" "F.Paste")
			(net "P12V_HDD5")
		)
		(pad "2" smd rect
			(at 0 1.397 180)
			(size 1.651 1.27)
			(layers "F.Cu" "F.Mask" "F.Paste")
			(net "GND")
		)
	)
	(footprint ""
		(layer "F.Cu")
		(at 80.4418 -401.9804 -90)
		(property "Reference" "R414"
			(at 0 0 270)
			(layer "F.SilkS")
			(hide yes)
			(effects
				(font
					(size 1.27 1.27)
				)
			)
		)
		(property "Value" "0R2J-2-GP"
			(at 0.064008 -3.993896 270)
			(unlocked yes)
			(layer "F.Fab")
			(hide yes)
			(effects
				(font
					(size 1.016 1.016)
					(thickness 0.1524)
				)
			)
		)
		(property "Device Type" "R402H16"
			(at 0.064008 -5.517896 270)
			(unlocked yes)
			(layer "F.Fab")
			(hide yes)
			(effects
				(font
					(size 1.016 1.016)
					(thickness 0.1524)
				)
			)
		)
		(duplicate_pad_numbers_are_jumpers no)
		(fp_line
			(start -0.508 -0.9398)
			(end -0.508 0.9398)
			(stroke
				(width 0.1524)
				(type default)
			)
			(layer "F.SilkS")
		)
		(fp_line
			(start 0.508 -0.9398)
			(end -0.508 -0.9398)
			(stroke
				(width 0.1524)
				(type default)
			)
			(layer "F.SilkS")
		)
		(fp_rect
			(start -0.508 0.9398)
			(end 0.508 -0.9398)
			(stroke
				(width 0)
				(type default)
			)
			(fill no)
			(layer "F.CrtYd")
		)
		(fp_rect
			(start -0.508 0.9398)
			(end 0.508 -0.9398)
			(stroke
				(width 0)
				(type default)
			)
			(fill no)
			(layer "F.Fab")
		)
		(pad "1" smd custom
			(at 0 -0.4445 270)
			(size 0.1397 0.1397)
			(layers "F.Cu" "F.Mask" "F.Paste")
			(net "SW_HDD6_G")
			(options
				(clearance outline)
				(anchor circle)
			)
			(primitives
				(gr_poly
					(pts
						(arc
							(start -0.1778 -0.2794)
							(mid -0.249642 -0.249642)
							(end -0.2794 -0.1778)
						)
						(arc
							(start -0.2794 0.1778)
							(mid -0.249642 0.249642)
							(end -0.1778 0.2794)
						)
						(arc
							(start 0.1778 0.2794)
							(mid 0.249642 0.249642)
							(end 0.2794 0.1778)
						)
						(arc
							(start 0.2794 -0.1778)
							(mid 0.249642 -0.249642)
							(end 0.1778 -0.2794)
						)
					)
					(width 0)
					(fill yes)
				)
			)
		)
		(pad "2" smd custom
			(at 0 0.4445 270)
			(size 0.1397 0.1397)
			(layers "F.Cu" "F.Mask" "F.Paste")
			(net "SW_HDD6_R")
			(options
				(clearance outline)
				(anchor circle)
			)
			(primitives
				(gr_poly
					(pts
						(arc
							(start -0.1778 -0.2794)
							(mid -0.249642 -0.249642)
							(end -0.2794 -0.1778)
						)
						(arc
							(start -0.2794 0.1778)
							(mid -0.249642 0.249642)
							(end -0.1778 0.2794)
						)
						(arc
							(start 0.1778 0.2794)
							(mid 0.249642 0.249642)
							(end 0.2794 0.1778)
						)
						(arc
							(start 0.2794 -0.1778)
							(mid 0.249642 -0.249642)
							(end 0.1778 -0.2794)
						)
					)
					(width 0)
					(fill yes)
				)
			)
		)
	)
	(footprint ""
		(layer "F.Cu")
		(at 39.248334 -30.499558 180)
		(property "Reference" "PTC3"
			(at 0 0 180)
			(layer "F.SilkS")
			(hide yes)
			(effects
				(font
					(size 1.27 1.27)
				)
			)
		)
		(property "Value" "ST330U10VDM-2GP"
			(at 0 -9.6012 180)
			(unlocked yes)
			(layer "F.Fab")
			(hide yes)
			(effects
				(font
					(size 1.016 1.016)
					(thickness 0.1524)
				)
			)
		)
		(property "Device Type" "CT7343H150"
			(at 0 -11.1252 180)
			(unlocked yes)
			(layer "F.Fab")
			(hide yes)
			(effects
				(font
					(size 1.016 1.016)
					(thickness 0.1524)
				)
			)
		)
		(duplicate_pad_numbers_are_jumpers no)
		(fp_line
			(start 2.286 4.8768)
			(end -2.286 4.8768)
			(stroke
				(width 0.1524)
				(type default)
			)
			(layer "F.SilkS")
		)
		(fp_line
			(start 2.286 2.032)
			(end 2.286 4.8768)
			(stroke
				(width 0.1524)
				(type default)
			)
			(layer "F.SilkS")
		)
		(fp_line
			(start 2.286 -2.032)
			(end 2.286 -4.8768)
			(stroke
				(width 0.1524)
				(type default)
			)
			(layer "F.SilkS")
		)
		(fp_line
			(start 2.286 -4.8768)
			(end -2.286 -4.8768)
			(stroke
				(width 0.1524)
				(type default)
			)
			(layer "F.SilkS")
		)
		(fp_line
			(start 2.1082 -4.699)
			(end -2.1082 -4.699)
			(stroke
				(width 0.508)
				(type default)
			)
			(layer "F.SilkS")
		)
		(fp_line
			(start -2.286 4.8768)
			(end -2.286 2.032)
			(stroke
				(width 0.1524)
				(type default)
			)
			(layer "F.SilkS")
		)
		(fp_line
			(start -2.286 -4.8768)
			(end -2.286 -2.032)
			(stroke
				(width 0.1524)
				(type default)
			)
			(layer "F.SilkS")
		)
		(fp_rect
			(start -2.1463 3.6449)
			(end 2.1463 -3.6449)
			(stroke
				(width 0)
				(type default)
			)
			(fill no)
			(layer "F.CrtYd")
		)
		(fp_poly
			(pts
				(xy -2.54 4.953) (xy -2.54 4.2926) (xy -3.81 4.2926) (xy -3.81 -4.2926) (xy -2.54 -4.2926) (xy -2.54 -4.953)
				(xy 2.54 -4.953) (xy 2.54 -4.2926) (xy 3.81 -4.2926) (xy 3.81 -1.6256) (xy 2.1463 -1.6256) (xy 2.1463 -3.6449)
				(xy -2.1463 -3.6449) (xy -2.1463 3.6449) (xy 2.1463 3.6449) (xy 2.1463 -1.6129) (xy 3.81 -1.6129)
				(xy 3.81 4.2926) (xy 2.54 4.2926) (xy 2.54 4.953)
			)
			(stroke
				(width 0)
				(type default)
			)
			(fill no)
			(layer "F.CrtYd")
		)
		(fp_rect
			(start 2.54 4.2926)
			(end 3.81 -4.2926)
			(stroke
				(width 0)
				(type default)
			)
			(fill no)
			(layer "F.Fab")
		)
		(fp_rect
			(start -2.54 4.953)
			(end 2.54 -4.953)
			(stroke
				(width 0)
				(type default)
			)
			(fill no)
			(layer "F.Fab")
		)
		(fp_rect
			(start -3.81 4.2926)
			(end -2.54 -4.2926)
			(stroke
				(width 0)
				(type default)
			)
			(fill no)
			(layer "F.Fab")
		)
		(pad "1" smd rect
			(at 0 -3.1496 180)
			(size 2.413 2.286)
			(layers "F.Cu" "F.Mask" "F.Paste")
			(net "P5VB")
		)
		(pad "2" smd rect
			(at 0 3.1496 180)
			(size 2.413 2.286)
			(layers "F.Cu" "F.Mask" "F.Paste")
			(net "GND")
		)
		(zone
			(layer "F.Cu")
			(hatch none 0.5)
			(connect_pads
				(clearance 0)
			)
			(min_thickness 0.25)
			(keepout
				(tracks allowed)
				(vias not_allowed)
				(pads allowed)
				(copperpour not_allowed)
				(footprints allowed)
			)
			(placement
				(enabled no)
				(sheetname "")
			)
			(fill
				(thermal_gap 0.5)
				(thermal_bridge_width 0.5)
				(island_removal_mode 0)
			)
			(polygon
				(pts
					(xy 37.737034 -28.810458) (xy 37.737034 -25.902158) (xy 40.759634 -25.902158) (xy 40.759634 -28.797758)
					(xy 40.759634 -29.127958) (xy 37.737034 -29.127958)
				)
			)
		)
		(zone
			(layer "F.Cu")
			(hatch none 0.5)
			(connect_pads
				(clearance 0)
			)
			(min_thickness 0.25)
			(keepout
				(tracks allowed)
				(vias not_allowed)
				(pads allowed)
				(copperpour not_allowed)
				(footprints allowed)
			)
			(placement
				(enabled no)
				(sheetname "")
			)
			(fill
				(thermal_gap 0.5)
				(thermal_bridge_width 0.5)
				(island_removal_mode 0)
			)
			(polygon
				(pts
					(xy 40.759634 -35.096958) (xy 37.737034 -35.096958) (xy 37.737034 -32.201358) (xy 37.737034 -31.871158)
					(xy 40.759634 -31.871158) (xy 40.759634 -32.201358)
				)
			)
		)
	)
	(footprint ""
		(layer "F.Cu")
		(at 227.499926 -67.669918 90)
		(property "Reference" "SKT5"
			(at 0 0 90)
			(layer "F.SilkS")
			(hide yes)
			(effects
				(font
					(size 1.27 1.27)
				)
			)
		)
		(property "Value" "SKT-SATA14P-15P-12-GP"
			(at -22.6187 8.1788 90)
			(unlocked yes)
			(layer "F.Fab")
			(hide yes)
			(effects
				(font
					(size 1.016 1.016)
					(thickness 0.1524)
				)
			)
		)
		(property "Device Type" "87945-1001"
			(at -22.6187 6.6548 90)
			(unlocked yes)
			(layer "F.Fab")
			(hide yes)
			(effects
				(font
					(size 1.016 1.016)
					(thickness 0.1524)
				)
			)
		)
		(duplicate_pad_numbers_are_jumpers no)
		(fp_line
			(start -15.3924 -5.8547)
			(end -16.3576 -5.8547)
			(stroke
				(width 0.3302)
				(type default)
			)
			(layer "F.SilkS")
		)
		(fp_line
			(start 20.4724 -5.7658)
			(end 20.4724 -2.3114)
			(stroke
				(width 0.1524)
				(type default)
			)
			(layer "F.SilkS")
		)
		(fp_line
			(start -20.4724 -5.7658)
			(end 20.4724 -5.7658)
			(stroke
				(width 0.1524)
				(type default)
			)
			(layer "F.SilkS")
		)
		(fp_line
			(start 23.7617 -2.3114)
			(end 23.7617 2.3114)
			(stroke
				(width 0.1524)
				(type default)
			)
			(layer "F.SilkS")
		)
		(fp_line
			(start 20.4724 -2.3114)
			(end 23.7617 -2.3114)
			(stroke
				(width 0.1524)
				(type default)
			)
			(layer "F.SilkS")
		)
		(fp_line
			(start -20.4724 -2.3114)
			(end -20.4724 -5.7658)
			(stroke
				(width 0.1524)
				(type default)
			)
			(layer "F.SilkS")
		)
		(fp_line
			(start -23.7617 -2.3114)
			(end -20.4724 -2.3114)
			(stroke
				(width 0.1524)
				(type default)
			)
			(layer "F.SilkS")
		)
		(fp_line
			(start 23.117556 -0.5461)
			(end 23.117556 0.5461)
			(stroke
				(width 0.3048)
				(type default)
			)
			(layer "F.SilkS")
		)
		(fp_line
			(start -20.882356 -0.5461)
			(end -20.882356 0.5461)
			(stroke
				(width 0.3048)
				(type default)
			)
			(layer "F.SilkS")
		)
		(fp_line
			(start 20.882356 0.5461)
			(end 20.882356 -0.5461)
			(stroke
				(width 0.3048)
				(type default)
			)
			(layer "F.SilkS")
		)
		(fp_line
			(start -23.117556 0.5461)
			(end -23.117556 -0.5461)
			(stroke
				(width 0.3048)
				(type default)
			)
			(layer "F.SilkS")
		)
		(fp_line
			(start 23.7617 2.3114)
			(end 20.4724 2.3114)
			(stroke
				(width 0.1524)
				(type default)
			)
			(layer "F.SilkS")
		)
		(fp_line
			(start 20.4724 2.3114)
			(end 20.4724 9.652)
			(stroke
				(width 0.1524)
				(type default)
			)
			(layer "F.SilkS")
		)
		(fp_line
			(start -20.4724 2.3114)
			(end -23.7617 2.3114)
			(stroke
				(width 0.1524)
				(type default)
			)
			(layer "F.SilkS")
		)
		(fp_line
			(start -23.7617 2.3114)
			(end -23.7617 -2.3114)
			(stroke
				(width 0.1524)
				(type default)
			)
			(layer "F.SilkS")
		)
		(fp_line
			(start 17.8435 7.9502)
			(end -17.8435 7.9502)
			(stroke
				(width 0.1524)
				(type default)
			)
			(layer "F.SilkS")
		)
		(fp_line
			(start -17.8435 7.9502)
			(end -17.8435 9.652)
			(stroke
				(width 0.1524)
				(type default)
			)
			(layer "F.SilkS")
		)
		(fp_line
			(start 20.4724 9.652)
			(end 17.8435 9.652)
			(stroke
				(width 0.1524)
				(type default)
			)
			(layer "F.SilkS")
		)
		(fp_line
			(start 17.8435 9.652)
			(end 17.8435 7.9502)
			(stroke
				(width 0.1524)
				(type default)
			)
			(layer "F.SilkS")
		)
		(fp_line
			(start -17.8435 9.652)
			(end -20.4724 9.652)
			(stroke
				(width 0.1524)
				(type default)
			)
			(layer "F.SilkS")
		)
		(fp_line
			(start -20.4724 9.652)
			(end -20.4724 2.3114)
			(stroke
				(width 0.1524)
				(type default)
			)
			(layer "F.SilkS")
		)
		(fp_arc
			(start 20.882356 -0.5461)
			(mid 21.999956 -1.6637)
			(end 23.117556 -0.5461)
			(stroke
				(width 0.3048)
				(type default)
			)
			(layer "F.SilkS")
		)
		(fp_arc
			(start -23.117556 -0.5461)
			(mid -21.999956 -1.6637)
			(end -20.882356 -0.5461)
			(stroke
				(width 0.3048)
				(type default)
			)
			(layer "F.SilkS")
		)
		(fp_arc
			(start 23.117556 0.5461)
			(mid 21.999956 1.6637)
			(end 20.882356 0.5461)
			(stroke
				(width 0.3048)
				(type default)
			)
			(layer "F.SilkS")
		)
		(fp_arc
			(start -20.882356 0.5461)
			(mid -21.999956 1.6637)
			(end -23.117556 0.5461)
			(stroke
				(width 0.3048)
				(type default)
			)
			(layer "F.SilkS")
		)
		(fp_poly
			(pts
				(xy -15.87119 -5.838698) (xy -15.23619 -6.473698) (xy -16.50619 -6.473698)
			)
			(stroke
				(width 0)
				(type default)
			)
			(fill yes)
			(layer "F.SilkS")
		)
		(fp_poly
			(pts
				(xy -20.2184 -5.5118) (xy 20.2184 -5.5118) (xy 20.2184 -2.0574) (xy 23.5077 -2.0574) (xy 23.5077 2.0574)
				(xy 20.2184 2.0574) (xy 20.2184 9.398) (xy 18.0975 9.398) (xy 18.0975 7.6962) (xy -18.0975 7.6962)
				(xy -18.0975 9.398) (xy -20.2184 9.398) (xy -20.2184 2.0574) (xy -23.5077 2.0574) (xy -23.5077 -2.0574)
				(xy -20.2184 -2.0574)
			)
			(stroke
				(width 0)
				(type default)
			)
			(fill no)
			(layer "F.CrtYd")
		)
		(fp_poly
			(pts
				(xy -20.2184 -5.5118) (xy -20.2184 -6.0198) (xy -20.7264 -6.0198) (xy -20.7264 -2.5654) (xy -24.0157 -2.5654)
				(xy -24.0157 2.5654) (xy -20.7264 2.5654) (xy -20.7264 9.906) (xy -17.5895 9.906) (xy -17.5895 8.2042)
				(xy 17.5895 8.2042) (xy 17.5895 9.906) (xy 20.7264 9.906) (xy 20.7264 2.5654) (xy 24.0157 2.5654)
				(xy 24.0157 -2.5654) (xy 20.7264 -2.5654) (xy 20.7264 -6.0198) (xy -20.21586 -6.0198) (xy -20.21586 -5.5118)
				(xy 20.2184 -5.5118) (xy 20.2184 -2.0574) (xy 23.5077 -2.0574) (xy 23.5077 2.0574) (xy 20.2184 2.0574)
				(xy 20.2184 9.398) (xy 18.0975 9.398) (xy 18.0975 7.6962) (xy -18.0975 7.6962) (xy -18.0975 9.398)
				(xy -20.2184 9.398) (xy -20.2184 2.0574) (xy -23.5077 2.0574) (xy -23.5077 -2.0574) (xy -20.2184 -2.0574)
			)
			(stroke
				(width 0)
				(type default)
			)
			(fill no)
			(layer "F.CrtYd")
		)
		(fp_poly
			(pts
				(xy -20.7264 -6.0198) (xy -20.7264 -2.5654) (xy -24.0157 -2.5654) (xy -24.0157 2.5654) (xy -20.7264 2.5654)
				(xy -20.7264 9.906) (xy -17.5895 9.906) (xy -17.5895 8.2042) (xy 17.5895 8.2042) (xy 17.5895 9.906)
				(xy 20.7264 9.906) (xy 20.7264 2.5654) (xy 24.0157 2.5654) (xy 24.0157 -2.5654) (xy 20.7264 -2.5654)
				(xy 20.7264 -6.0198)
			)
			(stroke
				(width 0)
				(type default)
			)
			(fill no)
			(layer "F.Fab")
		)
		(pad "" np_thru_hole circle
			(at -18.999962 -2.350008 90)
			(size 0.254 0.254)
			(drill 1.8542)
			(layers "*.Cu" "*.Mask")
			(clearance 1.1557)
			(thermal_gap 1.1557)
		)
		(pad "" np_thru_hole circle
			(at 18.999962 -2.350008 90)
			(size 0.254 0.254)
			(drill 1.8542)
			(layers "*.Cu" "*.Mask")
			(clearance 1.1557)
			(thermal_gap 1.1557)
		)
		(pad "H1" thru_hole oval
			(at -21.999956 0 90)
			(size 1.524 2.6162)
			(drill oval 0.8128 1.905)
			(layers "*.Cu" "*.Mask")
			(remove_unused_layers no)
			(net "GND")
			(clearance 0.1524)
			(thermal_gap 0.1524)
		)
		(pad "H2" thru_hole oval
			(at 21.999956 0 90)
			(size 1.524 2.6162)
			(drill oval 0.8128 1.905)
			(layers "*.Cu" "*.Mask")
			(remove_unused_layers no)
			(net "GND")
			(clearance 0.1524)
			(thermal_gap 0.1524)
		)
		(pad "P1" smd rect
			(at -1.89992 -4.249928 90)
			(size 0.6604 2.3876)
			(layers "F.Cu" "F.Mask" "F.Paste")
			(net "Net_25")
		)
		(pad "P2" smd rect
			(at -0.62992 -4.249928 90)
			(size 0.6604 2.3876)
			(layers "F.Cu" "F.Mask" "F.Paste")
			(net "Net_24")
		)
		(pad "P3" smd rect
			(at 0.64008 -4.249928 90)
			(size 0.6604 2.3876)
			(layers "F.Cu" "F.Mask" "F.Paste")
			(net "Net_23")
		)
		(pad "P4" smd rect
			(at 1.91008 -4.249928 90)
			(size 0.6604 2.3876)
			(layers "F.Cu" "F.Mask" "F.Paste")
			(net "GND")
		)
		(pad "P5" smd rect
			(at 3.18008 -4.249928 90)
			(size 0.6604 2.3876)
			(layers "F.Cu" "F.Mask" "F.Paste")
			(net "HDD_PRSNT_NET4")
		)
		(pad "P6" smd rect
			(at 4.45008 -4.249928 90)
			(size 0.6604 2.3876)
			(layers "F.Cu" "F.Mask" "F.Paste")
			(net "GND")
		)
		(pad "P7" smd rect
			(at 5.72008 -4.249928 90)
			(size 0.6604 2.3876)
			(layers "F.Cu" "F.Mask" "F.Paste")
			(net "5V_PRE_4")
		)
		(pad "P8" smd rect
			(at 6.99008 -4.249928 90)
			(size 0.6604 2.3876)
			(layers "F.Cu" "F.Mask" "F.Paste")
			(net "P5V_HDD4")
		)
		(pad "P9" smd rect
			(at 8.26008 -4.249928 90)
			(size 0.6604 2.3876)
			(layers "F.Cu" "F.Mask" "F.Paste")
			(net "P5V_HDD4")
		)
		(pad "P10" smd rect
			(at 9.53008 -4.249928 90)
			(size 0.6604 2.3876)
			(layers "F.Cu" "F.Mask" "F.Paste")
			(net "GND")
		)
		(pad "P11" smd rect
			(at 10.80008 -4.249928 90)
			(size 0.6604 2.3876)
			(layers "F.Cu" "F.Mask" "F.Paste")
			(net "ACT_HDD4")
		)
		(pad "P12" smd rect
			(at 12.07008 -4.249928 90)
			(size 0.6604 2.3876)
			(layers "F.Cu" "F.Mask" "F.Paste")
			(net "GND")
		)
		(pad "P13" smd rect
			(at 13.34008 -4.249928 90)
			(size 0.6604 2.3876)
			(layers "F.Cu" "F.Mask" "F.Paste")
			(net "12V_PRE_4")
		)
		(pad "P14" smd rect
			(at 14.61008 -4.249928 90)
			(size 0.6604 2.3876)
			(layers "F.Cu" "F.Mask" "F.Paste")
			(net "P12V_HDD4")
		)
		(pad "P15" smd rect
			(at 15.88008 -4.249928 90)
			(size 0.6604 2.3876)
			(layers "F.Cu" "F.Mask" "F.Paste")
			(net "P12V_HDD4")
		)
		(pad "S1" smd rect
			(at -15.86992 -4.249928 90)
			(size 0.6604 2.3876)
			(layers "F.Cu" "F.Mask" "F.Paste")
			(net "GND")
		)
		(pad "S2" smd rect
			(at -14.59992 -4.249928 90)
			(size 0.6604 2.3876)
			(layers "F.Cu" "F.Mask" "F.Paste")
			(net "SAS2X28_A_HDD4_TX_+")
		)
		(pad "S3" smd rect
			(at -13.32992 -4.249928 90)
			(size 0.6604 2.3876)
			(layers "F.Cu" "F.Mask" "F.Paste")
			(net "SAS2X28_A_HDD4_TX_-")
		)
		(pad "S4" smd rect
			(at -12.05992 -4.249928 90)
			(size 0.6604 2.3876)
			(layers "F.Cu" "F.Mask" "F.Paste")
			(net "GND")
		)
		(pad "S5" smd rect
			(at -10.78992 -4.249928 90)
			(size 0.6604 2.3876)
			(layers "F.Cu" "F.Mask" "F.Paste")
			(net "SAS2X28_DRIVE_RX_N_A4")
		)
		(pad "S6" smd rect
			(at -9.51992 -4.249928 90)
			(size 0.6604 2.3876)
			(layers "F.Cu" "F.Mask" "F.Paste")
			(net "SAS2X28_DRIVE_RX_P_A4")
		)
		(pad "S7" smd rect
			(at -8.24992 -4.249928 90)
			(size 0.6604 2.3876)
			(layers "F.Cu" "F.Mask" "F.Paste")
			(net "GND")
		)
		(pad "S8" smd rect
			(at -7.480046 -2.100072 90)
			(size 0.508 1.905)
			(layers "F.Cu" "F.Mask" "F.Paste")
			(net "GND")
		)
		(pad "S9" smd rect
			(at -6.679946 -2.100072 90)
			(size 0.508 1.905)
			(layers "F.Cu" "F.Mask" "F.Paste")
			(net "SAS2X28_B_HDD4_TX_+")
		)
		(pad "S10" smd rect
			(at -5.8801 -2.100072 90)
			(size 0.508 1.905)
			(layers "F.Cu" "F.Mask" "F.Paste")
			(net "SAS2X28_B_HDD4_TX_-")
		)
		(pad "S11" smd rect
			(at -5.08 -2.100072 90)
			(size 0.508 1.905)
			(layers "F.Cu" "F.Mask" "F.Paste")
			(net "GND")
		)
		(pad "S12" smd rect
			(at -4.2799 -2.100072 90)
			(size 0.508 1.905)
			(layers "F.Cu" "F.Mask" "F.Paste")
			(net "SAS2X28_DRIVE_RX_N_B4")
		)
		(pad "S13" smd rect
			(at -3.480054 -2.100072 90)
			(size 0.508 1.905)
			(layers "F.Cu" "F.Mask" "F.Paste")
			(net "SAS2X28_DRIVE_RX_P_B4")
		)
		(pad "S14" smd rect
			(at -2.679954 -2.100072 90)
			(size 0.508 1.905)
			(layers "F.Cu" "F.Mask" "F.Paste")
			(net "GND")
		)
		(zone
			(layers "F.Cu" "B.Cu" "In1.Cu" "In2.Cu" "In3.Cu" "In4.Cu" "In5.Cu" "In6.Cu")
			(hatch none 0.5)
			(connect_pads
				(clearance 0)
			)
			(min_thickness 0.25)
			(keepout
				(tracks not_allowed)
				(vias allowed)
				(pads allowed)
				(copperpour not_allowed)
				(footprints allowed)
			)
			(placement
				(enabled no)
				(sheetname "")
			)
			(fill
				(thermal_gap 0.5)
				(thermal_bridge_width 0.5)
				(island_removal_mode 0)
			)
			(polygon
				(pts
					(arc
						(start 226.381818 -86.66988)
						(mid 223.918018 -86.66988)
						(end 226.381818 -86.66988)
					)
				)
			)
		)
		(zone
			(layers "F.Cu" "B.Cu" "In1.Cu" "In2.Cu" "In3.Cu" "In4.Cu" "In5.Cu" "In6.Cu")
			(hatch none 0.5)
			(connect_pads
				(clearance 0)
			)
			(min_thickness 0.25)
			(keepout
				(tracks not_allowed)
				(vias allowed)
				(pads allowed)
				(copperpour not_allowed)
				(footprints allowed)
			)
			(placement
				(enabled no)
				(sheetname "")
			)
			(fill
				(thermal_gap 0.5)
				(thermal_bridge_width 0.5)
				(island_removal_mode 0)
			)
			(polygon
				(pts
					(arc
						(start 226.381818 -48.669956)
						(mid 223.918018 -48.669956)
						(end 226.381818 -48.669956)
					)
				)
			)
		)
	)
	(footprint ""
		(layer "F.Cu")
		(at 236.067346 -40.259 -90)
		(property "Reference" "R492"
			(at 0 0 270)
			(layer "F.SilkS")
			(hide yes)
			(effects
				(font
					(size 1.27 1.27)
				)
			)
		)
		(property "Value" "1KR2F-3-GP"
			(at 0.064008 -3.993896 270)
			(unlocked yes)
			(layer "F.Fab")
			(hide yes)
			(effects
				(font
					(size 1.016 1.016)
					(thickness 0.1524)
				)
			)
		)
		(property "Device Type" "R402H16"
			(at 0.064008 -5.517896 270)
			(unlocked yes)
			(layer "F.Fab")
			(hide yes)
			(effects
				(font
					(size 1.016 1.016)
					(thickness 0.1524)
				)
			)
		)
		(duplicate_pad_numbers_are_jumpers no)
		(fp_line
			(start -0.508 -0.9398)
			(end -0.508 0.9398)
			(stroke
				(width 0.1524)
				(type default)
			)
			(layer "F.SilkS")
		)
		(fp_line
			(start 0.508 -0.9398)
			(end -0.508 -0.9398)
			(stroke
				(width 0.1524)
				(type default)
			)
			(layer "F.SilkS")
		)
		(fp_rect
			(start -0.508 0.9398)
			(end 0.508 -0.9398)
			(stroke
				(width 0)
				(type default)
			)
			(fill no)
			(layer "F.CrtYd")
		)
		(fp_rect
			(start -0.508 0.9398)
			(end 0.508 -0.9398)
			(stroke
				(width 0)
				(type default)
			)
			(fill no)
			(layer "F.Fab")
		)
		(pad "1" smd custom
			(at 0 -0.4445 270)
			(size 0.1397 0.1397)
			(layers "F.Cu" "F.Mask" "F.Paste")
			(net "FLT_HDD4_B")
			(options
				(clearance outline)
				(anchor circle)
			)
			(primitives
				(gr_poly
					(pts
						(arc
							(start -0.1778 -0.2794)
							(mid -0.249642 -0.249642)
							(end -0.2794 -0.1778)
						)
						(arc
							(start -0.2794 0.1778)
							(mid -0.249642 0.249642)
							(end -0.1778 0.2794)
						)
						(arc
							(start 0.1778 0.2794)
							(mid 0.249642 0.249642)
							(end 0.2794 0.1778)
						)
						(arc
							(start 0.2794 -0.1778)
							(mid 0.249642 -0.249642)
							(end 0.1778 -0.2794)
						)
					)
					(width 0)
					(fill yes)
				)
			)
		)
		(pad "2" smd custom
			(at 0 0.4445 270)
			(size 0.1397 0.1397)
			(layers "F.Cu" "F.Mask" "F.Paste")
			(net "FLT_HDD4_DRIVE")
			(options
				(clearance outline)
				(anchor circle)
			)
			(primitives
				(gr_poly
					(pts
						(arc
							(start -0.1778 -0.2794)
							(mid -0.249642 -0.249642)
							(end -0.2794 -0.1778)
						)
						(arc
							(start -0.2794 0.1778)
							(mid -0.249642 0.249642)
							(end -0.1778 0.2794)
						)
						(arc
							(start 0.1778 0.2794)
							(mid 0.249642 0.249642)
							(end 0.2794 0.1778)
						)
						(arc
							(start 0.2794 -0.1778)
							(mid 0.249642 -0.249642)
							(end 0.1778 -0.2794)
						)
					)
					(width 0)
					(fill yes)
				)
			)
		)
	)
	(footprint ""
		(layer "F.Cu")
		(at 45.338746 -414.810702 90)
		(property "Reference" "U32"
			(at 0 0 90)
			(layer "F.SilkS")
			(hide yes)
			(effects
				(font
					(size 1.27 1.27)
				)
			)
		)
		(property "Value" "P2003EVG-GP"
			(at 0 -11.1252 90)
			(unlocked yes)
			(layer "F.Fab")
			(hide yes)
			(effects
				(font
					(size 1.016 1.016)
					(thickness 0.1524)
				)
			)
		)
		(property "Device Type" "SOIC8H79"
			(at 0 -12.6492 90)
			(unlocked yes)
			(layer "F.Fab")
			(hide yes)
			(effects
				(font
					(size 1.016 1.016)
					(thickness 0.1524)
				)
			)
		)
		(duplicate_pad_numbers_are_jumpers no)
		(fp_line
			(start 2.1336 -1.4224)
			(end -2.7432 -1.4224)
			(stroke
				(width 0.1524)
				(type default)
			)
			(layer "F.SilkS")
		)
		(fp_line
			(start -2.7432 -1.4224)
			(end -2.7432 1.4224)
			(stroke
				(width 0.1524)
				(type default)
			)
			(layer "F.SilkS")
		)
		(fp_line
			(start -2.7432 -0.508)
			(end -2.2352 0)
			(stroke
				(width 0.1524)
				(type default)
			)
			(layer "F.SilkS")
		)
		(fp_line
			(start -2.2352 0)
			(end -2.7432 0.508)
			(stroke
				(width 0.1524)
				(type default)
			)
			(layer "F.SilkS")
		)
		(fp_line
			(start 2.1336 1.4224)
			(end 2.1336 -1.4224)
			(stroke
				(width 0.1524)
				(type default)
			)
			(layer "F.SilkS")
		)
		(fp_line
			(start -2.7432 1.4224)
			(end 2.1336 1.4224)
			(stroke
				(width 0.1524)
				(type default)
			)
			(layer "F.SilkS")
		)
		(fp_line
			(start -2.6162 3.429)
			(end -2.6162 1.4732)
			(stroke
				(width 0.4064)
				(type default)
			)
			(layer "F.SilkS")
		)
		(fp_poly
			(pts
				(xy 2.2098 -1.4224) (xy 2.2098 1.4224) (xy -2.2225 1.4224) (xy -2.2225 -1.4224)
			)
			(stroke
				(width 0)
				(type default)
			)
			(fill yes)
			(layer "F.SilkS")
		)
		(fp_rect
			(start -2.4511 2.9972)
			(end 2.4511 -2.9972)
			(stroke
				(width 0)
				(type default)
			)
			(fill no)
			(layer "F.CrtYd")
		)
		(fp_poly
			(pts
				(xy -2.8194 3.6322) (xy -2.8194 -3.6322) (xy 2.8194 -3.6322) (xy 2.8194 -2.2987) (xy 2.4511 -2.2987)
				(xy 2.4511 -2.9972) (xy -2.4511 -2.9972) (xy -2.4511 2.9972) (xy 2.4511 2.9972) (xy 2.4511 -2.286)
				(xy 2.8194 -2.286) (xy 2.8194 3.6322)
			)
			(stroke
				(width 0)
				(type default)
			)
			(fill no)
			(layer "F.CrtYd")
		)
		(fp_rect
			(start -2.8194 3.6322)
			(end 2.8194 -3.6322)
			(stroke
				(width 0)
				(type default)
			)
			(fill no)
			(layer "F.Fab")
		)
		(pad "1" smd rect
			(at -1.905 2.54 90)
			(size 0.635 1.651)
			(layers "F.Cu" "F.Mask" "F.Paste")
			(net "P12V")
		)
		(pad "2" smd rect
			(at -0.635 2.54 90)
			(size 0.635 1.651)
			(layers "F.Cu" "F.Mask" "F.Paste")
			(net "P12V")
		)
		(pad "3" smd rect
			(at 0.635 2.54 90)
			(size 0.635 1.651)
			(layers "F.Cu" "F.Mask" "F.Paste")
			(net "P12V")
		)
		(pad "4" smd rect
			(at 1.905 2.54 90)
			(size 0.635 1.651)
			(layers "F.Cu" "F.Mask" "F.Paste")
			(net "SW_HDD10_N")
		)
		(pad "5" smd rect
			(at 1.905 -2.54 90)
			(size 0.635 1.651)
			(layers "F.Cu" "F.Mask" "F.Paste")
			(net "P12V_HDD10")
		)
		(pad "6" smd rect
			(at 0.635 -2.54 90)
			(size 0.635 1.651)
			(layers "F.Cu" "F.Mask" "F.Paste")
			(net "P12V_HDD10")
		)
		(pad "7" smd rect
			(at -0.635 -2.54 90)
			(size 0.635 1.651)
			(layers "F.Cu" "F.Mask" "F.Paste")
			(net "P12V_HDD10")
		)
		(pad "8" smd rect
			(at -1.905 -2.54 90)
			(size 0.635 1.651)
			(layers "F.Cu" "F.Mask" "F.Paste")
			(net "P12V_HDD10")
		)
	)
	(footprint ""
		(layer "F.Cu")
		(at 59.943746 -10.8077 90)
		(property "Reference" "PC24"
			(at 0 0 90)
			(layer "F.SilkS")
			(hide yes)
			(effects
				(font
					(size 1.27 1.27)
				)
			)
		)
		(property "Value" "SC22U25V5MX-GP"
			(at -0.0762 -6.1214 90)
			(unlocked yes)
			(layer "F.Fab")
			(hide yes)
			(effects
				(font
					(size 1.016 1.016)
					(thickness 0.1524)
				)
			)
		)
		(property "Device Type" "C805H58"
			(at -0.0762 -8.1534 90)
			(unlocked yes)
			(layer "F.Fab")
			(hide yes)
			(effects
				(font
					(size 1.016 1.016)
					(thickness 0.1524)
				)
			)
		)
		(duplicate_pad_numbers_are_jumpers no)
		(fp_line
			(start 0.635 0)
			(end -0.635 0)
			(stroke
				(width 0.508)
				(type default)
			)
			(layer "F.SilkS")
		)
		(fp_rect
			(start -0.9652 1.778)
			(end 0.9652 -1.778)
			(stroke
				(width 0)
				(type default)
			)
			(fill no)
			(layer "F.CrtYd")
		)
		(fp_poly
			(pts
				(xy -0.9652 -1.778) (xy 0.9652 -1.778) (xy 0.9652 1.778) (xy -0.9652 1.778)
			)
			(stroke
				(width 0)
				(type default)
			)
			(fill no)
			(layer "F.Fab")
		)
		(pad "1" smd rect
			(at 0 -0.9652 90)
			(size 1.397 1.143)
			(layers "F.Cu" "F.Mask" "F.Paste")
			(net "P5VB_12VIN")
		)
		(pad "2" smd rect
			(at 0 0.9652 90)
			(size 1.397 1.143)
			(layers "F.Cu" "F.Mask" "F.Paste")
			(net "GND")
		)
	)
	(footprint ""
		(layer "F.Cu")
		(at 192.913 -487.934)
		(property "Reference" "C110"
			(at 0 0 0)
			(layer "F.SilkS")
			(hide yes)
			(effects
				(font
					(size 1.27 1.27)
				)
			)
		)
		(property "Value" "SCD1U10V2KX-5GP"
			(at 1.1811 -2.7051 0)
			(unlocked yes)
			(layer "F.Fab")
			(hide yes)
			(effects
				(font
					(size 1.016 1.016)
					(thickness 0.1524)
				)
			)
		)
		(property "Device Type" "C402H22"
			(at 1.1811 -4.2291 0)
			(unlocked yes)
			(layer "F.Fab")
			(hide yes)
			(effects
				(font
					(size 1.016 1.016)
					(thickness 0.1524)
				)
			)
		)
		(duplicate_pad_numbers_are_jumpers no)
		(fp_rect
			(start -0.4318 0.9525)
			(end 0.4318 -0.9525)
			(stroke
				(width 0)
				(type default)
			)
			(fill no)
			(layer "F.CrtYd")
		)
		(fp_rect
			(start -0.4318 0.9525)
			(end 0.4318 -0.9525)
			(stroke
				(width 0)
				(type default)
			)
			(fill no)
			(layer "F.Fab")
		)
		(pad "1" smd custom
			(at 0 -0.4445)
			(size 0.1524 0.1524)
			(layers "F.Cu" "F.Mask" "F.Paste")
			(net "P3V3")
			(options
				(clearance outline)
				(anchor circle)
			)
			(primitives
				(gr_poly
					(pts
						(arc
							(start 0.3048 -0.2032)
							(mid 0.275042 -0.275042)
							(end 0.2032 -0.3048)
						)
						(arc
							(start -0.2032 -0.3048)
							(mid -0.275042 -0.275042)
							(end -0.3048 -0.2032)
						)
						(arc
							(start -0.3048 0.2032)
							(mid -0.275042 0.275042)
							(end -0.2032 0.3048)
						)
						(arc
							(start 0.2032 0.3048)
							(mid 0.275042 0.275042)
							(end 0.3048 0.2032)
						)
					)
					(width 0)
					(fill yes)
				)
			)
		)
		(pad "2" smd custom
			(at 0 0.4445)
			(size 0.1524 0.1524)
			(layers "F.Cu" "F.Mask" "F.Paste")
			(net "GND")
			(options
				(clearance outline)
				(anchor circle)
			)
			(primitives
				(gr_poly
					(pts
						(arc
							(start 0.3048 -0.2032)
							(mid 0.275042 -0.275042)
							(end 0.2032 -0.3048)
						)
						(arc
							(start -0.2032 -0.3048)
							(mid -0.275042 -0.275042)
							(end -0.3048 -0.2032)
						)
						(arc
							(start -0.3048 0.2032)
							(mid -0.275042 0.275042)
							(end -0.2032 0.3048)
						)
						(arc
							(start 0.2032 0.3048)
							(mid 0.275042 0.275042)
							(end 0.3048 0.2032)
						)
					)
					(width 0)
					(fill yes)
				)
			)
		)
	)
	(footprint ""
		(layer "F.Cu")
		(at 11.8872 -104.2924 180)
		(property "Reference" "R406"
			(at 0 0 180)
			(layer "F.SilkS")
			(hide yes)
			(effects
				(font
					(size 1.27 1.27)
				)
			)
		)
		(property "Value" "10KR2F-2-GP"
			(at 0.064008 -3.993896 180)
			(unlocked yes)
			(layer "F.Fab")
			(hide yes)
			(effects
				(font
					(size 1.016 1.016)
					(thickness 0.1524)
				)
			)
		)
		(property "Device Type" "R402H16"
			(at 0.064008 -5.517896 180)
			(unlocked yes)
			(layer "F.Fab")
			(hide yes)
			(effects
				(font
					(size 1.016 1.016)
					(thickness 0.1524)
				)
			)
		)
		(duplicate_pad_numbers_are_jumpers no)
		(fp_line
			(start 0.508 -0.9398)
			(end -0.508 -0.9398)
			(stroke
				(width 0.1524)
				(type default)
			)
			(layer "F.SilkS")
		)
		(fp_line
			(start -0.508 -0.9398)
			(end -0.508 0.9398)
			(stroke
				(width 0.1524)
				(type default)
			)
			(layer "F.SilkS")
		)
		(fp_rect
			(start -0.508 0.9398)
			(end 0.508 -0.9398)
			(stroke
				(width 0)
				(type default)
			)
			(fill no)
			(layer "F.CrtYd")
		)
		(fp_rect
			(start -0.508 0.9398)
			(end 0.508 -0.9398)
			(stroke
				(width 0)
				(type default)
			)
			(fill no)
			(layer "F.Fab")
		)
		(pad "1" smd custom
			(at 0 -0.4445 180)
			(size 0.1397 0.1397)
			(layers "F.Cu" "F.Mask" "F.Paste")
			(net "P3V3")
			(options
				(clearance outline)
				(anchor circle)
			)
			(primitives
				(gr_poly
					(pts
						(arc
							(start -0.1778 -0.2794)
							(mid -0.249642 -0.249642)
							(end -0.2794 -0.1778)
						)
						(arc
							(start -0.2794 0.1778)
							(mid -0.249642 0.249642)
							(end -0.1778 0.2794)
						)
						(arc
							(start 0.1778 0.2794)
							(mid 0.249642 0.249642)
							(end 0.2794 0.1778)
						)
						(arc
							(start 0.2794 -0.1778)
							(mid 0.249642 -0.249642)
							(end 0.1778 -0.2794)
						)
					)
					(width 0)
					(fill yes)
				)
			)
		)
		(pad "2" smd custom
			(at 0 0.4445 180)
			(size 0.1397 0.1397)
			(layers "F.Cu" "F.Mask" "F.Paste")
			(net "DPB_HW_REV")
			(options
				(clearance outline)
				(anchor circle)
			)
			(primitives
				(gr_poly
					(pts
						(arc
							(start -0.1778 -0.2794)
							(mid -0.249642 -0.249642)
							(end -0.2794 -0.1778)
						)
						(arc
							(start -0.2794 0.1778)
							(mid -0.249642 0.249642)
							(end -0.1778 0.2794)
						)
						(arc
							(start 0.1778 0.2794)
							(mid 0.249642 0.249642)
							(end 0.2794 0.1778)
						)
						(arc
							(start 0.2794 -0.1778)
							(mid 0.249642 -0.249642)
							(end 0.1778 -0.2794)
						)
					)
					(width 0)
					(fill yes)
				)
			)
		)
	)
	(footprint ""
		(layer "F.Cu")
		(at 55.9562 -396.9004 180)
		(property "Reference" "C210"
			(at 0 0 180)
			(layer "F.SilkS")
			(hide yes)
			(effects
				(font
					(size 1.27 1.27)
				)
			)
		)
		(property "Value" "SC10U25V6KX-1GP"
			(at -0.0762 -5.1308 180)
			(unlocked yes)
			(layer "F.Fab")
			(hide yes)
			(effects
				(font
					(size 1.016 1.016)
					(thickness 0.1524)
				)
			)
		)
		(property "Device Type" "C1206H71"
			(at -0.127 -6.6548 180)
			(unlocked yes)
			(layer "F.Fab")
			(hide yes)
			(effects
				(font
					(size 1.016 1.016)
					(thickness 0.1524)
				)
			)
		)
		(duplicate_pad_numbers_are_jumpers no)
		(fp_line
			(start 1.016 2.2352)
			(end -1.016 2.2352)
			(stroke
				(width 0.1524)
				(type default)
			)
			(layer "F.SilkS")
		)
		(fp_line
			(start 1.016 0.8382)
			(end 1.016 2.2352)
			(stroke
				(width 0.1524)
				(type default)
			)
			(layer "F.SilkS")
		)
		(fp_line
			(start 1.016 -2.2352)
			(end 1.016 -0.8382)
			(stroke
				(width 0.1524)
				(type default)
			)
			(layer "F.SilkS")
		)
		(fp_line
			(start -1.016 2.2352)
			(end -1.016 0.8382)
			(stroke
				(width 0.1524)
				(type default)
			)
			(layer "F.SilkS")
		)
		(fp_line
			(start -1.016 -0.8382)
			(end -1.016 -2.2352)
			(stroke
				(width 0.1524)
				(type default)
			)
			(layer "F.SilkS")
		)
		(fp_line
			(start -1.016 -2.2352)
			(end 1.016 -2.2352)
			(stroke
				(width 0.1524)
				(type default)
			)
			(layer "F.SilkS")
		)
		(fp_rect
			(start -1.0922 2.3114)
			(end 1.0922 -2.3114)
			(stroke
				(width 0)
				(type default)
			)
			(fill no)
			(layer "F.CrtYd")
		)
		(fp_poly
			(pts
				(xy 1.0922 -2.3114) (xy 1.0922 2.3114) (xy -1.0922 2.3114) (xy -1.0922 -2.3114)
			)
			(stroke
				(width 0)
				(type default)
			)
			(fill no)
			(layer "F.Fab")
		)
		(pad "1" smd rect
			(at 0 -1.397 180)
			(size 1.651 1.27)
			(layers "F.Cu" "F.Mask" "F.Paste")
			(net "P12V_HDD6")
		)
		(pad "2" smd rect
			(at 0 1.397 180)
			(size 1.651 1.27)
			(layers "F.Cu" "F.Mask" "F.Paste")
			(net "GND")
		)
	)
	(footprint ""
		(layer "F.Cu")
		(at 216.910412 -70.592696)
		(property "Reference" "R167"
			(at 0 0 0)
			(layer "F.SilkS")
			(hide yes)
			(effects
				(font
					(size 1.27 1.27)
				)
			)
		)
		(property "Value" "220R3F-1-GP"
			(at -0.0254 -2.5146 0)
			(unlocked yes)
			(layer "F.Fab")
			(hide yes)
			(effects
				(font
					(size 1.016 1.016)
					(thickness 0.1524)
				)
			)
		)
		(property "Device Type" "R603H22"
			(at -0.0254 -4.0386 0)
			(unlocked yes)
			(layer "F.Fab")
			(hide yes)
			(effects
				(font
					(size 1.016 1.016)
					(thickness 0.1524)
				)
			)
		)
		(duplicate_pad_numbers_are_jumpers no)
		(fp_line
			(start -0.4826 0)
			(end -0.2032 0)
			(stroke
				(width 0.2032)
				(type default)
			)
			(layer "F.SilkS")
		)
		(fp_line
			(start 0.2032 0)
			(end 0.4826 0)
			(stroke
				(width 0.2032)
				(type default)
			)
			(layer "F.SilkS")
		)
		(fp_rect
			(start -0.5842 1.3335)
			(end 0.5842 -1.3335)
			(stroke
				(width 0)
				(type default)
			)
			(fill no)
			(layer "F.CrtYd")
		)
		(fp_rect
			(start -0.5842 1.3335)
			(end 0.5842 -1.3335)
			(stroke
				(width 0)
				(type default)
			)
			(fill no)
			(layer "F.Fab")
		)
		(pad "1" smd custom
			(at 0 -0.762)
			(size 0.2159 0.2159)
			(layers "F.Cu" "F.Mask" "F.Paste")
			(net "HDD_PRSNT_NET4")
			(options
				(clearance outline)
				(anchor circle)
			)
			(primitives
				(gr_poly
					(pts
						(arc
							(start -0.3302 -0.4318)
							(mid -0.402042 -0.402042)
							(end -0.4318 -0.3302)
						)
						(arc
							(start -0.4318 0.3302)
							(mid -0.402042 0.402042)
							(end -0.3302 0.4318)
						)
						(arc
							(start 0.3302 0.4318)
							(mid 0.402042 0.402042)
							(end 0.4318 0.3302)
						)
						(arc
							(start 0.4318 -0.3302)
							(mid 0.402042 -0.402042)
							(end 0.3302 -0.4318)
						)
					)
					(width 0)
					(fill yes)
				)
			)
		)
		(pad "2" smd custom
			(at 0 0.762)
			(size 0.2159 0.2159)
			(layers "F.Cu" "F.Mask" "F.Paste")
			(net "HDD_PRSNT4")
			(options
				(clearance outline)
				(anchor circle)
			)
			(primitives
				(gr_poly
					(pts
						(arc
							(start -0.3302 -0.4318)
							(mid -0.402042 -0.402042)
							(end -0.4318 -0.3302)
						)
						(arc
							(start -0.4318 0.3302)
							(mid -0.402042 0.402042)
							(end -0.3302 0.4318)
						)
						(arc
							(start 0.3302 0.4318)
							(mid 0.402042 0.402042)
							(end 0.4318 0.3302)
						)
						(arc
							(start 0.4318 -0.3302)
							(mid 0.402042 -0.402042)
							(end 0.3302 -0.4318)
						)
					)
					(width 0)
					(fill yes)
				)
			)
		)
	)
	(footprint ""
		(layer "F.Cu")
		(at 77.977746 -86.1187 -90)
		(property "Reference" "R239"
			(at 0 0 270)
			(layer "F.SilkS")
			(hide yes)
			(effects
				(font
					(size 1.27 1.27)
				)
			)
		)
		(property "Value" "0R2J-2-GP"
			(at 0.064008 -3.993896 270)
			(unlocked yes)
			(layer "F.Fab")
			(hide yes)
			(effects
				(font
					(size 1.016 1.016)
					(thickness 0.1524)
				)
			)
		)
		(property "Device Type" "R402H16"
			(at 0.064008 -5.517896 270)
			(unlocked yes)
			(layer "F.Fab")
			(hide yes)
			(effects
				(font
					(size 1.016 1.016)
					(thickness 0.1524)
				)
			)
		)
		(duplicate_pad_numbers_are_jumpers no)
		(fp_line
			(start -0.508 -0.9398)
			(end -0.508 0.9398)
			(stroke
				(width 0.1524)
				(type default)
			)
			(layer "F.SilkS")
		)
		(fp_line
			(start 0.508 -0.9398)
			(end -0.508 -0.9398)
			(stroke
				(width 0.1524)
				(type default)
			)
			(layer "F.SilkS")
		)
		(fp_rect
			(start -0.508 0.9398)
			(end 0.508 -0.9398)
			(stroke
				(width 0)
				(type default)
			)
			(fill no)
			(layer "F.CrtYd")
		)
		(fp_rect
			(start -0.508 0.9398)
			(end 0.508 -0.9398)
			(stroke
				(width 0)
				(type default)
			)
			(fill no)
			(layer "F.Fab")
		)
		(pad "1" smd custom
			(at 0 -0.4445 270)
			(size 0.1397 0.1397)
			(layers "F.Cu" "F.Mask" "F.Paste")
			(net "DRIVE_PWR9")
			(options
				(clearance outline)
				(anchor circle)
			)
			(primitives
				(gr_poly
					(pts
						(arc
							(start -0.1778 -0.2794)
							(mid -0.249642 -0.249642)
							(end -0.2794 -0.1778)
						)
						(arc
							(start -0.2794 0.1778)
							(mid -0.249642 0.249642)
							(end -0.1778 0.2794)
						)
						(arc
							(start 0.1778 0.2794)
							(mid 0.249642 0.249642)
							(end 0.2794 0.1778)
						)
						(arc
							(start 0.2794 -0.1778)
							(mid 0.249642 -0.249642)
							(end 0.1778 -0.2794)
						)
					)
					(width 0)
					(fill yes)
				)
			)
		)
		(pad "2" smd custom
			(at 0 0.4445 270)
			(size 0.1397 0.1397)
			(layers "F.Cu" "F.Mask" "F.Paste")
			(net "SW_PWR_HDD9")
			(options
				(clearance outline)
				(anchor circle)
			)
			(primitives
				(gr_poly
					(pts
						(arc
							(start -0.1778 -0.2794)
							(mid -0.249642 -0.249642)
							(end -0.2794 -0.1778)
						)
						(arc
							(start -0.2794 0.1778)
							(mid -0.249642 0.249642)
							(end -0.1778 0.2794)
						)
						(arc
							(start 0.1778 0.2794)
							(mid 0.249642 0.249642)
							(end 0.2794 0.1778)
						)
						(arc
							(start 0.2794 -0.1778)
							(mid 0.249642 -0.249642)
							(end 0.1778 -0.2794)
						)
					)
					(width 0)
					(fill yes)
				)
			)
		)
	)
	(footprint ""
		(layer "F.Cu")
		(at 52.07 -418.973 90)
		(property "Reference" "R558"
			(at 0 0 90)
			(layer "F.SilkS")
			(hide yes)
			(effects
				(font
					(size 1.27 1.27)
				)
			)
		)
		(property "Value" "200KR2F-L-GP"
			(at 0.064008 -3.993896 90)
			(unlocked yes)
			(layer "F.Fab")
			(hide yes)
			(effects
				(font
					(size 1.016 1.016)
					(thickness 0.1524)
				)
			)
		)
		(property "Device Type" "R402H16"
			(at 0.064008 -5.517896 90)
			(unlocked yes)
			(layer "F.Fab")
			(hide yes)
			(effects
				(font
					(size 1.016 1.016)
					(thickness 0.1524)
				)
			)
		)
		(duplicate_pad_numbers_are_jumpers no)
		(fp_line
			(start 0.508 -0.9398)
			(end -0.508 -0.9398)
			(stroke
				(width 0.1524)
				(type default)
			)
			(layer "F.SilkS")
		)
		(fp_line
			(start -0.508 -0.9398)
			(end -0.508 0.9398)
			(stroke
				(width 0.1524)
				(type default)
			)
			(layer "F.SilkS")
		)
		(fp_rect
			(start -0.508 0.9398)
			(end 0.508 -0.9398)
			(stroke
				(width 0)
				(type default)
			)
			(fill no)
			(layer "F.CrtYd")
		)
		(fp_rect
			(start -0.508 0.9398)
			(end 0.508 -0.9398)
			(stroke
				(width 0)
				(type default)
			)
			(fill no)
			(layer "F.Fab")
		)
		(pad "1" smd custom
			(at 0 -0.4445 90)
			(size 0.1397 0.1397)
			(layers "F.Cu" "F.Mask" "F.Paste")
			(net "SW_HDD10_R")
			(options
				(clearance outline)
				(anchor circle)
			)
			(primitives
				(gr_poly
					(pts
						(arc
							(start -0.1778 -0.2794)
							(mid -0.249642 -0.249642)
							(end -0.2794 -0.1778)
						)
						(arc
							(start -0.2794 0.1778)
							(mid -0.249642 0.249642)
							(end -0.1778 0.2794)
						)
						(arc
							(start 0.1778 0.2794)
							(mid 0.249642 0.249642)
							(end 0.2794 0.1778)
						)
						(arc
							(start 0.2794 -0.1778)
							(mid 0.249642 -0.249642)
							(end 0.1778 -0.2794)
						)
					)
					(width 0)
					(fill yes)
				)
			)
		)
		(pad "2" smd custom
			(at 0 0.4445 90)
			(size 0.1397 0.1397)
			(layers "F.Cu" "F.Mask" "F.Paste")
			(net "SW_HDD10_N")
			(options
				(clearance outline)
				(anchor circle)
			)
			(primitives
				(gr_poly
					(pts
						(arc
							(start -0.1778 -0.2794)
							(mid -0.249642 -0.249642)
							(end -0.2794 -0.1778)
						)
						(arc
							(start -0.2794 0.1778)
							(mid -0.249642 0.249642)
							(end -0.1778 0.2794)
						)
						(arc
							(start 0.1778 0.2794)
							(mid 0.249642 0.249642)
							(end 0.2794 0.1778)
						)
						(arc
							(start 0.2794 -0.1778)
							(mid 0.249642 -0.249642)
							(end 0.1778 -0.2794)
						)
					)
					(width 0)
					(fill yes)
				)
			)
		)
	)
	(footprint ""
		(layer "F.Cu")
		(at 25.527 -282.829)
		(property "Reference" "R204"
			(at 0 0 0)
			(layer "F.SilkS")
			(hide yes)
			(effects
				(font
					(size 1.27 1.27)
				)
			)
		)
		(property "Value" "4K7R2J-2-GP"
			(at 0.064008 -3.993896 0)
			(unlocked yes)
			(layer "F.Fab")
			(hide yes)
			(effects
				(font
					(size 1.016 1.016)
					(thickness 0.1524)
				)
			)
		)
		(property "Device Type" "R402H16"
			(at 0.064008 -5.517896 0)
			(unlocked yes)
			(layer "F.Fab")
			(hide yes)
			(effects
				(font
					(size 1.016 1.016)
					(thickness 0.1524)
				)
			)
		)
		(duplicate_pad_numbers_are_jumpers no)
		(fp_line
			(start -0.508 -0.9398)
			(end -0.508 0.9398)
			(stroke
				(width 0.1524)
				(type default)
			)
			(layer "F.SilkS")
		)
		(fp_line
			(start 0.508 -0.9398)
			(end -0.508 -0.9398)
			(stroke
				(width 0.1524)
				(type default)
			)
			(layer "F.SilkS")
		)
		(fp_rect
			(start -0.508 0.9398)
			(end 0.508 -0.9398)
			(stroke
				(width 0)
				(type default)
			)
			(fill no)
			(layer "F.CrtYd")
		)
		(fp_rect
			(start -0.508 0.9398)
			(end 0.508 -0.9398)
			(stroke
				(width 0)
				(type default)
			)
			(fill no)
			(layer "F.Fab")
		)
		(pad "1" smd custom
			(at 0 -0.4445)
			(size 0.1397 0.1397)
			(layers "F.Cu" "F.Mask" "F.Paste")
			(net "P12V")
			(options
				(clearance outline)
				(anchor circle)
			)
			(primitives
				(gr_poly
					(pts
						(arc
							(start -0.1778 -0.2794)
							(mid -0.249642 -0.249642)
							(end -0.2794 -0.1778)
						)
						(arc
							(start -0.2794 0.1778)
							(mid -0.249642 0.249642)
							(end -0.1778 0.2794)
						)
						(arc
							(start 0.1778 0.2794)
							(mid 0.249642 0.249642)
							(end 0.2794 0.1778)
						)
						(arc
							(start 0.2794 -0.1778)
							(mid 0.249642 -0.249642)
							(end 0.1778 -0.2794)
						)
					)
					(width 0)
					(fill yes)
				)
			)
		)
		(pad "2" smd custom
			(at 0 0.4445)
			(size 0.1397 0.1397)
			(layers "F.Cu" "F.Mask" "F.Paste")
			(net "SW_HDD7_R")
			(options
				(clearance outline)
				(anchor circle)
			)
			(primitives
				(gr_poly
					(pts
						(arc
							(start -0.1778 -0.2794)
							(mid -0.249642 -0.249642)
							(end -0.2794 -0.1778)
						)
						(arc
							(start -0.2794 0.1778)
							(mid -0.249642 0.249642)
							(end -0.1778 0.2794)
						)
						(arc
							(start 0.1778 0.2794)
							(mid 0.249642 0.249642)
							(end 0.2794 0.1778)
						)
						(arc
							(start 0.2794 -0.1778)
							(mid 0.249642 -0.249642)
							(end 0.1778 -0.2794)
						)
					)
					(width 0)
					(fill yes)
				)
			)
		)
	)
	(footprint ""
		(layer "F.Cu")
		(at 33.273746 -263.9187 -90)
		(property "Reference" "C215"
			(at 0 0 270)
			(layer "F.SilkS")
			(hide yes)
			(effects
				(font
					(size 1.27 1.27)
				)
			)
		)
		(property "Value" "SCD01U50V2KX-1GP"
			(at 1.1811 -2.7051 270)
			(unlocked yes)
			(layer "F.Fab")
			(hide yes)
			(effects
				(font
					(size 1.016 1.016)
					(thickness 0.1524)
				)
			)
		)
		(property "Device Type" "C402H22"
			(at 1.1811 -4.2291 270)
			(unlocked yes)
			(layer "F.Fab")
			(hide yes)
			(effects
				(font
					(size 1.016 1.016)
					(thickness 0.1524)
				)
			)
		)
		(duplicate_pad_numbers_are_jumpers no)
		(fp_rect
			(start -0.4318 0.9525)
			(end 0.4318 -0.9525)
			(stroke
				(width 0)
				(type default)
			)
			(fill no)
			(layer "F.CrtYd")
		)
		(fp_rect
			(start -0.4318 0.9525)
			(end 0.4318 -0.9525)
			(stroke
				(width 0)
				(type default)
			)
			(fill no)
			(layer "F.Fab")
		)
		(pad "1" smd custom
			(at 0 -0.4445 270)
			(size 0.1524 0.1524)
			(layers "F.Cu" "F.Mask" "F.Paste")
			(net "SAS2X28_DRIVE_RX_P_A7")
			(options
				(clearance outline)
				(anchor circle)
			)
			(primitives
				(gr_poly
					(pts
						(arc
							(start 0.3048 -0.2032)
							(mid 0.275042 -0.275042)
							(end 0.2032 -0.3048)
						)
						(arc
							(start -0.2032 -0.3048)
							(mid -0.275042 -0.275042)
							(end -0.3048 -0.2032)
						)
						(arc
							(start -0.3048 0.2032)
							(mid -0.275042 0.275042)
							(end -0.2032 0.3048)
						)
						(arc
							(start 0.2032 0.3048)
							(mid 0.275042 0.275042)
							(end 0.3048 0.2032)
						)
					)
					(width 0)
					(fill yes)
				)
			)
		)
		(pad "2" smd custom
			(at 0 0.4445 270)
			(size 0.1524 0.1524)
			(layers "F.Cu" "F.Mask" "F.Paste")
			(net "SAS2X28_A_HDD7_RX_+")
			(options
				(clearance outline)
				(anchor circle)
			)
			(primitives
				(gr_poly
					(pts
						(arc
							(start 0.3048 -0.2032)
							(mid 0.275042 -0.275042)
							(end 0.2032 -0.3048)
						)
						(arc
							(start -0.2032 -0.3048)
							(mid -0.275042 -0.275042)
							(end -0.3048 -0.2032)
						)
						(arc
							(start -0.3048 0.2032)
							(mid -0.275042 0.275042)
							(end -0.2032 0.3048)
						)
						(arc
							(start 0.2032 0.3048)
							(mid 0.275042 0.275042)
							(end 0.3048 0.2032)
						)
					)
					(width 0)
					(fill yes)
				)
			)
		)
	)
	(footprint ""
		(layer "F.Cu")
		(at 78.994 -196.342)
		(property "Reference" "R571"
			(at 0 0 0)
			(layer "F.SilkS")
			(hide yes)
			(effects
				(font
					(size 1.27 1.27)
				)
			)
		)
		(property "Value" "300KR2F-GP"
			(at 0.064008 -3.993896 0)
			(unlocked yes)
			(layer "F.Fab")
			(hide yes)
			(effects
				(font
					(size 1.016 1.016)
					(thickness 0.1524)
				)
			)
		)
		(property "Device Type" "R402H16"
			(at 0.064008 -5.517896 0)
			(unlocked yes)
			(layer "F.Fab")
			(hide yes)
			(effects
				(font
					(size 1.016 1.016)
					(thickness 0.1524)
				)
			)
		)
		(duplicate_pad_numbers_are_jumpers no)
		(fp_line
			(start -0.508 -0.9398)
			(end -0.508 0.9398)
			(stroke
				(width 0.1524)
				(type default)
			)
			(layer "F.SilkS")
		)
		(fp_line
			(start 0.508 -0.9398)
			(end -0.508 -0.9398)
			(stroke
				(width 0.1524)
				(type default)
			)
			(layer "F.SilkS")
		)
		(fp_rect
			(start -0.508 0.9398)
			(end 0.508 -0.9398)
			(stroke
				(width 0)
				(type default)
			)
			(fill no)
			(layer "F.CrtYd")
		)
		(fp_rect
			(start -0.508 0.9398)
			(end 0.508 -0.9398)
			(stroke
				(width 0)
				(type default)
			)
			(fill no)
			(layer "F.Fab")
		)
		(pad "1" smd custom
			(at 0 -0.4445)
			(size 0.1397 0.1397)
			(layers "F.Cu" "F.Mask" "F.Paste")
			(net "SW_HDD8_N")
			(options
				(clearance outline)
				(anchor circle)
			)
			(primitives
				(gr_poly
					(pts
						(arc
							(start -0.1778 -0.2794)
							(mid -0.249642 -0.249642)
							(end -0.2794 -0.1778)
						)
						(arc
							(start -0.2794 0.1778)
							(mid -0.249642 0.249642)
							(end -0.1778 0.2794)
						)
						(arc
							(start 0.1778 0.2794)
							(mid 0.249642 0.249642)
							(end 0.2794 0.1778)
						)
						(arc
							(start 0.2794 -0.1778)
							(mid 0.249642 -0.249642)
							(end 0.1778 -0.2794)
						)
					)
					(width 0)
					(fill yes)
				)
			)
		)
		(pad "2" smd custom
			(at 0 0.4445)
			(size 0.1397 0.1397)
			(layers "F.Cu" "F.Mask" "F.Paste")
			(net "P12V")
			(options
				(clearance outline)
				(anchor circle)
			)
			(primitives
				(gr_poly
					(pts
						(arc
							(start -0.1778 -0.2794)
							(mid -0.249642 -0.249642)
							(end -0.2794 -0.1778)
						)
						(arc
							(start -0.2794 0.1778)
							(mid -0.249642 0.249642)
							(end -0.1778 0.2794)
						)
						(arc
							(start 0.1778 0.2794)
							(mid 0.249642 0.249642)
							(end 0.2794 0.1778)
						)
						(arc
							(start 0.2794 -0.1778)
							(mid 0.249642 -0.249642)
							(end 0.1778 -0.2794)
						)
					)
					(width 0)
					(fill yes)
				)
			)
		)
	)
	(footprint ""
		(layer "F.Cu")
		(at 48.208946 -246.9134 90)
		(property "Reference" "Q41"
			(at 0 0 90)
			(layer "F.SilkS")
			(hide yes)
			(effects
				(font
					(size 1.27 1.27)
				)
			)
		)
		(property "Value" "PMBS3904-1-GP"
			(at 0 -9.0932 90)
			(unlocked yes)
			(layer "F.Fab")
			(hide yes)
			(effects
				(font
					(size 1.016 1.016)
					(thickness 0.1524)
				)
			)
		)
		(property "Device Type" "SOT-23-10H44"
			(at 0 -10.6172 90)
			(unlocked yes)
			(layer "F.Fab")
			(hide yes)
			(effects
				(font
					(size 1.016 1.016)
					(thickness 0.1524)
				)
			)
		)
		(duplicate_pad_numbers_are_jumpers no)
		(fp_line
			(start 1.651 -1.778)
			(end -1.651 -1.778)
			(stroke
				(width 0.1524)
				(type default)
			)
			(layer "F.SilkS")
		)
		(fp_line
			(start -1.651 -1.778)
			(end -1.651 1.778)
			(stroke
				(width 0.1524)
				(type default)
			)
			(layer "F.SilkS")
		)
		(fp_line
			(start 1.651 1.778)
			(end 1.651 -1.778)
			(stroke
				(width 0.1524)
				(type default)
			)
			(layer "F.SilkS")
		)
		(fp_line
			(start -1.651 1.778)
			(end 1.651 1.778)
			(stroke
				(width 0.1524)
				(type default)
			)
			(layer "F.SilkS")
		)
		(fp_line
			(start -0.9906 1.86309)
			(end -0.701294 2.15265)
			(stroke
				(width 0.0127)
				(type default)
			)
			(layer "F.SilkS")
		)
		(fp_line
			(start -0.994156 1.8669)
			(end -0.987044 1.8669)
			(stroke
				(width 0.0127)
				(type default)
			)
			(layer "F.SilkS")
		)
		(fp_line
			(start -1.003808 1.876552)
			(end -0.977646 1.876552)
			(stroke
				(width 0.0127)
				(type default)
			)
			(layer "F.SilkS")
		)
		(fp_line
			(start -0.635 1.8796)
			(end -1.7526 1.8796)
			(stroke
				(width 0.3302)
				(type default)
			)
			(layer "F.SilkS")
		)
		(fp_line
			(start -1.7526 1.8796)
			(end -1.7526 0.9906)
			(stroke
				(width 0.3302)
				(type default)
			)
			(layer "F.SilkS")
		)
		(fp_line
			(start -1.013206 1.88595)
			(end -0.967994 1.88595)
			(stroke
				(width 0.0127)
				(type default)
			)
			(layer "F.SilkS")
		)
		(fp_line
			(start -1.022858 1.895602)
			(end -0.958596 1.895602)
			(stroke
				(width 0.0127)
				(type default)
			)
			(layer "F.SilkS")
		)
		(fp_line
			(start -1.032256 1.905)
			(end -0.948944 1.905)
			(stroke
				(width 0.0127)
				(type default)
			)
			(layer "F.SilkS")
		)
		(fp_line
			(start -1.041908 1.914652)
			(end -0.939546 1.914652)
			(stroke
				(width 0.0127)
				(type default)
			)
			(layer "F.SilkS")
		)
		(fp_line
			(start -1.051306 1.92405)
			(end -0.929894 1.92405)
			(stroke
				(width 0.0127)
				(type default)
			)
			(layer "F.SilkS")
		)
		(fp_line
			(start -1.060958 1.933702)
			(end -0.920496 1.933702)
			(stroke
				(width 0.0127)
				(type default)
			)
			(layer "F.SilkS")
		)
		(fp_line
			(start -1.070356 1.9431)
			(end -0.910844 1.9431)
			(stroke
				(width 0.0127)
				(type default)
			)
			(layer "F.SilkS")
		)
		(fp_line
			(start -1.080008 1.952752)
			(end -0.901446 1.952752)
			(stroke
				(width 0.0127)
				(type default)
			)
			(layer "F.SilkS")
		)
		(fp_line
			(start -1.089406 1.96215)
			(end -0.891794 1.96215)
			(stroke
				(width 0.0127)
				(type default)
			)
			(layer "F.SilkS")
		)
		(fp_line
			(start -1.099058 1.971802)
			(end -0.882396 1.971802)
			(stroke
				(width 0.0127)
				(type default)
			)
			(layer "F.SilkS")
		)
		(fp_line
			(start -1.108456 1.9812)
			(end -0.872744 1.9812)
			(stroke
				(width 0.0127)
				(type default)
			)
			(layer "F.SilkS")
		)
		(fp_line
			(start -1.118108 1.990852)
			(end -0.863346 1.990852)
			(stroke
				(width 0.0127)
				(type default)
			)
			(layer "F.SilkS")
		)
		(fp_line
			(start -1.127506 2.00025)
			(end -0.853694 2.00025)
			(stroke
				(width 0.0127)
				(type default)
			)
			(layer "F.SilkS")
		)
		(fp_line
			(start -1.137158 2.009902)
			(end -0.844296 2.009902)
			(stroke
				(width 0.0127)
				(type default)
			)
			(layer "F.SilkS")
		)
		(fp_line
			(start -1.146556 2.0193)
			(end -0.834644 2.0193)
			(stroke
				(width 0.0127)
				(type default)
			)
			(layer "F.SilkS")
		)
		(fp_line
			(start -1.156208 2.028952)
			(end -0.825246 2.028952)
			(stroke
				(width 0.0127)
				(type default)
			)
			(layer "F.SilkS")
		)
		(fp_line
			(start -1.165606 2.03835)
			(end -0.815594 2.03835)
			(stroke
				(width 0.0127)
				(type default)
			)
			(layer "F.SilkS")
		)
		(fp_line
			(start -1.175258 2.048002)
			(end -0.806196 2.048002)
			(stroke
				(width 0.0127)
				(type default)
			)
			(layer "F.SilkS")
		)
		(fp_line
			(start -1.184656 2.0574)
			(end -0.796544 2.0574)
			(stroke
				(width 0.0127)
				(type default)
			)
			(layer "F.SilkS")
		)
		(fp_line
			(start -1.194308 2.067052)
			(end -0.787146 2.067052)
			(stroke
				(width 0.0127)
				(type default)
			)
			(layer "F.SilkS")
		)
		(fp_line
			(start -1.203706 2.07645)
			(end -0.777494 2.07645)
			(stroke
				(width 0.0127)
				(type default)
			)
			(layer "F.SilkS")
		)
		(fp_line
			(start -1.213358 2.086102)
			(end -0.768096 2.086102)
			(stroke
				(width 0.0127)
				(type default)
			)
			(layer "F.SilkS")
		)
		(fp_line
			(start -1.222756 2.0955)
			(end -0.758444 2.0955)
			(stroke
				(width 0.0127)
				(type default)
			)
			(layer "F.SilkS")
		)
		(fp_line
			(start -1.232408 2.105152)
			(end -0.749046 2.105152)
			(stroke
				(width 0.0127)
				(type default)
			)
			(layer "F.SilkS")
		)
		(fp_line
			(start -1.241806 2.11455)
			(end -0.739394 2.11455)
			(stroke
				(width 0.0127)
				(type default)
			)
			(layer "F.SilkS")
		)
		(fp_line
			(start -1.251458 2.124202)
			(end -0.729996 2.124202)
			(stroke
				(width 0.0127)
				(type default)
			)
			(layer "F.SilkS")
		)
		(fp_line
			(start -1.260856 2.1336)
			(end -0.720344 2.1336)
			(stroke
				(width 0.0127)
				(type default)
			)
			(layer "F.SilkS")
		)
		(fp_line
			(start -0.719074 2.145538)
			(end -1.265936 2.14122)
			(stroke
				(width 0.0127)
				(type default)
			)
			(layer "F.SilkS")
		)
		(fp_line
			(start -1.279398 2.152142)
			(end -0.9906 1.86309)
			(stroke
				(width 0.0127)
				(type default)
			)
			(layer "F.SilkS")
		)
		(fp_line
			(start -0.71628 2.15265)
			(end -1.26492 2.15265)
			(stroke
				(width 0.0127)
				(type default)
			)
			(layer "F.SilkS")
		)
		(fp_line
			(start -1.279144 2.15265)
			(end -0.701294 2.15265)
			(stroke
				(width 0.0127)
				(type default)
			)
			(layer "F.SilkS")
		)
		(fp_poly
			(pts
				(xy -1.285748 2.159) (xy -1.285748 1.8796) (xy -1.778 1.8796) (xy -1.778 -1.8796) (xy 1.778 -1.8796)
				(xy 1.778 1.8796) (xy -0.694944 1.8796) (xy -0.694944 2.159)
			)
			(stroke
				(width 0)
				(type default)
			)
			(fill no)
			(layer "F.CrtYd")
		)
		(fp_poly
			(pts
				(xy -1.285748 2.159) (xy -1.285748 1.8796) (xy -1.778 1.8796) (xy -1.778 -1.8796) (xy 1.778 -1.8796)
				(xy 1.778 1.8796) (xy -0.694944 1.8796) (xy -0.694944 2.159)
			)
			(stroke
				(width 0)
				(type default)
			)
			(fill no)
			(layer "F.Fab")
		)
		(pad "1" smd rect
			(at -0.98425 0.9525 90)
			(size 0.762 1.143)
			(layers "F.Cu" "F.Mask" "F.Paste")
			(net "FLT_HDD7_B")
		)
		(pad "2" smd rect
			(at 0.98425 0.9525 90)
			(size 0.762 1.143)
			(layers "F.Cu" "F.Mask" "F.Paste")
			(net "GND")
		)
		(pad "3" smd rect
			(at 0 -0.9525 90)
			(size 0.762 1.143)
			(layers "F.Cu" "F.Mask" "F.Paste")
			(net "DRIVE_ACT_7")
		)
	)
	(footprint ""
		(layer "F.Cu")
		(at 5.206746 -334.0227)
		(property "Reference" "TP5"
			(at 0 0 0)
			(layer "F.SilkS")
			(hide yes)
			(effects
				(font
					(size 1.27 1.27)
				)
			)
		)
		(property "Value" "TPAD32-GP"
			(at 0 -3.166364 0)
			(unlocked yes)
			(layer "F.Fab")
			(hide yes)
			(effects
				(font
					(size 1.016 1.016)
					(thickness 0.1524)
				)
			)
		)
		(property "Device Type" "TPAD32"
			(at 0 -4.690618 0)
			(unlocked yes)
			(layer "F.Fab")
			(hide yes)
			(effects
				(font
					(size 1.016 1.016)
					(thickness 0.1524)
				)
			)
		)
		(duplicate_pad_numbers_are_jumpers no)
		(fp_poly
			(pts
				(arc
					(start 0.4064 0)
					(mid -0.4064 0)
					(end 0.4064 0)
				)
			)
			(stroke
				(width 0)
				(type default)
			)
			(fill no)
			(layer "F.CrtYd")
		)
		(fp_poly
			(pts
				(arc
					(start 0.7112 0)
					(mid -0.7112 0)
					(end 0.7112 0)
				)
			)
			(stroke
				(width 0)
				(type default)
			)
			(fill no)
			(layer "F.Fab")
		)
		(pad "1" smd circle
			(at 0 0)
			(size 0.8128 0.8128)
			(layers "F.Cu" "F.Mask" "F.Paste")
			(net "SAS2X28_A_PRSNT15")
		)
	)
	(footprint ""
		(layer "F.Cu")
		(at 221.360746 -347.3577 -90)
		(property "Reference" "R118"
			(at 0 0 270)
			(layer "F.SilkS")
			(hide yes)
			(effects
				(font
					(size 1.27 1.27)
				)
			)
		)
		(property "Value" "0R2J-2-GP"
			(at 0.064008 -3.993896 270)
			(unlocked yes)
			(layer "F.Fab")
			(hide yes)
			(effects
				(font
					(size 1.016 1.016)
					(thickness 0.1524)
				)
			)
		)
		(property "Device Type" "R402H16"
			(at 0.064008 -5.517896 270)
			(unlocked yes)
			(layer "F.Fab")
			(hide yes)
			(effects
				(font
					(size 1.016 1.016)
					(thickness 0.1524)
				)
			)
		)
		(duplicate_pad_numbers_are_jumpers no)
		(fp_line
			(start -0.508 -0.9398)
			(end -0.508 0.9398)
			(stroke
				(width 0.1524)
				(type default)
			)
			(layer "F.SilkS")
		)
		(fp_line
			(start 0.508 -0.9398)
			(end -0.508 -0.9398)
			(stroke
				(width 0.1524)
				(type default)
			)
			(layer "F.SilkS")
		)
		(fp_rect
			(start -0.508 0.9398)
			(end 0.508 -0.9398)
			(stroke
				(width 0)
				(type default)
			)
			(fill no)
			(layer "F.CrtYd")
		)
		(fp_rect
			(start -0.508 0.9398)
			(end 0.508 -0.9398)
			(stroke
				(width 0)
				(type default)
			)
			(fill no)
			(layer "F.Fab")
		)
		(pad "1" smd custom
			(at 0 -0.4445 270)
			(size 0.1397 0.1397)
			(layers "F.Cu" "F.Mask" "F.Paste")
			(net "FLT_NET_HDD1")
			(options
				(clearance outline)
				(anchor circle)
			)
			(primitives
				(gr_poly
					(pts
						(arc
							(start -0.1778 -0.2794)
							(mid -0.249642 -0.249642)
							(end -0.2794 -0.1778)
						)
						(arc
							(start -0.2794 0.1778)
							(mid -0.249642 0.249642)
							(end -0.1778 0.2794)
						)
						(arc
							(start 0.1778 0.2794)
							(mid 0.249642 0.249642)
							(end 0.2794 0.1778)
						)
						(arc
							(start 0.2794 -0.1778)
							(mid 0.249642 -0.249642)
							(end 0.1778 -0.2794)
						)
					)
					(width 0)
					(fill yes)
				)
			)
		)
		(pad "2" smd custom
			(at 0 0.4445 270)
			(size 0.1397 0.1397)
			(layers "F.Cu" "F.Mask" "F.Paste")
			(net "FLT_HDD1_DRIVE")
			(options
				(clearance outline)
				(anchor circle)
			)
			(primitives
				(gr_poly
					(pts
						(arc
							(start -0.1778 -0.2794)
							(mid -0.249642 -0.249642)
							(end -0.2794 -0.1778)
						)
						(arc
							(start -0.2794 0.1778)
							(mid -0.249642 0.249642)
							(end -0.1778 0.2794)
						)
						(arc
							(start 0.1778 0.2794)
							(mid 0.249642 0.249642)
							(end 0.2794 0.1778)
						)
						(arc
							(start 0.2794 -0.1778)
							(mid 0.249642 -0.249642)
							(end 0.1778 -0.2794)
						)
					)
					(width 0)
					(fill yes)
				)
			)
		)
	)
	(footprint ""
		(layer "F.Cu")
		(at 40.385746 -116.487702)
		(property "Reference" "C318"
			(at 0 0 0)
			(layer "F.SilkS")
			(hide yes)
			(effects
				(font
					(size 1.27 1.27)
				)
			)
		)
		(property "Value" "SC10U25V6KX-1GP"
			(at -0.0762 -5.1308 0)
			(unlocked yes)
			(layer "F.Fab")
			(hide yes)
			(effects
				(font
					(size 1.016 1.016)
					(thickness 0.1524)
				)
			)
		)
		(property "Device Type" "C1206H71"
			(at -0.127 -6.6548 0)
			(unlocked yes)
			(layer "F.Fab")
			(hide yes)
			(effects
				(font
					(size 1.016 1.016)
					(thickness 0.1524)
				)
			)
		)
		(duplicate_pad_numbers_are_jumpers no)
		(fp_line
			(start -1.016 -2.2352)
			(end 1.016 -2.2352)
			(stroke
				(width 0.1524)
				(type default)
			)
			(layer "F.SilkS")
		)
		(fp_line
			(start -1.016 -0.8382)
			(end -1.016 -2.2352)
			(stroke
				(width 0.1524)
				(type default)
			)
			(layer "F.SilkS")
		)
		(fp_line
			(start -1.016 2.2352)
			(end -1.016 0.8382)
			(stroke
				(width 0.1524)
				(type default)
			)
			(layer "F.SilkS")
		)
		(fp_line
			(start 1.016 -2.2352)
			(end 1.016 -0.8382)
			(stroke
				(width 0.1524)
				(type default)
			)
			(layer "F.SilkS")
		)
		(fp_line
			(start 1.016 0.8382)
			(end 1.016 2.2352)
			(stroke
				(width 0.1524)
				(type default)
			)
			(layer "F.SilkS")
		)
		(fp_line
			(start 1.016 2.2352)
			(end -1.016 2.2352)
			(stroke
				(width 0.1524)
				(type default)
			)
			(layer "F.SilkS")
		)
		(fp_rect
			(start -1.0922 2.3114)
			(end 1.0922 -2.3114)
			(stroke
				(width 0)
				(type default)
			)
			(fill no)
			(layer "F.CrtYd")
		)
		(fp_poly
			(pts
				(xy 1.0922 -2.3114) (xy 1.0922 2.3114) (xy -1.0922 2.3114) (xy -1.0922 -2.3114)
			)
			(stroke
				(width 0)
				(type default)
			)
			(fill no)
			(layer "F.Fab")
		)
		(pad "1" smd rect
			(at 0 -1.397)
			(size 1.651 1.27)
			(layers "F.Cu" "F.Mask" "F.Paste")
			(net "P12V_HDD13")
		)
		(pad "2" smd rect
			(at 0 1.397)
			(size 1.651 1.27)
			(layers "F.Cu" "F.Mask" "F.Paste")
			(net "GND")
		)
	)
	(footprint ""
		(layer "F.Cu")
		(at 41.274746 -225.834702)
		(property "Reference" "C298"
			(at 0 0 0)
			(layer "F.SilkS")
			(hide yes)
			(effects
				(font
					(size 1.27 1.27)
				)
			)
		)
		(property "Value" "SC1U16V3KX-5GP"
			(at 0 -2.8194 0)
			(unlocked yes)
			(layer "F.Fab")
			(hide yes)
			(effects
				(font
					(size 1.016 1.016)
					(thickness 0.1524)
				)
			)
		)
		(property "Device Type" "C603H36"
			(at 0 -4.3434 0)
			(unlocked yes)
			(layer "F.Fab")
			(hide yes)
			(effects
				(font
					(size 1.016 1.016)
					(thickness 0.1524)
				)
			)
		)
		(duplicate_pad_numbers_are_jumpers no)
		(fp_line
			(start 0.508 0)
			(end -0.508 0)
			(stroke
				(width 0.2032)
				(type default)
			)
			(layer "F.SilkS")
		)
		(fp_rect
			(start -0.5842 1.3335)
			(end 0.5842 -1.3335)
			(stroke
				(width 0)
				(type default)
			)
			(fill no)
			(layer "F.CrtYd")
		)
		(fp_rect
			(start -0.5842 1.3335)
			(end 0.5842 -1.3335)
			(stroke
				(width 0)
				(type default)
			)
			(fill no)
			(layer "F.Fab")
		)
		(pad "1" smd custom
			(at 0 -0.762)
			(size 0.2159 0.2159)
			(layers "F.Cu" "F.Mask" "F.Paste")
			(net "P5V_HDD12")
			(options
				(clearance outline)
				(anchor circle)
			)
			(primitives
				(gr_poly
					(pts
						(arc
							(start -0.3302 -0.4318)
							(mid -0.402042 -0.402042)
							(end -0.4318 -0.3302)
						)
						(arc
							(start -0.4318 0.3302)
							(mid -0.402042 0.402042)
							(end -0.3302 0.4318)
						)
						(arc
							(start 0.3302 0.4318)
							(mid 0.402042 0.402042)
							(end 0.4318 0.3302)
						)
						(arc
							(start 0.4318 -0.3302)
							(mid 0.402042 -0.402042)
							(end 0.3302 -0.4318)
						)
					)
					(width 0)
					(fill yes)
				)
			)
		)
		(pad "2" smd custom
			(at 0 0.762)
			(size 0.2159 0.2159)
			(layers "F.Cu" "F.Mask" "F.Paste")
			(net "GND")
			(options
				(clearance outline)
				(anchor circle)
			)
			(primitives
				(gr_poly
					(pts
						(arc
							(start -0.3302 -0.4318)
							(mid -0.402042 -0.402042)
							(end -0.4318 -0.3302)
						)
						(arc
							(start -0.4318 0.3302)
							(mid -0.402042 0.402042)
							(end -0.3302 0.4318)
						)
						(arc
							(start 0.3302 0.4318)
							(mid 0.402042 0.402042)
							(end 0.4318 0.3302)
						)
						(arc
							(start 0.4318 -0.3302)
							(mid 0.402042 -0.402042)
							(end 0.3302 -0.4318)
						)
					)
					(width 0)
					(fill yes)
				)
			)
		)
	)
	(footprint ""
		(layer "F.Cu")
		(at 7.619746 -215.81364)
		(property "Reference" "TP17"
			(at 0 0 0)
			(layer "F.SilkS")
			(hide yes)
			(effects
				(font
					(size 1.27 1.27)
				)
			)
		)
		(property "Value" "TPAD32-GP"
			(at 0 -3.166364 0)
			(unlocked yes)
			(layer "F.Fab")
			(hide yes)
			(effects
				(font
					(size 1.016 1.016)
					(thickness 0.1524)
				)
			)
		)
		(property "Device Type" "TPAD32"
			(at 0 -4.690618 0)
			(unlocked yes)
			(layer "F.Fab")
			(hide yes)
			(effects
				(font
					(size 1.016 1.016)
					(thickness 0.1524)
				)
			)
		)
		(duplicate_pad_numbers_are_jumpers no)
		(fp_poly
			(pts
				(arc
					(start 0.4064 0)
					(mid -0.4064 0)
					(end 0.4064 0)
				)
			)
			(stroke
				(width 0)
				(type default)
			)
			(fill no)
			(layer "F.CrtYd")
		)
		(fp_poly
			(pts
				(arc
					(start 0.7112 0)
					(mid -0.7112 0)
					(end 0.7112 0)
				)
			)
			(stroke
				(width 0)
				(type default)
			)
			(fill no)
			(layer "F.Fab")
		)
		(pad "1" smd circle
			(at 0 0)
			(size 0.8128 0.8128)
			(layers "F.Cu" "F.Mask" "F.Paste")
			(net "SAS_EXP_B_PWR15")
		)
	)
	(footprint ""
		(layer "F.Cu")
		(at 67.507358 -488.871514 -90)
		(property "Reference" "Q11"
			(at 0 0 270)
			(layer "F.SilkS")
			(hide yes)
			(effects
				(font
					(size 1.27 1.27)
				)
			)
		)
		(property "Value" "AO4406AL-GP"
			(at -3.707384 -1.5367 270)
			(unlocked yes)
			(layer "F.Fab")
			(hide yes)
			(effects
				(font
					(size 1.016 1.016)
					(thickness 0.1524)
				)
			)
		)
		(property "Device Type" "SOIC8H69"
			(at -3.707384 -3.0607 270)
			(unlocked yes)
			(layer "F.Fab")
			(hide yes)
			(effects
				(font
					(size 1.016 1.016)
					(thickness 0.1524)
				)
			)
		)
		(duplicate_pad_numbers_are_jumpers no)
		(fp_line
			(start -2.6289 3.4417)
			(end -2.6289 1.4732)
			(stroke
				(width 0.381)
				(type default)
			)
			(layer "F.SilkS")
		)
		(fp_line
			(start -2.7432 1.4224)
			(end -2.6416 1.4224)
			(stroke
				(width 0.1524)
				(type default)
			)
			(layer "F.SilkS")
		)
		(fp_line
			(start -2.7432 1.4224)
			(end 2.1336 1.4224)
			(stroke
				(width 0.1524)
				(type default)
			)
			(layer "F.SilkS")
		)
		(fp_line
			(start 2.1336 1.4224)
			(end 2.1336 -1.4224)
			(stroke
				(width 0.1524)
				(type default)
			)
			(layer "F.SilkS")
		)
		(fp_line
			(start -2.1844 -0.0508)
			(end -2.7178 0.508)
			(stroke
				(width 0.1524)
				(type default)
			)
			(layer "F.SilkS")
		)
		(fp_line
			(start -2.7178 -0.508)
			(end -2.1844 -0.0508)
			(stroke
				(width 0.1524)
				(type default)
			)
			(layer "F.SilkS")
		)
		(fp_line
			(start -2.7432 -1.4224)
			(end -2.7432 1.4224)
			(stroke
				(width 0.1524)
				(type default)
			)
			(layer "F.SilkS")
		)
		(fp_line
			(start 2.1336 -1.4224)
			(end -2.7432 -1.4224)
			(stroke
				(width 0.1524)
				(type default)
			)
			(layer "F.SilkS")
		)
		(fp_poly
			(pts
				(xy -2.2098 -1.4224) (xy -2.2098 1.4224) (xy 2.2098 1.4224) (xy 2.2098 -1.4224)
			)
			(stroke
				(width 0)
				(type default)
			)
			(fill yes)
			(layer "F.SilkS")
		)
		(fp_rect
			(start -2.450084 2.999994)
			(end 2.450084 -2.999994)
			(stroke
				(width 0)
				(type default)
			)
			(fill no)
			(layer "F.CrtYd")
		)
		(fp_poly
			(pts
				(xy -2.8194 3.6322) (xy -2.8194 -3.6322) (xy 2.8194 -3.6322) (xy 2.8194 1.18364) (xy 2.450084 1.18364)
				(xy 2.450084 -2.999994) (xy -2.450084 -2.999994) (xy -2.450084 2.999994) (xy 2.450084 2.999994)
				(xy 2.450084 1.18618) (xy 2.8194 1.18618) (xy 2.8194 3.6322)
			)
			(stroke
				(width 0)
				(type default)
			)
			(fill no)
			(layer "F.CrtYd")
		)
		(fp_rect
			(start -2.8194 3.6322)
			(end 2.8194 -3.6322)
			(stroke
				(width 0)
				(type default)
			)
			(fill no)
			(layer "F.Fab")
		)
		(pad "1" smd rect
			(at -1.905 2.54 270)
			(size 0.635 1.651)
			(layers "F.Cu" "F.Mask" "F.Paste")
			(net "P5V_HDD5")
		)
		(pad "2" smd rect
			(at -0.635 2.54 270)
			(size 0.635 1.651)
			(layers "F.Cu" "F.Mask" "F.Paste")
			(net "P5V_HDD5")
		)
		(pad "3" smd rect
			(at 0.635 2.54 270)
			(size 0.635 1.651)
			(layers "F.Cu" "F.Mask" "F.Paste")
			(net "P5V_HDD5")
		)
		(pad "4" smd rect
			(at 1.905 2.54 270)
			(size 0.635 1.651)
			(layers "F.Cu" "F.Mask" "F.Paste")
			(net "SW_HDD5_P")
		)
		(pad "5" smd rect
			(at 1.905 -2.54 270)
			(size 0.635 1.651)
			(layers "F.Cu" "F.Mask" "F.Paste")
			(net "P5VB")
		)
		(pad "6" smd rect
			(at 0.635 -2.54 270)
			(size 0.635 1.651)
			(layers "F.Cu" "F.Mask" "F.Paste")
			(net "P5VB")
		)
		(pad "7" smd rect
			(at -0.635 -2.54 270)
			(size 0.635 1.651)
			(layers "F.Cu" "F.Mask" "F.Paste")
			(net "P5VB")
		)
		(pad "8" smd rect
			(at -1.905 -2.54 270)
			(size 0.635 1.651)
			(layers "F.Cu" "F.Mask" "F.Paste")
			(net "P5VB")
		)
	)
	(footprint ""
		(layer "F.Cu")
		(at 39.623746 -143.7767 90)
		(property "Reference" "R215"
			(at 0 0 90)
			(layer "F.SilkS")
			(hide yes)
			(effects
				(font
					(size 1.27 1.27)
				)
			)
		)
		(property "Value" "330R2F-GP"
			(at 0.064008 -3.993896 90)
			(unlocked yes)
			(layer "F.Fab")
			(hide yes)
			(effects
				(font
					(size 1.016 1.016)
					(thickness 0.1524)
				)
			)
		)
		(property "Device Type" "R402H16"
			(at 0.064008 -5.517896 90)
			(unlocked yes)
			(layer "F.Fab")
			(hide yes)
			(effects
				(font
					(size 1.016 1.016)
					(thickness 0.1524)
				)
			)
		)
		(duplicate_pad_numbers_are_jumpers no)
		(fp_line
			(start 0.508 -0.9398)
			(end -0.508 -0.9398)
			(stroke
				(width 0.1524)
				(type default)
			)
			(layer "F.SilkS")
		)
		(fp_line
			(start -0.508 -0.9398)
			(end -0.508 0.9398)
			(stroke
				(width 0.1524)
				(type default)
			)
			(layer "F.SilkS")
		)
		(fp_rect
			(start -0.508 0.9398)
			(end 0.508 -0.9398)
			(stroke
				(width 0)
				(type default)
			)
			(fill no)
			(layer "F.CrtYd")
		)
		(fp_rect
			(start -0.508 0.9398)
			(end 0.508 -0.9398)
			(stroke
				(width 0)
				(type default)
			)
			(fill no)
			(layer "F.Fab")
		)
		(pad "1" smd custom
			(at 0 -0.4445 90)
			(size 0.1397 0.1397)
			(layers "F.Cu" "F.Mask" "F.Paste")
			(net "P3V3_HDD8_LED")
			(options
				(clearance outline)
				(anchor circle)
			)
			(primitives
				(gr_poly
					(pts
						(arc
							(start -0.1778 -0.2794)
							(mid -0.249642 -0.249642)
							(end -0.2794 -0.1778)
						)
						(arc
							(start -0.2794 0.1778)
							(mid -0.249642 0.249642)
							(end -0.1778 0.2794)
						)
						(arc
							(start 0.1778 0.2794)
							(mid 0.249642 0.249642)
							(end 0.2794 0.1778)
						)
						(arc
							(start 0.2794 -0.1778)
							(mid 0.249642 -0.249642)
							(end 0.1778 -0.2794)
						)
					)
					(width 0)
					(fill yes)
				)
			)
		)
		(pad "2" smd custom
			(at 0 0.4445 90)
			(size 0.1397 0.1397)
			(layers "F.Cu" "F.Mask" "F.Paste")
			(net "FLT_HDD8")
			(options
				(clearance outline)
				(anchor circle)
			)
			(primitives
				(gr_poly
					(pts
						(arc
							(start -0.1778 -0.2794)
							(mid -0.249642 -0.249642)
							(end -0.2794 -0.1778)
						)
						(arc
							(start -0.2794 0.1778)
							(mid -0.249642 0.249642)
							(end -0.1778 0.2794)
						)
						(arc
							(start 0.1778 0.2794)
							(mid 0.249642 0.249642)
							(end 0.2794 0.1778)
						)
						(arc
							(start 0.2794 -0.1778)
							(mid 0.249642 -0.249642)
							(end 0.1778 -0.2794)
						)
					)
					(width 0)
					(fill yes)
				)
			)
		)
	)
	(footprint ""
		(layer "F.Cu")
		(at 227.499926 -247.160034 180)
		(property "Reference" "LED3"
			(at 0 0 180)
			(layer "F.SilkS")
			(hide yes)
			(effects
				(font
					(size 1.27 1.27)
				)
			)
		)
		(property "Value" "LED-RB-4-GP"
			(at 5.88899 1.80848 180)
			(unlocked yes)
			(layer "F.Fab")
			(hide yes)
			(effects
				(font
					(size 1.016 1.016)
					(thickness 0.1524)
				)
			)
		)
		(property "Device Type" "LED1613-4PH20"
			(at 5.88899 0.28448 180)
			(unlocked yes)
			(layer "F.Fab")
			(hide yes)
			(effects
				(font
					(size 1.016 1.016)
					(thickness 0.1524)
				)
			)
		)
		(duplicate_pad_numbers_are_jumpers no)
		(fp_line
			(start 1.4478 0.9652)
			(end -1.4478 0.9652)
			(stroke
				(width 0.1524)
				(type default)
			)
			(layer "F.SilkS")
		)
		(fp_line
			(start 1.4478 -0.9652)
			(end 1.4478 0.9652)
			(stroke
				(width 0.1524)
				(type default)
			)
			(layer "F.SilkS")
		)
		(fp_line
			(start -1.4478 0.9652)
			(end -1.4478 -0.9652)
			(stroke
				(width 0.1524)
				(type default)
			)
			(layer "F.SilkS")
		)
		(fp_line
			(start -1.4478 0.9652)
			(end -1.4478 -0.9652)
			(stroke
				(width 0.508)
				(type default)
			)
			(layer "F.SilkS")
		)
		(fp_line
			(start -1.4478 -0.9652)
			(end 1.4478 -0.9652)
			(stroke
				(width 0.1524)
				(type default)
			)
			(layer "F.SilkS")
		)
		(fp_rect
			(start -0.8001 0.6477)
			(end 0.8001 -0.6477)
			(stroke
				(width 0)
				(type default)
			)
			(fill no)
			(layer "F.CrtYd")
		)
		(fp_poly
			(pts
				(xy -1.7018 1.2192) (xy -1.7018 -0.06223) (xy -0.8001 -0.06223) (xy -0.8001 0.6477) (xy 0.8001 0.6477)
				(xy 0.8001 -0.6477) (xy -0.8001 -0.6477) (xy -0.8001 -0.0635) (xy -1.7018 -0.0635) (xy -1.7018 -1.2192)
				(xy 1.7018 -1.2192) (xy 1.7018 1.2192)
			)
			(stroke
				(width 0)
				(type default)
			)
			(fill no)
			(layer "F.CrtYd")
		)
		(fp_rect
			(start -1.7018 1.2192)
			(end 1.7018 -1.2192)
			(stroke
				(width 0)
				(type default)
			)
			(fill no)
			(layer "F.Fab")
		)
		(pad "1" smd rect
			(at -0.73025 0.4064 180)
			(size 0.9144 0.6096)
			(layers "F.Cu" "F.Mask" "F.Paste")
			(net "DRV_ACT_NET2")
		)
		(pad "2" smd rect
			(at -0.73025 -0.4064 180)
			(size 0.9144 0.6096)
			(layers "F.Cu" "F.Mask" "F.Paste")
			(net "FLT_NET_HDD2")
		)
		(pad "3" smd rect
			(at 0.73025 -0.4064 180)
			(size 0.9144 0.6096)
			(layers "F.Cu" "F.Mask" "F.Paste")
			(net "FLT_HDD2")
		)
		(pad "4" smd rect
			(at 0.73025 0.4064 180)
			(size 0.9144 0.6096)
			(layers "F.Cu" "F.Mask" "F.Paste")
			(net "DRV_ACT_2")
		)
	)
	(footprint ""
		(layer "F.Cu")
		(at 204.850746 -483.5017)
		(property "Reference" "TP25"
			(at 0 0 0)
			(layer "F.SilkS")
			(hide yes)
			(effects
				(font
					(size 1.27 1.27)
				)
			)
		)
		(property "Value" "TPAD32-GP"
			(at 0 -3.166364 0)
			(unlocked yes)
			(layer "F.Fab")
			(hide yes)
			(effects
				(font
					(size 1.016 1.016)
					(thickness 0.1524)
				)
			)
		)
		(property "Device Type" "TPAD32"
			(at 0 -4.690618 0)
			(unlocked yes)
			(layer "F.Fab")
			(hide yes)
			(effects
				(font
					(size 1.016 1.016)
					(thickness 0.1524)
				)
			)
		)
		(duplicate_pad_numbers_are_jumpers no)
		(fp_poly
			(pts
				(arc
					(start 0.4064 0)
					(mid -0.4064 0)
					(end 0.4064 0)
				)
			)
			(stroke
				(width 0)
				(type default)
			)
			(fill no)
			(layer "F.CrtYd")
		)
		(fp_poly
			(pts
				(arc
					(start 0.7112 0)
					(mid -0.7112 0)
					(end 0.7112 0)
				)
			)
			(stroke
				(width 0)
				(type default)
			)
			(fill no)
			(layer "F.Fab")
		)
		(pad "1" smd circle
			(at 0 0)
			(size 0.8128 0.8128)
			(layers "F.Cu" "F.Mask" "F.Paste")
			(net "ACT_HDD0")
		)
	)
	(footprint ""
		(layer "F.Cu")
		(at 77.342746 -19.586702 90)
		(property "Reference" "R302"
			(at 0 0 90)
			(layer "F.SilkS")
			(hide yes)
			(effects
				(font
					(size 1.27 1.27)
				)
			)
		)
		(property "Value" "2R2010J-1-GP"
			(at 0.254 -8.0772 90)
			(unlocked yes)
			(layer "F.Fab")
			(hide yes)
			(effects
				(font
					(size 1.016 1.016)
					(thickness 0.1524)
				)
			)
		)
		(property "Device Type" "R2010H28"
			(at 0.254 -9.6774 90)
			(unlocked yes)
			(layer "F.Fab")
			(hide yes)
			(effects
				(font
					(size 1.016 1.016)
					(thickness 0.1524)
				)
			)
		)
		(duplicate_pad_numbers_are_jumpers no)
		(fp_line
			(start 1.651 -3.302)
			(end -1.651 -3.302)
			(stroke
				(width 0.1524)
				(type default)
			)
			(layer "F.SilkS")
		)
		(fp_line
			(start -1.651 -3.302)
			(end -1.651 3.302)
			(stroke
				(width 0.1524)
				(type default)
			)
			(layer "F.SilkS")
		)
		(fp_line
			(start 1.651 3.302)
			(end 1.651 -3.302)
			(stroke
				(width 0.1524)
				(type default)
			)
			(layer "F.SilkS")
		)
		(fp_line
			(start -1.651 3.302)
			(end 1.651 3.302)
			(stroke
				(width 0.1524)
				(type default)
			)
			(layer "F.SilkS")
		)
		(fp_rect
			(start -1.7272 -3.3782)
			(end 1.7272 3.3782)
			(stroke
				(width 0)
				(type default)
			)
			(fill no)
			(layer "F.CrtYd")
		)
		(fp_poly
			(pts
				(xy 1.7272 3.3782) (xy 1.7272 -3.3782) (xy -1.7272 -3.3782) (xy -1.7272 3.3782)
			)
			(stroke
				(width 0)
				(type default)
			)
			(fill no)
			(layer "F.Fab")
		)
		(pad "1" smd rect
			(at 0 -2.3495 90)
			(size 2.794 1.143)
			(layers "F.Cu" "F.Mask" "F.Paste")
			(net "5V_PRE_14")
		)
		(pad "2" smd rect
			(at 0 2.3495 90)
			(size 2.794 1.143)
			(layers "F.Cu" "F.Mask" "F.Paste")
			(net "P5V_HDD14")
		)
	)
	(footprint ""
		(layer "F.Cu")
		(at 26.415746 -373.4562 180)
		(property "Reference" "R311"
			(at 0 0 180)
			(layer "F.SilkS")
			(hide yes)
			(effects
				(font
					(size 1.27 1.27)
				)
			)
		)
		(property "Value" "4K7R2J-2-GP"
			(at 0.064008 -3.993896 180)
			(unlocked yes)
			(layer "F.Fab")
			(hide yes)
			(effects
				(font
					(size 1.016 1.016)
					(thickness 0.1524)
				)
			)
		)
		(property "Device Type" "R402H16"
			(at 0.064008 -5.517896 180)
			(unlocked yes)
			(layer "F.Fab")
			(hide yes)
			(effects
				(font
					(size 1.016 1.016)
					(thickness 0.1524)
				)
			)
		)
		(duplicate_pad_numbers_are_jumpers no)
		(fp_line
			(start 0.508 -0.9398)
			(end -0.508 -0.9398)
			(stroke
				(width 0.1524)
				(type default)
			)
			(layer "F.SilkS")
		)
		(fp_line
			(start -0.508 -0.9398)
			(end -0.508 0.9398)
			(stroke
				(width 0.1524)
				(type default)
			)
			(layer "F.SilkS")
		)
		(fp_rect
			(start -0.508 0.9398)
			(end 0.508 -0.9398)
			(stroke
				(width 0)
				(type default)
			)
			(fill no)
			(layer "F.CrtYd")
		)
		(fp_rect
			(start -0.508 0.9398)
			(end 0.508 -0.9398)
			(stroke
				(width 0)
				(type default)
			)
			(fill no)
			(layer "F.Fab")
		)
		(pad "1" smd custom
			(at 0 -0.4445 180)
			(size 0.1397 0.1397)
			(layers "F.Cu" "F.Mask" "F.Paste")
			(net "P3V3")
			(options
				(clearance outline)
				(anchor circle)
			)
			(primitives
				(gr_poly
					(pts
						(arc
							(start -0.1778 -0.2794)
							(mid -0.249642 -0.249642)
							(end -0.2794 -0.1778)
						)
						(arc
							(start -0.2794 0.1778)
							(mid -0.249642 0.249642)
							(end -0.1778 0.2794)
						)
						(arc
							(start 0.1778 0.2794)
							(mid 0.249642 0.249642)
							(end 0.2794 0.1778)
						)
						(arc
							(start 0.2794 -0.1778)
							(mid 0.249642 -0.249642)
							(end 0.1778 -0.2794)
						)
					)
					(width 0)
					(fill yes)
				)
			)
		)
		(pad "2" smd custom
			(at 0 0.4445 180)
			(size 0.1397 0.1397)
			(layers "F.Cu" "F.Mask" "F.Paste")
			(net "I2C_B_TMP1_A2")
			(options
				(clearance outline)
				(anchor circle)
			)
			(primitives
				(gr_poly
					(pts
						(arc
							(start -0.1778 -0.2794)
							(mid -0.249642 -0.249642)
							(end -0.2794 -0.1778)
						)
						(arc
							(start -0.2794 0.1778)
							(mid -0.249642 0.249642)
							(end -0.1778 0.2794)
						)
						(arc
							(start 0.1778 0.2794)
							(mid 0.249642 0.249642)
							(end 0.2794 0.1778)
						)
						(arc
							(start 0.2794 -0.1778)
							(mid 0.249642 -0.249642)
							(end 0.1778 -0.2794)
						)
					)
					(width 0)
					(fill yes)
				)
			)
		)
	)
	(footprint ""
		(layer "F.Cu")
		(at 42.290746 -233.454702 180)
		(property "Reference" "R279"
			(at 0 0 180)
			(layer "F.SilkS")
			(hide yes)
			(effects
				(font
					(size 1.27 1.27)
				)
			)
		)
		(property "Value" "220R3F-1-GP"
			(at -0.0254 -2.5146 180)
			(unlocked yes)
			(layer "F.Fab")
			(hide yes)
			(effects
				(font
					(size 1.016 1.016)
					(thickness 0.1524)
				)
			)
		)
		(property "Device Type" "R603H22"
			(at -0.0254 -4.0386 180)
			(unlocked yes)
			(layer "F.Fab")
			(hide yes)
			(effects
				(font
					(size 1.016 1.016)
					(thickness 0.1524)
				)
			)
		)
		(duplicate_pad_numbers_are_jumpers no)
		(fp_line
			(start 0.2032 0)
			(end 0.4826 0)
			(stroke
				(width 0.2032)
				(type default)
			)
			(layer "F.SilkS")
		)
		(fp_line
			(start -0.4826 0)
			(end -0.2032 0)
			(stroke
				(width 0.2032)
				(type default)
			)
			(layer "F.SilkS")
		)
		(fp_rect
			(start -0.5842 1.3335)
			(end 0.5842 -1.3335)
			(stroke
				(width 0)
				(type default)
			)
			(fill no)
			(layer "F.CrtYd")
		)
		(fp_rect
			(start -0.5842 1.3335)
			(end 0.5842 -1.3335)
			(stroke
				(width 0)
				(type default)
			)
			(fill no)
			(layer "F.Fab")
		)
		(pad "1" smd custom
			(at 0 -0.762 180)
			(size 0.2159 0.2159)
			(layers "F.Cu" "F.Mask" "F.Paste")
			(net "HDD_PRSNT_NET12")
			(options
				(clearance outline)
				(anchor circle)
			)
			(primitives
				(gr_poly
					(pts
						(arc
							(start -0.3302 -0.4318)
							(mid -0.402042 -0.402042)
							(end -0.4318 -0.3302)
						)
						(arc
							(start -0.4318 0.3302)
							(mid -0.402042 0.402042)
							(end -0.3302 0.4318)
						)
						(arc
							(start 0.3302 0.4318)
							(mid 0.402042 0.402042)
							(end 0.4318 0.3302)
						)
						(arc
							(start 0.4318 -0.3302)
							(mid 0.402042 -0.402042)
							(end 0.3302 -0.4318)
						)
					)
					(width 0)
					(fill yes)
				)
			)
		)
		(pad "2" smd custom
			(at 0 0.762 180)
			(size 0.2159 0.2159)
			(layers "F.Cu" "F.Mask" "F.Paste")
			(net "HDD_PRSNT12")
			(options
				(clearance outline)
				(anchor circle)
			)
			(primitives
				(gr_poly
					(pts
						(arc
							(start -0.3302 -0.4318)
							(mid -0.402042 -0.402042)
							(end -0.4318 -0.3302)
						)
						(arc
							(start -0.4318 0.3302)
							(mid -0.402042 0.402042)
							(end -0.3302 0.4318)
						)
						(arc
							(start 0.3302 0.4318)
							(mid 0.402042 0.402042)
							(end 0.4318 0.3302)
						)
						(arc
							(start 0.4318 -0.3302)
							(mid 0.402042 -0.402042)
							(end 0.3302 -0.4318)
						)
					)
					(width 0)
					(fill yes)
				)
			)
		)
	)
	(footprint ""
		(layer "F.Cu")
		(at 81.914746 -12.474702 180)
		(property "Reference" "C333"
			(at 0 0 180)
			(layer "F.SilkS")
			(hide yes)
			(effects
				(font
					(size 1.27 1.27)
				)
			)
		)
		(property "Value" "SC10U25V6KX-1GP"
			(at -0.0762 -5.1308 180)
			(unlocked yes)
			(layer "F.Fab")
			(hide yes)
			(effects
				(font
					(size 1.016 1.016)
					(thickness 0.1524)
				)
			)
		)
		(property "Device Type" "C1206H71"
			(at -0.127 -6.6548 180)
			(unlocked yes)
			(layer "F.Fab")
			(hide yes)
			(effects
				(font
					(size 1.016 1.016)
					(thickness 0.1524)
				)
			)
		)
		(duplicate_pad_numbers_are_jumpers no)
		(fp_line
			(start 1.016 2.2352)
			(end -1.016 2.2352)
			(stroke
				(width 0.1524)
				(type default)
			)
			(layer "F.SilkS")
		)
		(fp_line
			(start 1.016 0.8382)
			(end 1.016 2.2352)
			(stroke
				(width 0.1524)
				(type default)
			)
			(layer "F.SilkS")
		)
		(fp_line
			(start 1.016 -2.2352)
			(end 1.016 -0.8382)
			(stroke
				(width 0.1524)
				(type default)
			)
			(layer "F.SilkS")
		)
		(fp_line
			(start -1.016 2.2352)
			(end -1.016 0.8382)
			(stroke
				(width 0.1524)
				(type default)
			)
			(layer "F.SilkS")
		)
		(fp_line
			(start -1.016 -0.8382)
			(end -1.016 -2.2352)
			(stroke
				(width 0.1524)
				(type default)
			)
			(layer "F.SilkS")
		)
		(fp_line
			(start -1.016 -2.2352)
			(end 1.016 -2.2352)
			(stroke
				(width 0.1524)
				(type default)
			)
			(layer "F.SilkS")
		)
		(fp_rect
			(start -1.0922 2.3114)
			(end 1.0922 -2.3114)
			(stroke
				(width 0)
				(type default)
			)
			(fill no)
			(layer "F.CrtYd")
		)
		(fp_poly
			(pts
				(xy 1.0922 -2.3114) (xy 1.0922 2.3114) (xy -1.0922 2.3114) (xy -1.0922 -2.3114)
			)
			(stroke
				(width 0)
				(type default)
			)
			(fill no)
			(layer "F.Fab")
		)
		(pad "1" smd rect
			(at 0 -1.397 180)
			(size 1.651 1.27)
			(layers "F.Cu" "F.Mask" "F.Paste")
			(net "P12V_HDD14")
		)
		(pad "2" smd rect
			(at 0 1.397 180)
			(size 1.651 1.27)
			(layers "F.Cu" "F.Mask" "F.Paste")
			(net "GND")
		)
	)
	(footprint ""
		(layer "F.Cu")
		(at 27.177746 -311.305702 180)
		(property "Reference" "R259"
			(at 0 0 180)
			(layer "F.SilkS")
			(hide yes)
			(effects
				(font
					(size 1.27 1.27)
				)
			)
		)
		(property "Value" "1KR2F-3-GP"
			(at 0.064008 -3.993896 180)
			(unlocked yes)
			(layer "F.Fab")
			(hide yes)
			(effects
				(font
					(size 1.016 1.016)
					(thickness 0.1524)
				)
			)
		)
		(property "Device Type" "R402H16"
			(at 0.064008 -5.517896 180)
			(unlocked yes)
			(layer "F.Fab")
			(hide yes)
			(effects
				(font
					(size 1.016 1.016)
					(thickness 0.1524)
				)
			)
		)
		(duplicate_pad_numbers_are_jumpers no)
		(fp_line
			(start 0.508 -0.9398)
			(end -0.508 -0.9398)
			(stroke
				(width 0.1524)
				(type default)
			)
			(layer "F.SilkS")
		)
		(fp_line
			(start -0.508 -0.9398)
			(end -0.508 0.9398)
			(stroke
				(width 0.1524)
				(type default)
			)
			(layer "F.SilkS")
		)
		(fp_rect
			(start -0.508 0.9398)
			(end 0.508 -0.9398)
			(stroke
				(width 0)
				(type default)
			)
			(fill no)
			(layer "F.CrtYd")
		)
		(fp_rect
			(start -0.508 0.9398)
			(end 0.508 -0.9398)
			(stroke
				(width 0)
				(type default)
			)
			(fill no)
			(layer "F.Fab")
		)
		(pad "1" smd custom
			(at 0 -0.4445 180)
			(size 0.1397 0.1397)
			(layers "F.Cu" "F.Mask" "F.Paste")
			(net "P3V3")
			(options
				(clearance outline)
				(anchor circle)
			)
			(primitives
				(gr_poly
					(pts
						(arc
							(start -0.1778 -0.2794)
							(mid -0.249642 -0.249642)
							(end -0.2794 -0.1778)
						)
						(arc
							(start -0.2794 0.1778)
							(mid -0.249642 0.249642)
							(end -0.1778 0.2794)
						)
						(arc
							(start 0.1778 0.2794)
							(mid 0.249642 0.249642)
							(end 0.2794 0.1778)
						)
						(arc
							(start 0.2794 -0.1778)
							(mid 0.249642 -0.249642)
							(end 0.1778 -0.2794)
						)
					)
					(width 0)
					(fill yes)
				)
			)
		)
		(pad "2" smd custom
			(at 0 0.4445 180)
			(size 0.1397 0.1397)
			(layers "F.Cu" "F.Mask" "F.Paste")
			(net "SW_PWR_HDD11")
			(options
				(clearance outline)
				(anchor circle)
			)
			(primitives
				(gr_poly
					(pts
						(arc
							(start -0.1778 -0.2794)
							(mid -0.249642 -0.249642)
							(end -0.2794 -0.1778)
						)
						(arc
							(start -0.2794 0.1778)
							(mid -0.249642 0.249642)
							(end -0.1778 0.2794)
						)
						(arc
							(start 0.1778 0.2794)
							(mid 0.249642 0.249642)
							(end 0.2794 0.1778)
						)
						(arc
							(start 0.2794 -0.1778)
							(mid 0.249642 -0.249642)
							(end 0.1778 -0.2794)
						)
					)
					(width 0)
					(fill yes)
				)
			)
		)
	)
	(footprint ""
		(layer "F.Cu")
		(at 199.897746 -286.6517)
		(property "Reference" "U7"
			(at 0 0 0)
			(layer "F.SilkS")
			(hide yes)
			(effects
				(font
					(size 1.27 1.27)
				)
			)
		)
		(property "Value" "74LVC1G08GW-1-GP"
			(at -2.3368 -8.6868 0)
			(unlocked yes)
			(layer "F.Fab")
			(hide yes)
			(effects
				(font
					(size 1.016 1.016)
					(thickness 0.1524)
				)
			)
		)
		(property "Device Type" "SC70-5H44"
			(at -2.3114 -10.414 0)
			(unlocked yes)
			(layer "F.Fab")
			(hide yes)
			(effects
				(font
					(size 1.016 1.016)
					(thickness 0.1524)
				)
			)
		)
		(duplicate_pad_numbers_are_jumpers no)
		(fp_line
			(start -1.27 -1.7018)
			(end 1.27 -1.7018)
			(stroke
				(width 0.1524)
				(type default)
			)
			(layer "F.SilkS")
		)
		(fp_line
			(start -1.27 1.7018)
			(end -1.27 -1.7018)
			(stroke
				(width 0.1524)
				(type default)
			)
			(layer "F.SilkS")
		)
		(fp_line
			(start 0.6604 -1.8034)
			(end 1.3843 -1.8034)
			(stroke
				(width 0.3302)
				(type default)
			)
			(layer "F.SilkS")
		)
		(fp_line
			(start 1.27 -1.7018)
			(end 1.27 1.7018)
			(stroke
				(width 0.1524)
				(type default)
			)
			(layer "F.SilkS")
		)
		(fp_line
			(start 1.27 1.7018)
			(end -1.27 1.7018)
			(stroke
				(width 0.1524)
				(type default)
			)
			(layer "F.SilkS")
		)
		(fp_line
			(start 1.3843 -1.8034)
			(end 1.3843 -1.1176)
			(stroke
				(width 0.3302)
				(type default)
			)
			(layer "F.SilkS")
		)
		(fp_rect
			(start -1.524 1.9558)
			(end 1.524 -1.9558)
			(stroke
				(width 0)
				(type default)
			)
			(fill no)
			(layer "F.CrtYd")
		)
		(fp_poly
			(pts
				(xy -1.524 -1.9558) (xy 1.524 -1.9558) (xy 1.524 1.9558) (xy -1.524 1.9558)
			)
			(stroke
				(width 0)
				(type default)
			)
			(fill no)
			(layer "F.Fab")
		)
		(pad "1" smd rect
			(at 0.65024 -0.8255)
			(size 0.4064 1.2192)
			(layers "F.Cu" "F.Mask" "F.Paste")
			(net "SAS2X28_B_HDD2_FLT")
		)
		(pad "2" smd rect
			(at 0 -0.8255)
			(size 0.4064 1.2192)
			(layers "F.Cu" "F.Mask" "F.Paste")
			(net "SAS2X28_A_HDD2_FLT")
		)
		(pad "3" smd rect
			(at -0.65024 -0.8255)
			(size 0.4064 1.2192)
			(layers "F.Cu" "F.Mask" "F.Paste")
			(net "GND")
		)
		(pad "4" smd rect
			(at -0.65024 0.8255)
			(size 0.4064 1.2192)
			(layers "F.Cu" "F.Mask" "F.Paste")
			(net "FLT_HDD2_DRIVE")
		)
		(pad "5" smd rect
			(at 0.65024 0.8255)
			(size 0.4064 1.2192)
			(layers "F.Cu" "F.Mask" "F.Paste")
			(net "P3V3")
		)
	)
	(footprint ""
		(layer "F.Cu")
		(at 194.691 -396.24 180)
		(property "Reference" "R564"
			(at 0 0 180)
			(layer "F.SilkS")
			(hide yes)
			(effects
				(font
					(size 1.27 1.27)
				)
			)
		)
		(property "Value" "300KR2F-GP"
			(at 0.064008 -3.993896 180)
			(unlocked yes)
			(layer "F.Fab")
			(hide yes)
			(effects
				(font
					(size 1.016 1.016)
					(thickness 0.1524)
				)
			)
		)
		(property "Device Type" "R402H16"
			(at 0.064008 -5.517896 180)
			(unlocked yes)
			(layer "F.Fab")
			(hide yes)
			(effects
				(font
					(size 1.016 1.016)
					(thickness 0.1524)
				)
			)
		)
		(duplicate_pad_numbers_are_jumpers no)
		(fp_line
			(start 0.508 -0.9398)
			(end -0.508 -0.9398)
			(stroke
				(width 0.1524)
				(type default)
			)
			(layer "F.SilkS")
		)
		(fp_line
			(start -0.508 -0.9398)
			(end -0.508 0.9398)
			(stroke
				(width 0.1524)
				(type default)
			)
			(layer "F.SilkS")
		)
		(fp_rect
			(start -0.508 0.9398)
			(end 0.508 -0.9398)
			(stroke
				(width 0)
				(type default)
			)
			(fill no)
			(layer "F.CrtYd")
		)
		(fp_rect
			(start -0.508 0.9398)
			(end 0.508 -0.9398)
			(stroke
				(width 0)
				(type default)
			)
			(fill no)
			(layer "F.Fab")
		)
		(pad "1" smd custom
			(at 0 -0.4445 180)
			(size 0.1397 0.1397)
			(layers "F.Cu" "F.Mask" "F.Paste")
			(net "SW_HDD1_N")
			(options
				(clearance outline)
				(anchor circle)
			)
			(primitives
				(gr_poly
					(pts
						(arc
							(start -0.1778 -0.2794)
							(mid -0.249642 -0.249642)
							(end -0.2794 -0.1778)
						)
						(arc
							(start -0.2794 0.1778)
							(mid -0.249642 0.249642)
							(end -0.1778 0.2794)
						)
						(arc
							(start 0.1778 0.2794)
							(mid 0.249642 0.249642)
							(end 0.2794 0.1778)
						)
						(arc
							(start 0.2794 -0.1778)
							(mid 0.249642 -0.249642)
							(end 0.1778 -0.2794)
						)
					)
					(width 0)
					(fill yes)
				)
			)
		)
		(pad "2" smd custom
			(at 0 0.4445 180)
			(size 0.1397 0.1397)
			(layers "F.Cu" "F.Mask" "F.Paste")
			(net "P12V")
			(options
				(clearance outline)
				(anchor circle)
			)
			(primitives
				(gr_poly
					(pts
						(arc
							(start -0.1778 -0.2794)
							(mid -0.249642 -0.249642)
							(end -0.2794 -0.1778)
						)
						(arc
							(start -0.2794 0.1778)
							(mid -0.249642 0.249642)
							(end -0.1778 0.2794)
						)
						(arc
							(start 0.1778 0.2794)
							(mid 0.249642 0.249642)
							(end 0.2794 0.1778)
						)
						(arc
							(start 0.2794 -0.1778)
							(mid 0.249642 -0.249642)
							(end 0.1778 -0.2794)
						)
					)
					(width 0)
					(fill yes)
				)
			)
		)
	)
	(footprint ""
		(layer "F.Cu")
		(at 11.8618 -162.4584 90)
		(property "Reference" "R360"
			(at 0 0 90)
			(layer "F.SilkS")
			(hide yes)
			(effects
				(font
					(size 1.27 1.27)
				)
			)
		)
		(property "Value" "0R2J-2-GP"
			(at 0.064008 -3.993896 90)
			(unlocked yes)
			(layer "F.Fab")
			(hide yes)
			(effects
				(font
					(size 1.016 1.016)
					(thickness 0.1524)
				)
			)
		)
		(property "Device Type" "R402H16"
			(at 0.064008 -5.517896 90)
			(unlocked yes)
			(layer "F.Fab")
			(hide yes)
			(effects
				(font
					(size 1.016 1.016)
					(thickness 0.1524)
				)
			)
		)
		(duplicate_pad_numbers_are_jumpers no)
		(fp_line
			(start 0.508 -0.9398)
			(end -0.508 -0.9398)
			(stroke
				(width 0.1524)
				(type default)
			)
			(layer "F.SilkS")
		)
		(fp_line
			(start -0.508 -0.9398)
			(end -0.508 0.9398)
			(stroke
				(width 0.1524)
				(type default)
			)
			(layer "F.SilkS")
		)
		(fp_rect
			(start -0.508 0.9398)
			(end 0.508 -0.9398)
			(stroke
				(width 0)
				(type default)
			)
			(fill no)
			(layer "F.CrtYd")
		)
		(fp_rect
			(start -0.508 0.9398)
			(end 0.508 -0.9398)
			(stroke
				(width 0)
				(type default)
			)
			(fill no)
			(layer "F.Fab")
		)
		(pad "1" smd custom
			(at 0 -0.4445 90)
			(size 0.1397 0.1397)
			(layers "F.Cu" "F.Mask" "F.Paste")
			(net "HB_EXP_A_INPUT")
			(options
				(clearance outline)
				(anchor circle)
			)
			(primitives
				(gr_poly
					(pts
						(arc
							(start -0.1778 -0.2794)
							(mid -0.249642 -0.249642)
							(end -0.2794 -0.1778)
						)
						(arc
							(start -0.2794 0.1778)
							(mid -0.249642 0.249642)
							(end -0.1778 0.2794)
						)
						(arc
							(start 0.1778 0.2794)
							(mid 0.249642 0.249642)
							(end 0.2794 0.1778)
						)
						(arc
							(start 0.2794 -0.1778)
							(mid 0.249642 -0.249642)
							(end 0.1778 -0.2794)
						)
					)
					(width 0)
					(fill yes)
				)
			)
		)
		(pad "2" smd custom
			(at 0 0.4445 90)
			(size 0.1397 0.1397)
			(layers "F.Cu" "F.Mask" "F.Paste")
			(net "SELF_1B&2B_HB")
			(options
				(clearance outline)
				(anchor circle)
			)
			(primitives
				(gr_poly
					(pts
						(arc
							(start -0.1778 -0.2794)
							(mid -0.249642 -0.249642)
							(end -0.2794 -0.1778)
						)
						(arc
							(start -0.2794 0.1778)
							(mid -0.249642 0.249642)
							(end -0.1778 0.2794)
						)
						(arc
							(start 0.1778 0.2794)
							(mid 0.249642 0.249642)
							(end 0.2794 0.1778)
						)
						(arc
							(start 0.2794 -0.1778)
							(mid 0.249642 -0.249642)
							(end 0.1778 -0.2794)
						)
					)
					(width 0)
					(fill yes)
				)
			)
		)
	)
	(footprint ""
		(layer "F.Cu")
		(at 206.31023 -383.850388 90)
		(property "Reference" "Q3"
			(at 0 0 90)
			(layer "F.SilkS")
			(hide yes)
			(effects
				(font
					(size 1.27 1.27)
				)
			)
		)
		(property "Value" "AO4406AL-GP"
			(at -3.707384 -1.5367 90)
			(unlocked yes)
			(layer "F.Fab")
			(hide yes)
			(effects
				(font
					(size 1.016 1.016)
					(thickness 0.1524)
				)
			)
		)
		(property "Device Type" "SOIC8H69"
			(at -3.707384 -3.0607 90)
			(unlocked yes)
			(layer "F.Fab")
			(hide yes)
			(effects
				(font
					(size 1.016 1.016)
					(thickness 0.1524)
				)
			)
		)
		(duplicate_pad_numbers_are_jumpers no)
		(fp_line
			(start 2.1336 -1.4224)
			(end -2.7432 -1.4224)
			(stroke
				(width 0.1524)
				(type default)
			)
			(layer "F.SilkS")
		)
		(fp_line
			(start -2.7432 -1.4224)
			(end -2.7432 1.4224)
			(stroke
				(width 0.1524)
				(type default)
			)
			(layer "F.SilkS")
		)
		(fp_line
			(start -2.7178 -0.508)
			(end -2.1844 -0.0508)
			(stroke
				(width 0.1524)
				(type default)
			)
			(layer "F.SilkS")
		)
		(fp_line
			(start -2.1844 -0.0508)
			(end -2.7178 0.508)
			(stroke
				(width 0.1524)
				(type default)
			)
			(layer "F.SilkS")
		)
		(fp_line
			(start 2.1336 1.4224)
			(end 2.1336 -1.4224)
			(stroke
				(width 0.1524)
				(type default)
			)
			(layer "F.SilkS")
		)
		(fp_line
			(start -2.7432 1.4224)
			(end 2.1336 1.4224)
			(stroke
				(width 0.1524)
				(type default)
			)
			(layer "F.SilkS")
		)
		(fp_line
			(start -2.7432 1.4224)
			(end -2.6416 1.4224)
			(stroke
				(width 0.1524)
				(type default)
			)
			(layer "F.SilkS")
		)
		(fp_line
			(start -2.6289 3.4417)
			(end -2.6289 1.4732)
			(stroke
				(width 0.381)
				(type default)
			)
			(layer "F.SilkS")
		)
		(fp_poly
			(pts
				(xy -2.2098 -1.4224) (xy -2.2098 1.4224) (xy 2.2098 1.4224) (xy 2.2098 -1.4224)
			)
			(stroke
				(width 0)
				(type default)
			)
			(fill yes)
			(layer "F.SilkS")
		)
		(fp_rect
			(start -2.450084 2.999994)
			(end 2.450084 -2.999994)
			(stroke
				(width 0)
				(type default)
			)
			(fill no)
			(layer "F.CrtYd")
		)
		(fp_poly
			(pts
				(xy -2.8194 3.6322) (xy -2.8194 -3.6322) (xy 2.8194 -3.6322) (xy 2.8194 1.18364) (xy 2.450084 1.18364)
				(xy 2.450084 -2.999994) (xy -2.450084 -2.999994) (xy -2.450084 2.999994) (xy 2.450084 2.999994)
				(xy 2.450084 1.18618) (xy 2.8194 1.18618) (xy 2.8194 3.6322)
			)
			(stroke
				(width 0)
				(type default)
			)
			(fill no)
			(layer "F.CrtYd")
		)
		(fp_rect
			(start -2.8194 3.6322)
			(end 2.8194 -3.6322)
			(stroke
				(width 0)
				(type default)
			)
			(fill no)
			(layer "F.Fab")
		)
		(pad "1" smd rect
			(at -1.905 2.54 90)
			(size 0.635 1.651)
			(layers "F.Cu" "F.Mask" "F.Paste")
			(net "P5V_HDD1")
		)
		(pad "2" smd rect
			(at -0.635 2.54 90)
			(size 0.635 1.651)
			(layers "F.Cu" "F.Mask" "F.Paste")
			(net "P5V_HDD1")
		)
		(pad "3" smd rect
			(at 0.635 2.54 90)
			(size 0.635 1.651)
			(layers "F.Cu" "F.Mask" "F.Paste")
			(net "P5V_HDD1")
		)
		(pad "4" smd rect
			(at 1.905 2.54 90)
			(size 0.635 1.651)
			(layers "F.Cu" "F.Mask" "F.Paste")
			(net "SW_HDD1_P")
		)
		(pad "5" smd rect
			(at 1.905 -2.54 90)
			(size 0.635 1.651)
			(layers "F.Cu" "F.Mask" "F.Paste")
			(net "P5VA")
		)
		(pad "6" smd rect
			(at 0.635 -2.54 90)
			(size 0.635 1.651)
			(layers "F.Cu" "F.Mask" "F.Paste")
			(net "P5VA")
		)
		(pad "7" smd rect
			(at -0.635 -2.54 90)
			(size 0.635 1.651)
			(layers "F.Cu" "F.Mask" "F.Paste")
			(net "P5VA")
		)
		(pad "8" smd rect
			(at -1.905 -2.54 90)
			(size 0.635 1.651)
			(layers "F.Cu" "F.Mask" "F.Paste")
			(net "P5VA")
		)
	)
	(footprint ""
		(layer "F.Cu")
		(at 217.9828 -86.6902 180)
		(property "Reference" "C177"
			(at 0 0 180)
			(layer "F.SilkS")
			(hide yes)
			(effects
				(font
					(size 1.27 1.27)
				)
			)
		)
		(property "Value" "SC10U25V6KX-1GP"
			(at -0.0762 -5.1308 180)
			(unlocked yes)
			(layer "F.Fab")
			(hide yes)
			(effects
				(font
					(size 1.016 1.016)
					(thickness 0.1524)
				)
			)
		)
		(property "Device Type" "C1206H71"
			(at -0.127 -6.6548 180)
			(unlocked yes)
			(layer "F.Fab")
			(hide yes)
			(effects
				(font
					(size 1.016 1.016)
					(thickness 0.1524)
				)
			)
		)
		(duplicate_pad_numbers_are_jumpers no)
		(fp_line
			(start 1.016 2.2352)
			(end -1.016 2.2352)
			(stroke
				(width 0.1524)
				(type default)
			)
			(layer "F.SilkS")
		)
		(fp_line
			(start 1.016 0.8382)
			(end 1.016 2.2352)
			(stroke
				(width 0.1524)
				(type default)
			)
			(layer "F.SilkS")
		)
		(fp_line
			(start 1.016 -2.2352)
			(end 1.016 -0.8382)
			(stroke
				(width 0.1524)
				(type default)
			)
			(layer "F.SilkS")
		)
		(fp_line
			(start -1.016 2.2352)
			(end -1.016 0.8382)
			(stroke
				(width 0.1524)
				(type default)
			)
			(layer "F.SilkS")
		)
		(fp_line
			(start -1.016 -0.8382)
			(end -1.016 -2.2352)
			(stroke
				(width 0.1524)
				(type default)
			)
			(layer "F.SilkS")
		)
		(fp_line
			(start -1.016 -2.2352)
			(end 1.016 -2.2352)
			(stroke
				(width 0.1524)
				(type default)
			)
			(layer "F.SilkS")
		)
		(fp_rect
			(start -1.0922 2.3114)
			(end 1.0922 -2.3114)
			(stroke
				(width 0)
				(type default)
			)
			(fill no)
			(layer "F.CrtYd")
		)
		(fp_poly
			(pts
				(xy 1.0922 -2.3114) (xy 1.0922 2.3114) (xy -1.0922 2.3114) (xy -1.0922 -2.3114)
			)
			(stroke
				(width 0)
				(type default)
			)
			(fill no)
			(layer "F.Fab")
		)
		(pad "1" smd rect
			(at 0 -1.397 180)
			(size 1.651 1.27)
			(layers "F.Cu" "F.Mask" "F.Paste")
			(net "P12V_HDD4")
		)
		(pad "2" smd rect
			(at 0 1.397 180)
			(size 1.651 1.27)
			(layers "F.Cu" "F.Mask" "F.Paste")
			(net "GND")
		)
	)
	(footprint ""
		(layer "F.Cu")
		(at 49.021746 -350.7867 90)
		(property "Reference" "R184"
			(at 0 0 90)
			(layer "F.SilkS")
			(hide yes)
			(effects
				(font
					(size 1.27 1.27)
				)
			)
		)
		(property "Value" "10KR2F-2-GP"
			(at 0.064008 -3.993896 90)
			(unlocked yes)
			(layer "F.Fab")
			(hide yes)
			(effects
				(font
					(size 1.016 1.016)
					(thickness 0.1524)
				)
			)
		)
		(property "Device Type" "R402H16"
			(at 0.064008 -5.517896 90)
			(unlocked yes)
			(layer "F.Fab")
			(hide yes)
			(effects
				(font
					(size 1.016 1.016)
					(thickness 0.1524)
				)
			)
		)
		(duplicate_pad_numbers_are_jumpers no)
		(fp_line
			(start 0.508 -0.9398)
			(end -0.508 -0.9398)
			(stroke
				(width 0.1524)
				(type default)
			)
			(layer "F.SilkS")
		)
		(fp_line
			(start -0.508 -0.9398)
			(end -0.508 0.9398)
			(stroke
				(width 0.1524)
				(type default)
			)
			(layer "F.SilkS")
		)
		(fp_rect
			(start -0.508 0.9398)
			(end 0.508 -0.9398)
			(stroke
				(width 0)
				(type default)
			)
			(fill no)
			(layer "F.CrtYd")
		)
		(fp_rect
			(start -0.508 0.9398)
			(end 0.508 -0.9398)
			(stroke
				(width 0)
				(type default)
			)
			(fill no)
			(layer "F.Fab")
		)
		(pad "1" smd custom
			(at 0 -0.4445 90)
			(size 0.1397 0.1397)
			(layers "F.Cu" "F.Mask" "F.Paste")
			(net "P5VB")
			(options
				(clearance outline)
				(anchor circle)
			)
			(primitives
				(gr_poly
					(pts
						(arc
							(start -0.1778 -0.2794)
							(mid -0.249642 -0.249642)
							(end -0.2794 -0.1778)
						)
						(arc
							(start -0.2794 0.1778)
							(mid -0.249642 0.249642)
							(end -0.1778 0.2794)
						)
						(arc
							(start 0.1778 0.2794)
							(mid 0.249642 0.249642)
							(end 0.2794 0.1778)
						)
						(arc
							(start 0.2794 -0.1778)
							(mid 0.249642 -0.249642)
							(end 0.1778 -0.2794)
						)
					)
					(width 0)
					(fill yes)
				)
			)
		)
		(pad "2" smd custom
			(at 0 0.4445 90)
			(size 0.1397 0.1397)
			(layers "F.Cu" "F.Mask" "F.Paste")
			(net "DRIVE_ACT_6")
			(options
				(clearance outline)
				(anchor circle)
			)
			(primitives
				(gr_poly
					(pts
						(arc
							(start -0.1778 -0.2794)
							(mid -0.249642 -0.249642)
							(end -0.2794 -0.1778)
						)
						(arc
							(start -0.2794 0.1778)
							(mid -0.249642 0.249642)
							(end -0.1778 0.2794)
						)
						(arc
							(start 0.1778 0.2794)
							(mid 0.249642 0.249642)
							(end 0.2794 0.1778)
						)
						(arc
							(start 0.2794 -0.1778)
							(mid 0.249642 -0.249642)
							(end 0.1778 -0.2794)
						)
					)
					(width 0)
					(fill yes)
				)
			)
		)
	)
	(footprint ""
		(layer "F.Cu")
		(at 75.564746 -22.761702 180)
		(property "Reference" "R303"
			(at 0 0 180)
			(layer "F.SilkS")
			(hide yes)
			(effects
				(font
					(size 1.27 1.27)
				)
			)
		)
		(property "Value" "220R3F-1-GP"
			(at -0.0254 -2.5146 180)
			(unlocked yes)
			(layer "F.Fab")
			(hide yes)
			(effects
				(font
					(size 1.016 1.016)
					(thickness 0.1524)
				)
			)
		)
		(property "Device Type" "R603H22"
			(at -0.0254 -4.0386 180)
			(unlocked yes)
			(layer "F.Fab")
			(hide yes)
			(effects
				(font
					(size 1.016 1.016)
					(thickness 0.1524)
				)
			)
		)
		(duplicate_pad_numbers_are_jumpers no)
		(fp_line
			(start 0.2032 0)
			(end 0.4826 0)
			(stroke
				(width 0.2032)
				(type default)
			)
			(layer "F.SilkS")
		)
		(fp_line
			(start -0.4826 0)
			(end -0.2032 0)
			(stroke
				(width 0.2032)
				(type default)
			)
			(layer "F.SilkS")
		)
		(fp_rect
			(start -0.5842 1.3335)
			(end 0.5842 -1.3335)
			(stroke
				(width 0)
				(type default)
			)
			(fill no)
			(layer "F.CrtYd")
		)
		(fp_rect
			(start -0.5842 1.3335)
			(end 0.5842 -1.3335)
			(stroke
				(width 0)
				(type default)
			)
			(fill no)
			(layer "F.Fab")
		)
		(pad "1" smd custom
			(at 0 -0.762 180)
			(size 0.2159 0.2159)
			(layers "F.Cu" "F.Mask" "F.Paste")
			(net "HDD_PRSNT_NET14")
			(options
				(clearance outline)
				(anchor circle)
			)
			(primitives
				(gr_poly
					(pts
						(arc
							(start -0.3302 -0.4318)
							(mid -0.402042 -0.402042)
							(end -0.4318 -0.3302)
						)
						(arc
							(start -0.4318 0.3302)
							(mid -0.402042 0.402042)
							(end -0.3302 0.4318)
						)
						(arc
							(start 0.3302 0.4318)
							(mid 0.402042 0.402042)
							(end 0.4318 0.3302)
						)
						(arc
							(start 0.4318 -0.3302)
							(mid 0.402042 -0.402042)
							(end 0.3302 -0.4318)
						)
					)
					(width 0)
					(fill yes)
				)
			)
		)
		(pad "2" smd custom
			(at 0 0.762 180)
			(size 0.2159 0.2159)
			(layers "F.Cu" "F.Mask" "F.Paste")
			(net "HDD_PRSNT14")
			(options
				(clearance outline)
				(anchor circle)
			)
			(primitives
				(gr_poly
					(pts
						(arc
							(start -0.3302 -0.4318)
							(mid -0.402042 -0.402042)
							(end -0.4318 -0.3302)
						)
						(arc
							(start -0.4318 0.3302)
							(mid -0.402042 0.402042)
							(end -0.3302 0.4318)
						)
						(arc
							(start 0.3302 0.4318)
							(mid 0.402042 0.402042)
							(end 0.4318 0.3302)
						)
						(arc
							(start 0.4318 -0.3302)
							(mid 0.402042 -0.402042)
							(end 0.3302 -0.4318)
						)
					)
					(width 0)
					(fill yes)
				)
			)
		)
	)
	(footprint ""
		(layer "F.Cu")
		(at 62.865 -274.3835)
		(property "Reference" "R383"
			(at 0 0 0)
			(layer "F.SilkS")
			(hide yes)
			(effects
				(font
					(size 1.27 1.27)
				)
			)
		)
		(property "Value" "10KR2F-2-GP"
			(at 0.064008 -3.993896 0)
			(unlocked yes)
			(layer "F.Fab")
			(hide yes)
			(effects
				(font
					(size 1.016 1.016)
					(thickness 0.1524)
				)
			)
		)
		(property "Device Type" "R402H16"
			(at 0.064008 -5.517896 0)
			(unlocked yes)
			(layer "F.Fab")
			(hide yes)
			(effects
				(font
					(size 1.016 1.016)
					(thickness 0.1524)
				)
			)
		)
		(duplicate_pad_numbers_are_jumpers no)
		(fp_line
			(start -0.508 -0.9398)
			(end -0.508 0.9398)
			(stroke
				(width 0.1524)
				(type default)
			)
			(layer "F.SilkS")
		)
		(fp_line
			(start 0.508 -0.9398)
			(end -0.508 -0.9398)
			(stroke
				(width 0.1524)
				(type default)
			)
			(layer "F.SilkS")
		)
		(fp_rect
			(start -0.508 0.9398)
			(end 0.508 -0.9398)
			(stroke
				(width 0)
				(type default)
			)
			(fill no)
			(layer "F.CrtYd")
		)
		(fp_rect
			(start -0.508 0.9398)
			(end 0.508 -0.9398)
			(stroke
				(width 0)
				(type default)
			)
			(fill no)
			(layer "F.Fab")
		)
		(pad "1" smd custom
			(at 0 -0.4445)
			(size 0.1397 0.1397)
			(layers "F.Cu" "F.Mask" "F.Paste")
			(net "P12V")
			(options
				(clearance outline)
				(anchor circle)
			)
			(primitives
				(gr_poly
					(pts
						(arc
							(start -0.1778 -0.2794)
							(mid -0.249642 -0.249642)
							(end -0.2794 -0.1778)
						)
						(arc
							(start -0.2794 0.1778)
							(mid -0.249642 0.249642)
							(end -0.1778 0.2794)
						)
						(arc
							(start 0.1778 0.2794)
							(mid 0.249642 0.249642)
							(end 0.2794 0.1778)
						)
						(arc
							(start 0.2794 -0.1778)
							(mid 0.249642 -0.249642)
							(end 0.1778 -0.2794)
						)
					)
					(width 0)
					(fill yes)
				)
			)
		)
		(pad "2" smd custom
			(at 0 0.4445)
			(size 0.1397 0.1397)
			(layers "F.Cu" "F.Mask" "F.Paste")
			(net "HDD7_LED_G")
			(options
				(clearance outline)
				(anchor circle)
			)
			(primitives
				(gr_poly
					(pts
						(arc
							(start -0.1778 -0.2794)
							(mid -0.249642 -0.249642)
							(end -0.2794 -0.1778)
						)
						(arc
							(start -0.2794 0.1778)
							(mid -0.249642 0.249642)
							(end -0.1778 0.2794)
						)
						(arc
							(start 0.1778 0.2794)
							(mid 0.249642 0.249642)
							(end 0.2794 0.1778)
						)
						(arc
							(start 0.2794 -0.1778)
							(mid 0.249642 -0.249642)
							(end 0.1778 -0.2794)
						)
					)
					(width 0)
					(fill yes)
				)
			)
		)
	)
	(footprint ""
		(layer "F.Cu")
		(at 21.742146 -255.1303 90)
		(property "Reference" "R372"
			(at 0 0 90)
			(layer "F.SilkS")
			(hide yes)
			(effects
				(font
					(size 1.27 1.27)
				)
			)
		)
		(property "Value" "4K7R2J-2-GP"
			(at 0.064008 -3.993896 90)
			(unlocked yes)
			(layer "F.Fab")
			(hide yes)
			(effects
				(font
					(size 1.016 1.016)
					(thickness 0.1524)
				)
			)
		)
		(property "Device Type" "R402H16"
			(at 0.064008 -5.517896 90)
			(unlocked yes)
			(layer "F.Fab")
			(hide yes)
			(effects
				(font
					(size 1.016 1.016)
					(thickness 0.1524)
				)
			)
		)
		(duplicate_pad_numbers_are_jumpers no)
		(fp_line
			(start 0.508 -0.9398)
			(end -0.508 -0.9398)
			(stroke
				(width 0.1524)
				(type default)
			)
			(layer "F.SilkS")
		)
		(fp_line
			(start -0.508 -0.9398)
			(end -0.508 0.9398)
			(stroke
				(width 0.1524)
				(type default)
			)
			(layer "F.SilkS")
		)
		(fp_rect
			(start -0.508 0.9398)
			(end 0.508 -0.9398)
			(stroke
				(width 0)
				(type default)
			)
			(fill no)
			(layer "F.CrtYd")
		)
		(fp_rect
			(start -0.508 0.9398)
			(end 0.508 -0.9398)
			(stroke
				(width 0)
				(type default)
			)
			(fill no)
			(layer "F.Fab")
		)
		(pad "1" smd custom
			(at 0 -0.4445 90)
			(size 0.1397 0.1397)
			(layers "F.Cu" "F.Mask" "F.Paste")
			(net "P3V3")
			(options
				(clearance outline)
				(anchor circle)
			)
			(primitives
				(gr_poly
					(pts
						(arc
							(start -0.1778 -0.2794)
							(mid -0.249642 -0.249642)
							(end -0.2794 -0.1778)
						)
						(arc
							(start -0.2794 0.1778)
							(mid -0.249642 0.249642)
							(end -0.1778 0.2794)
						)
						(arc
							(start 0.1778 0.2794)
							(mid 0.249642 0.249642)
							(end 0.2794 0.1778)
						)
						(arc
							(start 0.2794 -0.1778)
							(mid 0.249642 -0.249642)
							(end 0.1778 -0.2794)
						)
					)
					(width 0)
					(fill yes)
				)
			)
		)
		(pad "2" smd custom
			(at 0 0.4445 90)
			(size 0.1397 0.1397)
			(layers "F.Cu" "F.Mask" "F.Paste")
			(net "I2C_D_SDA")
			(options
				(clearance outline)
				(anchor circle)
			)
			(primitives
				(gr_poly
					(pts
						(arc
							(start -0.1778 -0.2794)
							(mid -0.249642 -0.249642)
							(end -0.2794 -0.1778)
						)
						(arc
							(start -0.2794 0.1778)
							(mid -0.249642 0.249642)
							(end -0.1778 0.2794)
						)
						(arc
							(start 0.1778 0.2794)
							(mid 0.249642 0.249642)
							(end 0.2794 0.1778)
						)
						(arc
							(start 0.2794 -0.1778)
							(mid 0.249642 -0.249642)
							(end 0.1778 -0.2794)
						)
					)
					(width 0)
					(fill yes)
				)
			)
		)
	)
	(footprint ""
		(layer "F.Cu")
		(at 60.629546 -191.7827 180)
		(property "Reference" "C240"
			(at 0 0 180)
			(layer "F.SilkS")
			(hide yes)
			(effects
				(font
					(size 1.27 1.27)
				)
			)
		)
		(property "Value" "SC10U25V6KX-1GP"
			(at -0.0762 -5.1308 180)
			(unlocked yes)
			(layer "F.Fab")
			(hide yes)
			(effects
				(font
					(size 1.016 1.016)
					(thickness 0.1524)
				)
			)
		)
		(property "Device Type" "C1206H71"
			(at -0.127 -6.6548 180)
			(unlocked yes)
			(layer "F.Fab")
			(hide yes)
			(effects
				(font
					(size 1.016 1.016)
					(thickness 0.1524)
				)
			)
		)
		(duplicate_pad_numbers_are_jumpers no)
		(fp_line
			(start 1.016 2.2352)
			(end -1.016 2.2352)
			(stroke
				(width 0.1524)
				(type default)
			)
			(layer "F.SilkS")
		)
		(fp_line
			(start 1.016 0.8382)
			(end 1.016 2.2352)
			(stroke
				(width 0.1524)
				(type default)
			)
			(layer "F.SilkS")
		)
		(fp_line
			(start 1.016 -2.2352)
			(end 1.016 -0.8382)
			(stroke
				(width 0.1524)
				(type default)
			)
			(layer "F.SilkS")
		)
		(fp_line
			(start -1.016 2.2352)
			(end -1.016 0.8382)
			(stroke
				(width 0.1524)
				(type default)
			)
			(layer "F.SilkS")
		)
		(fp_line
			(start -1.016 -0.8382)
			(end -1.016 -2.2352)
			(stroke
				(width 0.1524)
				(type default)
			)
			(layer "F.SilkS")
		)
		(fp_line
			(start -1.016 -2.2352)
			(end 1.016 -2.2352)
			(stroke
				(width 0.1524)
				(type default)
			)
			(layer "F.SilkS")
		)
		(fp_rect
			(start -1.0922 2.3114)
			(end 1.0922 -2.3114)
			(stroke
				(width 0)
				(type default)
			)
			(fill no)
			(layer "F.CrtYd")
		)
		(fp_poly
			(pts
				(xy 1.0922 -2.3114) (xy 1.0922 2.3114) (xy -1.0922 2.3114) (xy -1.0922 -2.3114)
			)
			(stroke
				(width 0)
				(type default)
			)
			(fill no)
			(layer "F.Fab")
		)
		(pad "1" smd rect
			(at 0 -1.397 180)
			(size 1.651 1.27)
			(layers "F.Cu" "F.Mask" "F.Paste")
			(net "P12V_HDD8")
		)
		(pad "2" smd rect
			(at 0 1.397 180)
			(size 1.651 1.27)
			(layers "F.Cu" "F.Mask" "F.Paste")
			(net "GND")
		)
	)
	(footprint ""
		(layer "F.Cu")
		(at 164.985446 -461.933036 90)
		(property "Reference" "R364"
			(at 0 0 90)
			(layer "F.SilkS")
			(hide yes)
			(effects
				(font
					(size 1.27 1.27)
				)
			)
		)
		(property "Value" "4K7R2J-2-GP"
			(at 0.064008 -3.993896 90)
			(unlocked yes)
			(layer "F.Fab")
			(hide yes)
			(effects
				(font
					(size 1.016 1.016)
					(thickness 0.1524)
				)
			)
		)
		(property "Device Type" "R402H16"
			(at 0.064008 -5.517896 90)
			(unlocked yes)
			(layer "F.Fab")
			(hide yes)
			(effects
				(font
					(size 1.016 1.016)
					(thickness 0.1524)
				)
			)
		)
		(duplicate_pad_numbers_are_jumpers no)
		(fp_line
			(start 0.508 -0.9398)
			(end -0.508 -0.9398)
			(stroke
				(width 0.1524)
				(type default)
			)
			(layer "F.SilkS")
		)
		(fp_line
			(start -0.508 -0.9398)
			(end -0.508 0.9398)
			(stroke
				(width 0.1524)
				(type default)
			)
			(layer "F.SilkS")
		)
		(fp_rect
			(start -0.508 0.9398)
			(end 0.508 -0.9398)
			(stroke
				(width 0)
				(type default)
			)
			(fill no)
			(layer "F.CrtYd")
		)
		(fp_rect
			(start -0.508 0.9398)
			(end 0.508 -0.9398)
			(stroke
				(width 0)
				(type default)
			)
			(fill no)
			(layer "F.Fab")
		)
		(pad "1" smd custom
			(at 0 -0.4445 90)
			(size 0.1397 0.1397)
			(layers "F.Cu" "F.Mask" "F.Paste")
			(net "P3V3")
			(options
				(clearance outline)
				(anchor circle)
			)
			(primitives
				(gr_poly
					(pts
						(arc
							(start -0.1778 -0.2794)
							(mid -0.249642 -0.249642)
							(end -0.2794 -0.1778)
						)
						(arc
							(start -0.2794 0.1778)
							(mid -0.249642 0.249642)
							(end -0.1778 0.2794)
						)
						(arc
							(start 0.1778 0.2794)
							(mid 0.249642 0.249642)
							(end 0.2794 0.1778)
						)
						(arc
							(start 0.2794 -0.1778)
							(mid 0.249642 -0.249642)
							(end 0.1778 -0.2794)
						)
					)
					(width 0)
					(fill yes)
				)
			)
		)
		(pad "2" smd custom
			(at 0 0.4445 90)
			(size 0.1397 0.1397)
			(layers "F.Cu" "F.Mask" "F.Paste")
			(net "VOL_SEN_ADDR")
			(options
				(clearance outline)
				(anchor circle)
			)
			(primitives
				(gr_poly
					(pts
						(arc
							(start -0.1778 -0.2794)
							(mid -0.249642 -0.249642)
							(end -0.2794 -0.1778)
						)
						(arc
							(start -0.2794 0.1778)
							(mid -0.249642 0.249642)
							(end -0.1778 0.2794)
						)
						(arc
							(start 0.1778 0.2794)
							(mid 0.249642 0.249642)
							(end 0.2794 0.1778)
						)
						(arc
							(start 0.2794 -0.1778)
							(mid 0.249642 -0.249642)
							(end 0.1778 -0.2794)
						)
					)
					(width 0)
					(fill yes)
				)
			)
		)
	)
	(footprint ""
		(layer "F.Cu")
		(at 210.946746 -183.1467)
		(property "Reference" "C159"
			(at 0 0 0)
			(layer "F.SilkS")
			(hide yes)
			(effects
				(font
					(size 1.27 1.27)
				)
			)
		)
		(property "Value" "SC10U25V6KX-1GP"
			(at -0.0762 -5.1308 0)
			(unlocked yes)
			(layer "F.Fab")
			(hide yes)
			(effects
				(font
					(size 1.016 1.016)
					(thickness 0.1524)
				)
			)
		)
		(property "Device Type" "C1206H71"
			(at -0.127 -6.6548 0)
			(unlocked yes)
			(layer "F.Fab")
			(hide yes)
			(effects
				(font
					(size 1.016 1.016)
					(thickness 0.1524)
				)
			)
		)
		(duplicate_pad_numbers_are_jumpers no)
		(fp_line
			(start -1.016 -2.2352)
			(end 1.016 -2.2352)
			(stroke
				(width 0.1524)
				(type default)
			)
			(layer "F.SilkS")
		)
		(fp_line
			(start -1.016 -0.8382)
			(end -1.016 -2.2352)
			(stroke
				(width 0.1524)
				(type default)
			)
			(layer "F.SilkS")
		)
		(fp_line
			(start -1.016 2.2352)
			(end -1.016 0.8382)
			(stroke
				(width 0.1524)
				(type default)
			)
			(layer "F.SilkS")
		)
		(fp_line
			(start 1.016 -2.2352)
			(end 1.016 -0.8382)
			(stroke
				(width 0.1524)
				(type default)
			)
			(layer "F.SilkS")
		)
		(fp_line
			(start 1.016 0.8382)
			(end 1.016 2.2352)
			(stroke
				(width 0.1524)
				(type default)
			)
			(layer "F.SilkS")
		)
		(fp_line
			(start 1.016 2.2352)
			(end -1.016 2.2352)
			(stroke
				(width 0.1524)
				(type default)
			)
			(layer "F.SilkS")
		)
		(fp_rect
			(start -1.0922 2.3114)
			(end 1.0922 -2.3114)
			(stroke
				(width 0)
				(type default)
			)
			(fill no)
			(layer "F.CrtYd")
		)
		(fp_poly
			(pts
				(xy 1.0922 -2.3114) (xy 1.0922 2.3114) (xy -1.0922 2.3114) (xy -1.0922 -2.3114)
			)
			(stroke
				(width 0)
				(type default)
			)
			(fill no)
			(layer "F.Fab")
		)
		(pad "1" smd rect
			(at 0 -1.397)
			(size 1.651 1.27)
			(layers "F.Cu" "F.Mask" "F.Paste")
			(net "P12V_HDD3")
		)
		(pad "2" smd rect
			(at 0 1.397)
			(size 1.651 1.27)
			(layers "F.Cu" "F.Mask" "F.Paste")
			(net "GND")
		)
	)
	(footprint ""
		(layer "F.Cu")
		(at 213.5632 -86.6902 180)
		(property "Reference" "C175"
			(at 0 0 180)
			(layer "F.SilkS")
			(hide yes)
			(effects
				(font
					(size 1.27 1.27)
				)
			)
		)
		(property "Value" "SC10U25V6KX-1GP"
			(at -0.0762 -5.1308 180)
			(unlocked yes)
			(layer "F.Fab")
			(hide yes)
			(effects
				(font
					(size 1.016 1.016)
					(thickness 0.1524)
				)
			)
		)
		(property "Device Type" "C1206H71"
			(at -0.127 -6.6548 180)
			(unlocked yes)
			(layer "F.Fab")
			(hide yes)
			(effects
				(font
					(size 1.016 1.016)
					(thickness 0.1524)
				)
			)
		)
		(duplicate_pad_numbers_are_jumpers no)
		(fp_line
			(start 1.016 2.2352)
			(end -1.016 2.2352)
			(stroke
				(width 0.1524)
				(type default)
			)
			(layer "F.SilkS")
		)
		(fp_line
			(start 1.016 0.8382)
			(end 1.016 2.2352)
			(stroke
				(width 0.1524)
				(type default)
			)
			(layer "F.SilkS")
		)
		(fp_line
			(start 1.016 -2.2352)
			(end 1.016 -0.8382)
			(stroke
				(width 0.1524)
				(type default)
			)
			(layer "F.SilkS")
		)
		(fp_line
			(start -1.016 2.2352)
			(end -1.016 0.8382)
			(stroke
				(width 0.1524)
				(type default)
			)
			(layer "F.SilkS")
		)
		(fp_line
			(start -1.016 -0.8382)
			(end -1.016 -2.2352)
			(stroke
				(width 0.1524)
				(type default)
			)
			(layer "F.SilkS")
		)
		(fp_line
			(start -1.016 -2.2352)
			(end 1.016 -2.2352)
			(stroke
				(width 0.1524)
				(type default)
			)
			(layer "F.SilkS")
		)
		(fp_rect
			(start -1.0922 2.3114)
			(end 1.0922 -2.3114)
			(stroke
				(width 0)
				(type default)
			)
			(fill no)
			(layer "F.CrtYd")
		)
		(fp_poly
			(pts
				(xy 1.0922 -2.3114) (xy 1.0922 2.3114) (xy -1.0922 2.3114) (xy -1.0922 -2.3114)
			)
			(stroke
				(width 0)
				(type default)
			)
			(fill no)
			(layer "F.Fab")
		)
		(pad "1" smd rect
			(at 0 -1.397 180)
			(size 1.651 1.27)
			(layers "F.Cu" "F.Mask" "F.Paste")
			(net "P12V_HDD4")
		)
		(pad "2" smd rect
			(at 0 1.397 180)
			(size 1.651 1.27)
			(layers "F.Cu" "F.Mask" "F.Paste")
			(net "GND")
		)
	)
	(footprint ""
		(layer "F.Cu")
		(at 54.508146 -191.7827 180)
		(property "Reference" "C243"
			(at 0 0 180)
			(layer "F.SilkS")
			(hide yes)
			(effects
				(font
					(size 1.27 1.27)
				)
			)
		)
		(property "Value" "SC1U25V3KX-1-GP"
			(at 0 -2.8194 180)
			(unlocked yes)
			(layer "F.Fab")
			(hide yes)
			(effects
				(font
					(size 1.016 1.016)
					(thickness 0.1524)
				)
			)
		)
		(property "Device Type" "C603H36"
			(at 0 -4.3434 180)
			(unlocked yes)
			(layer "F.Fab")
			(hide yes)
			(effects
				(font
					(size 1.016 1.016)
					(thickness 0.1524)
				)
			)
		)
		(duplicate_pad_numbers_are_jumpers no)
		(fp_line
			(start 0.508 0)
			(end -0.508 0)
			(stroke
				(width 0.2032)
				(type default)
			)
			(layer "F.SilkS")
		)
		(fp_rect
			(start -0.5842 1.3335)
			(end 0.5842 -1.3335)
			(stroke
				(width 0)
				(type default)
			)
			(fill no)
			(layer "F.CrtYd")
		)
		(fp_rect
			(start -0.5842 1.3335)
			(end 0.5842 -1.3335)
			(stroke
				(width 0)
				(type default)
			)
			(fill no)
			(layer "F.Fab")
		)
		(pad "1" smd custom
			(at 0 -0.762 180)
			(size 0.2159 0.2159)
			(layers "F.Cu" "F.Mask" "F.Paste")
			(net "P12V_HDD8")
			(options
				(clearance outline)
				(anchor circle)
			)
			(primitives
				(gr_poly
					(pts
						(arc
							(start -0.3302 -0.4318)
							(mid -0.402042 -0.402042)
							(end -0.4318 -0.3302)
						)
						(arc
							(start -0.4318 0.3302)
							(mid -0.402042 0.402042)
							(end -0.3302 0.4318)
						)
						(arc
							(start 0.3302 0.4318)
							(mid 0.402042 0.402042)
							(end 0.4318 0.3302)
						)
						(arc
							(start 0.4318 -0.3302)
							(mid 0.402042 -0.402042)
							(end 0.3302 -0.4318)
						)
					)
					(width 0)
					(fill yes)
				)
			)
		)
		(pad "2" smd custom
			(at 0 0.762 180)
			(size 0.2159 0.2159)
			(layers "F.Cu" "F.Mask" "F.Paste")
			(net "GND")
			(options
				(clearance outline)
				(anchor circle)
			)
			(primitives
				(gr_poly
					(pts
						(arc
							(start -0.3302 -0.4318)
							(mid -0.402042 -0.402042)
							(end -0.4318 -0.3302)
						)
						(arc
							(start -0.4318 0.3302)
							(mid -0.402042 0.402042)
							(end -0.3302 0.4318)
						)
						(arc
							(start 0.3302 0.4318)
							(mid 0.402042 0.402042)
							(end 0.4318 0.3302)
						)
						(arc
							(start 0.4318 -0.3302)
							(mid 0.402042 -0.402042)
							(end 0.3302 -0.4318)
						)
					)
					(width 0)
					(fill yes)
				)
			)
		)
	)
	(footprint ""
		(layer "F.Cu")
		(at 51.561746 -22.9997 90)
		(property "Reference" "TP20"
			(at 0 0 90)
			(layer "F.SilkS")
			(hide yes)
			(effects
				(font
					(size 1.27 1.27)
				)
			)
		)
		(property "Value" "TPAD32-GP"
			(at 0 -3.166364 90)
			(unlocked yes)
			(layer "F.Fab")
			(hide yes)
			(effects
				(font
					(size 1.016 1.016)
					(thickness 0.1524)
				)
			)
		)
		(property "Device Type" "TPAD32"
			(at 0 -4.690618 90)
			(unlocked yes)
			(layer "F.Fab")
			(hide yes)
			(effects
				(font
					(size 1.016 1.016)
					(thickness 0.1524)
				)
			)
		)
		(duplicate_pad_numbers_are_jumpers no)
		(fp_poly
			(pts
				(arc
					(start 0 0.4064)
					(mid 0 -0.4064)
					(end 0 0.4064)
				)
			)
			(stroke
				(width 0)
				(type default)
			)
			(fill no)
			(layer "F.CrtYd")
		)
		(fp_poly
			(pts
				(arc
					(start 0 0.7112)
					(mid 0 -0.7112)
					(end 0 0.7112)
				)
			)
			(stroke
				(width 0)
				(type default)
			)
			(fill no)
			(layer "F.Fab")
		)
		(pad "1" smd circle
			(at 0 0 90)
			(size 0.8128 0.8128)
			(layers "F.Cu" "F.Mask" "F.Paste")
			(net "P5VB_EN")
		)
	)
	(footprint ""
		(layer "F.Cu")
		(at 59.9694 -481.4824)
		(property "Reference" "R376"
			(at 0 0 0)
			(layer "F.SilkS")
			(hide yes)
			(effects
				(font
					(size 1.27 1.27)
				)
			)
		)
		(property "Value" "0R2J-2-GP"
			(at 0.064008 -3.993896 0)
			(unlocked yes)
			(layer "F.Fab")
			(hide yes)
			(effects
				(font
					(size 1.016 1.016)
					(thickness 0.1524)
				)
			)
		)
		(property "Device Type" "R402H16"
			(at 0.064008 -5.517896 0)
			(unlocked yes)
			(layer "F.Fab")
			(hide yes)
			(effects
				(font
					(size 1.016 1.016)
					(thickness 0.1524)
				)
			)
		)
		(duplicate_pad_numbers_are_jumpers no)
		(fp_line
			(start -0.508 -0.9398)
			(end -0.508 0.9398)
			(stroke
				(width 0.1524)
				(type default)
			)
			(layer "F.SilkS")
		)
		(fp_line
			(start 0.508 -0.9398)
			(end -0.508 -0.9398)
			(stroke
				(width 0.1524)
				(type default)
			)
			(layer "F.SilkS")
		)
		(fp_rect
			(start -0.508 0.9398)
			(end 0.508 -0.9398)
			(stroke
				(width 0)
				(type default)
			)
			(fill no)
			(layer "F.CrtYd")
		)
		(fp_rect
			(start -0.508 0.9398)
			(end 0.508 -0.9398)
			(stroke
				(width 0)
				(type default)
			)
			(fill no)
			(layer "F.Fab")
		)
		(pad "1" smd custom
			(at 0 -0.4445)
			(size 0.1397 0.1397)
			(layers "F.Cu" "F.Mask" "F.Paste")
			(net "HDD_PRSNT_NET5")
			(options
				(clearance outline)
				(anchor circle)
			)
			(primitives
				(gr_poly
					(pts
						(arc
							(start -0.1778 -0.2794)
							(mid -0.249642 -0.249642)
							(end -0.2794 -0.1778)
						)
						(arc
							(start -0.2794 0.1778)
							(mid -0.249642 0.249642)
							(end -0.1778 0.2794)
						)
						(arc
							(start 0.1778 0.2794)
							(mid 0.249642 0.249642)
							(end 0.2794 0.1778)
						)
						(arc
							(start 0.2794 -0.1778)
							(mid 0.249642 -0.249642)
							(end 0.1778 -0.2794)
						)
					)
					(width 0)
					(fill yes)
				)
			)
		)
		(pad "2" smd custom
			(at 0 0.4445)
			(size 0.1397 0.1397)
			(layers "F.Cu" "F.Mask" "F.Paste")
			(net "HDD5_LED_B")
			(options
				(clearance outline)
				(anchor circle)
			)
			(primitives
				(gr_poly
					(pts
						(arc
							(start -0.1778 -0.2794)
							(mid -0.249642 -0.249642)
							(end -0.2794 -0.1778)
						)
						(arc
							(start -0.2794 0.1778)
							(mid -0.249642 0.249642)
							(end -0.1778 0.2794)
						)
						(arc
							(start 0.1778 0.2794)
							(mid 0.249642 0.249642)
							(end 0.2794 0.1778)
						)
						(arc
							(start 0.2794 -0.1778)
							(mid 0.249642 -0.249642)
							(end 0.1778 -0.2794)
						)
					)
					(width 0)
					(fill yes)
				)
			)
		)
	)
	(footprint ""
		(layer "F.Cu")
		(at 42.500042 -273.670014 90)
		(property "Reference" "SKT8"
			(at 0 0 90)
			(layer "F.SilkS")
			(hide yes)
			(effects
				(font
					(size 1.27 1.27)
				)
			)
		)
		(property "Value" "SKT-SATA14P-15P-12-GP"
			(at -22.6187 8.1788 90)
			(unlocked yes)
			(layer "F.Fab")
			(hide yes)
			(effects
				(font
					(size 1.016 1.016)
					(thickness 0.1524)
				)
			)
		)
		(property "Device Type" "87945-1001"
			(at -22.6187 6.6548 90)
			(unlocked yes)
			(layer "F.Fab")
			(hide yes)
			(effects
				(font
					(size 1.016 1.016)
					(thickness 0.1524)
				)
			)
		)
		(duplicate_pad_numbers_are_jumpers no)
		(fp_line
			(start -15.3924 -5.8547)
			(end -16.3576 -5.8547)
			(stroke
				(width 0.3302)
				(type default)
			)
			(layer "F.SilkS")
		)
		(fp_line
			(start 20.4724 -5.7658)
			(end 20.4724 -2.3114)
			(stroke
				(width 0.1524)
				(type default)
			)
			(layer "F.SilkS")
		)
		(fp_line
			(start -20.4724 -5.7658)
			(end 20.4724 -5.7658)
			(stroke
				(width 0.1524)
				(type default)
			)
			(layer "F.SilkS")
		)
		(fp_line
			(start 23.7617 -2.3114)
			(end 23.7617 2.3114)
			(stroke
				(width 0.1524)
				(type default)
			)
			(layer "F.SilkS")
		)
		(fp_line
			(start 20.4724 -2.3114)
			(end 23.7617 -2.3114)
			(stroke
				(width 0.1524)
				(type default)
			)
			(layer "F.SilkS")
		)
		(fp_line
			(start -20.4724 -2.3114)
			(end -20.4724 -5.7658)
			(stroke
				(width 0.1524)
				(type default)
			)
			(layer "F.SilkS")
		)
		(fp_line
			(start -23.7617 -2.3114)
			(end -20.4724 -2.3114)
			(stroke
				(width 0.1524)
				(type default)
			)
			(layer "F.SilkS")
		)
		(fp_line
			(start 23.117556 -0.5461)
			(end 23.117556 0.5461)
			(stroke
				(width 0.3048)
				(type default)
			)
			(layer "F.SilkS")
		)
		(fp_line
			(start -20.882356 -0.5461)
			(end -20.882356 0.5461)
			(stroke
				(width 0.3048)
				(type default)
			)
			(layer "F.SilkS")
		)
		(fp_line
			(start 20.882356 0.5461)
			(end 20.882356 -0.5461)
			(stroke
				(width 0.3048)
				(type default)
			)
			(layer "F.SilkS")
		)
		(fp_line
			(start -23.117556 0.5461)
			(end -23.117556 -0.5461)
			(stroke
				(width 0.3048)
				(type default)
			)
			(layer "F.SilkS")
		)
		(fp_line
			(start 23.7617 2.3114)
			(end 20.4724 2.3114)
			(stroke
				(width 0.1524)
				(type default)
			)
			(layer "F.SilkS")
		)
		(fp_line
			(start 20.4724 2.3114)
			(end 20.4724 9.652)
			(stroke
				(width 0.1524)
				(type default)
			)
			(layer "F.SilkS")
		)
		(fp_line
			(start -20.4724 2.3114)
			(end -23.7617 2.3114)
			(stroke
				(width 0.1524)
				(type default)
			)
			(layer "F.SilkS")
		)
		(fp_line
			(start -23.7617 2.3114)
			(end -23.7617 -2.3114)
			(stroke
				(width 0.1524)
				(type default)
			)
			(layer "F.SilkS")
		)
		(fp_line
			(start 17.8435 7.9502)
			(end -17.8435 7.9502)
			(stroke
				(width 0.1524)
				(type default)
			)
			(layer "F.SilkS")
		)
		(fp_line
			(start -17.8435 7.9502)
			(end -17.8435 9.652)
			(stroke
				(width 0.1524)
				(type default)
			)
			(layer "F.SilkS")
		)
		(fp_line
			(start 20.4724 9.652)
			(end 17.8435 9.652)
			(stroke
				(width 0.1524)
				(type default)
			)
			(layer "F.SilkS")
		)
		(fp_line
			(start 17.8435 9.652)
			(end 17.8435 7.9502)
			(stroke
				(width 0.1524)
				(type default)
			)
			(layer "F.SilkS")
		)
		(fp_line
			(start -17.8435 9.652)
			(end -20.4724 9.652)
			(stroke
				(width 0.1524)
				(type default)
			)
			(layer "F.SilkS")
		)
		(fp_line
			(start -20.4724 9.652)
			(end -20.4724 2.3114)
			(stroke
				(width 0.1524)
				(type default)
			)
			(layer "F.SilkS")
		)
		(fp_arc
			(start 20.882356 -0.5461)
			(mid 21.999956 -1.6637)
			(end 23.117556 -0.5461)
			(stroke
				(width 0.3048)
				(type default)
			)
			(layer "F.SilkS")
		)
		(fp_arc
			(start -23.117556 -0.5461)
			(mid -21.999956 -1.6637)
			(end -20.882356 -0.5461)
			(stroke
				(width 0.3048)
				(type default)
			)
			(layer "F.SilkS")
		)
		(fp_arc
			(start 23.117556 0.5461)
			(mid 21.999956 1.6637)
			(end 20.882356 0.5461)
			(stroke
				(width 0.3048)
				(type default)
			)
			(layer "F.SilkS")
		)
		(fp_arc
			(start -20.882356 0.5461)
			(mid -21.999956 1.6637)
			(end -23.117556 0.5461)
			(stroke
				(width 0.3048)
				(type default)
			)
			(layer "F.SilkS")
		)
		(fp_poly
			(pts
				(xy -15.87119 -5.838698) (xy -15.23619 -6.473698) (xy -16.50619 -6.473698)
			)
			(stroke
				(width 0)
				(type default)
			)
			(fill yes)
			(layer "F.SilkS")
		)
		(fp_poly
			(pts
				(xy -20.2184 -5.5118) (xy 20.2184 -5.5118) (xy 20.2184 -2.0574) (xy 23.5077 -2.0574) (xy 23.5077 2.0574)
				(xy 20.2184 2.0574) (xy 20.2184 9.398) (xy 18.0975 9.398) (xy 18.0975 7.6962) (xy -18.0975 7.6962)
				(xy -18.0975 9.398) (xy -20.2184 9.398) (xy -20.2184 2.0574) (xy -23.5077 2.0574) (xy -23.5077 -2.0574)
				(xy -20.2184 -2.0574)
			)
			(stroke
				(width 0)
				(type default)
			)
			(fill no)
			(layer "F.CrtYd")
		)
		(fp_poly
			(pts
				(xy -20.2184 -5.5118) (xy -20.2184 -6.0198) (xy -20.7264 -6.0198) (xy -20.7264 -2.5654) (xy -24.0157 -2.5654)
				(xy -24.0157 2.5654) (xy -20.7264 2.5654) (xy -20.7264 9.906) (xy -17.5895 9.906) (xy -17.5895 8.2042)
				(xy 17.5895 8.2042) (xy 17.5895 9.906) (xy 20.7264 9.906) (xy 20.7264 2.5654) (xy 24.0157 2.5654)
				(xy 24.0157 -2.5654) (xy 20.7264 -2.5654) (xy 20.7264 -6.0198) (xy -20.21586 -6.0198) (xy -20.21586 -5.5118)
				(xy 20.2184 -5.5118) (xy 20.2184 -2.0574) (xy 23.5077 -2.0574) (xy 23.5077 2.0574) (xy 20.2184 2.0574)
				(xy 20.2184 9.398) (xy 18.0975 9.398) (xy 18.0975 7.6962) (xy -18.0975 7.6962) (xy -18.0975 9.398)
				(xy -20.2184 9.398) (xy -20.2184 2.0574) (xy -23.5077 2.0574) (xy -23.5077 -2.0574) (xy -20.2184 -2.0574)
			)
			(stroke
				(width 0)
				(type default)
			)
			(fill no)
			(layer "F.CrtYd")
		)
		(fp_poly
			(pts
				(xy -20.7264 -6.0198) (xy -20.7264 -2.5654) (xy -24.0157 -2.5654) (xy -24.0157 2.5654) (xy -20.7264 2.5654)
				(xy -20.7264 9.906) (xy -17.5895 9.906) (xy -17.5895 8.2042) (xy 17.5895 8.2042) (xy 17.5895 9.906)
				(xy 20.7264 9.906) (xy 20.7264 2.5654) (xy 24.0157 2.5654) (xy 24.0157 -2.5654) (xy 20.7264 -2.5654)
				(xy 20.7264 -6.0198)
			)
			(stroke
				(width 0)
				(type default)
			)
			(fill no)
			(layer "F.Fab")
		)
		(pad "" np_thru_hole circle
			(at -18.999962 -2.350008 90)
			(size 0.254 0.254)
			(drill 1.8542)
			(layers "*.Cu" "*.Mask")
			(clearance 1.1557)
			(thermal_gap 1.1557)
		)
		(pad "" np_thru_hole circle
			(at 18.999962 -2.350008 90)
			(size 0.254 0.254)
			(drill 1.8542)
			(layers "*.Cu" "*.Mask")
			(clearance 1.1557)
			(thermal_gap 1.1557)
		)
		(pad "H1" thru_hole oval
			(at -21.999956 0 90)
			(size 1.524 2.6162)
			(drill oval 0.8128 1.905)
			(layers "*.Cu" "*.Mask")
			(remove_unused_layers no)
			(net "GND")
			(clearance 0.1524)
			(thermal_gap 0.1524)
		)
		(pad "H2" thru_hole oval
			(at 21.999956 0 90)
			(size 1.524 2.6162)
			(drill oval 0.8128 1.905)
			(layers "*.Cu" "*.Mask")
			(remove_unused_layers no)
			(net "GND")
			(clearance 0.1524)
			(thermal_gap 0.1524)
		)
		(pad "P1" smd rect
			(at -1.89992 -4.249928 90)
			(size 0.6604 2.3876)
			(layers "F.Cu" "F.Mask" "F.Paste")
			(net "Net_10")
		)
		(pad "P2" smd rect
			(at -0.62992 -4.249928 90)
			(size 0.6604 2.3876)
			(layers "F.Cu" "F.Mask" "F.Paste")
			(net "Net_9")
		)
		(pad "P3" smd rect
			(at 0.64008 -4.249928 90)
			(size 0.6604 2.3876)
			(layers "F.Cu" "F.Mask" "F.Paste")
			(net "Net_8")
		)
		(pad "P4" smd rect
			(at 1.91008 -4.249928 90)
			(size 0.6604 2.3876)
			(layers "F.Cu" "F.Mask" "F.Paste")
			(net "GND")
		)
		(pad "P5" smd rect
			(at 3.18008 -4.249928 90)
			(size 0.6604 2.3876)
			(layers "F.Cu" "F.Mask" "F.Paste")
			(net "HDD_PRSNT_NET7")
		)
		(pad "P6" smd rect
			(at 4.45008 -4.249928 90)
			(size 0.6604 2.3876)
			(layers "F.Cu" "F.Mask" "F.Paste")
			(net "GND")
		)
		(pad "P7" smd rect
			(at 5.72008 -4.249928 90)
			(size 0.6604 2.3876)
			(layers "F.Cu" "F.Mask" "F.Paste")
			(net "5V_PRE_7")
		)
		(pad "P8" smd rect
			(at 6.99008 -4.249928 90)
			(size 0.6604 2.3876)
			(layers "F.Cu" "F.Mask" "F.Paste")
			(net "P5V_HDD7")
		)
		(pad "P9" smd rect
			(at 8.26008 -4.249928 90)
			(size 0.6604 2.3876)
			(layers "F.Cu" "F.Mask" "F.Paste")
			(net "P5V_HDD7")
		)
		(pad "P10" smd rect
			(at 9.53008 -4.249928 90)
			(size 0.6604 2.3876)
			(layers "F.Cu" "F.Mask" "F.Paste")
			(net "GND")
		)
		(pad "P11" smd rect
			(at 10.80008 -4.249928 90)
			(size 0.6604 2.3876)
			(layers "F.Cu" "F.Mask" "F.Paste")
			(net "ACT_HDD7")
		)
		(pad "P12" smd rect
			(at 12.07008 -4.249928 90)
			(size 0.6604 2.3876)
			(layers "F.Cu" "F.Mask" "F.Paste")
			(net "GND")
		)
		(pad "P13" smd rect
			(at 13.34008 -4.249928 90)
			(size 0.6604 2.3876)
			(layers "F.Cu" "F.Mask" "F.Paste")
			(net "12V_PRE_7")
		)
		(pad "P14" smd rect
			(at 14.61008 -4.249928 90)
			(size 0.6604 2.3876)
			(layers "F.Cu" "F.Mask" "F.Paste")
			(net "P12V_HDD7")
		)
		(pad "P15" smd rect
			(at 15.88008 -4.249928 90)
			(size 0.6604 2.3876)
			(layers "F.Cu" "F.Mask" "F.Paste")
			(net "P12V_HDD7")
		)
		(pad "S1" smd rect
			(at -15.86992 -4.249928 90)
			(size 0.6604 2.3876)
			(layers "F.Cu" "F.Mask" "F.Paste")
			(net "GND")
		)
		(pad "S2" smd rect
			(at -14.59992 -4.249928 90)
			(size 0.6604 2.3876)
			(layers "F.Cu" "F.Mask" "F.Paste")
			(net "SAS2X28_A_HDD7_TX_+")
		)
		(pad "S3" smd rect
			(at -13.32992 -4.249928 90)
			(size 0.6604 2.3876)
			(layers "F.Cu" "F.Mask" "F.Paste")
			(net "SAS2X28_A_HDD7_TX_-")
		)
		(pad "S4" smd rect
			(at -12.05992 -4.249928 90)
			(size 0.6604 2.3876)
			(layers "F.Cu" "F.Mask" "F.Paste")
			(net "GND")
		)
		(pad "S5" smd rect
			(at -10.78992 -4.249928 90)
			(size 0.6604 2.3876)
			(layers "F.Cu" "F.Mask" "F.Paste")
			(net "SAS2X28_DRIVE_RX_N_A7")
		)
		(pad "S6" smd rect
			(at -9.51992 -4.249928 90)
			(size 0.6604 2.3876)
			(layers "F.Cu" "F.Mask" "F.Paste")
			(net "SAS2X28_DRIVE_RX_P_A7")
		)
		(pad "S7" smd rect
			(at -8.24992 -4.249928 90)
			(size 0.6604 2.3876)
			(layers "F.Cu" "F.Mask" "F.Paste")
			(net "GND")
		)
		(pad "S8" smd rect
			(at -7.480046 -2.100072 90)
			(size 0.508 1.905)
			(layers "F.Cu" "F.Mask" "F.Paste")
			(net "GND")
		)
		(pad "S9" smd rect
			(at -6.679946 -2.100072 90)
			(size 0.508 1.905)
			(layers "F.Cu" "F.Mask" "F.Paste")
			(net "SAS2X28_B_HDD7_TX_+")
		)
		(pad "S10" smd rect
			(at -5.8801 -2.100072 90)
			(size 0.508 1.905)
			(layers "F.Cu" "F.Mask" "F.Paste")
			(net "SAS2X28_B_HDD7_TX_-")
		)
		(pad "S11" smd rect
			(at -5.08 -2.100072 90)
			(size 0.508 1.905)
			(layers "F.Cu" "F.Mask" "F.Paste")
			(net "GND")
		)
		(pad "S12" smd rect
			(at -4.2799 -2.100072 90)
			(size 0.508 1.905)
			(layers "F.Cu" "F.Mask" "F.Paste")
			(net "SAS2X28_DRIVE_RX_N_B7")
		)
		(pad "S13" smd rect
			(at -3.480054 -2.100072 90)
			(size 0.508 1.905)
			(layers "F.Cu" "F.Mask" "F.Paste")
			(net "SAS2X28_DRIVE_RX_P_B7")
		)
		(pad "S14" smd rect
			(at -2.679954 -2.100072 90)
			(size 0.508 1.905)
			(layers "F.Cu" "F.Mask" "F.Paste")
			(net "GND")
		)
		(zone
			(layers "F.Cu" "B.Cu" "In1.Cu" "In2.Cu" "In3.Cu" "In4.Cu" "In5.Cu" "In6.Cu")
			(hatch none 0.5)
			(connect_pads
				(clearance 0)
			)
			(min_thickness 0.25)
			(keepout
				(tracks not_allowed)
				(vias allowed)
				(pads allowed)
				(copperpour not_allowed)
				(footprints allowed)
			)
			(placement
				(enabled no)
				(sheetname "")
			)
			(fill
				(thermal_gap 0.5)
				(thermal_bridge_width 0.5)
				(island_removal_mode 0)
			)
			(polygon
				(pts
					(arc
						(start 41.381934 -292.669976)
						(mid 38.918134 -292.669976)
						(end 41.381934 -292.669976)
					)
				)
			)
		)
		(zone
			(layers "F.Cu" "B.Cu" "In1.Cu" "In2.Cu" "In3.Cu" "In4.Cu" "In5.Cu" "In6.Cu")
			(hatch none 0.5)
			(connect_pads
				(clearance 0)
			)
			(min_thickness 0.25)
			(keepout
				(tracks not_allowed)
				(vias allowed)
				(pads allowed)
				(copperpour not_allowed)
				(footprints allowed)
			)
			(placement
				(enabled no)
				(sheetname "")
			)
			(fill
				(thermal_gap 0.5)
				(thermal_bridge_width 0.5)
				(island_removal_mode 0)
			)
			(polygon
				(pts
					(arc
						(start 41.381934 -254.670052)
						(mid 38.918134 -254.670052)
						(end 41.381934 -254.670052)
					)
				)
			)
		)
	)
	(footprint ""
		(layer "F.Cu")
		(at 230.335582 -247.495568 90)
		(property "Reference" "R128"
			(at 0 0 90)
			(layer "F.SilkS")
			(hide yes)
			(effects
				(font
					(size 1.27 1.27)
				)
			)
		)
		(property "Value" "10KR2F-2-GP"
			(at 0.064008 -3.993896 90)
			(unlocked yes)
			(layer "F.Fab")
			(hide yes)
			(effects
				(font
					(size 1.016 1.016)
					(thickness 0.1524)
				)
			)
		)
		(property "Device Type" "R402H16"
			(at 0.064008 -5.517896 90)
			(unlocked yes)
			(layer "F.Fab")
			(hide yes)
			(effects
				(font
					(size 1.016 1.016)
					(thickness 0.1524)
				)
			)
		)
		(duplicate_pad_numbers_are_jumpers no)
		(fp_line
			(start 0.508 -0.9398)
			(end -0.508 -0.9398)
			(stroke
				(width 0.1524)
				(type default)
			)
			(layer "F.SilkS")
		)
		(fp_line
			(start -0.508 -0.9398)
			(end -0.508 0.9398)
			(stroke
				(width 0.1524)
				(type default)
			)
			(layer "F.SilkS")
		)
		(fp_rect
			(start -0.508 0.9398)
			(end 0.508 -0.9398)
			(stroke
				(width 0)
				(type default)
			)
			(fill no)
			(layer "F.CrtYd")
		)
		(fp_rect
			(start -0.508 0.9398)
			(end 0.508 -0.9398)
			(stroke
				(width 0)
				(type default)
			)
			(fill no)
			(layer "F.Fab")
		)
		(pad "1" smd custom
			(at 0 -0.4445 90)
			(size 0.1397 0.1397)
			(layers "F.Cu" "F.Mask" "F.Paste")
			(net "P5VA")
			(options
				(clearance outline)
				(anchor circle)
			)
			(primitives
				(gr_poly
					(pts
						(arc
							(start -0.1778 -0.2794)
							(mid -0.249642 -0.249642)
							(end -0.2794 -0.1778)
						)
						(arc
							(start -0.2794 0.1778)
							(mid -0.249642 0.249642)
							(end -0.1778 0.2794)
						)
						(arc
							(start 0.1778 0.2794)
							(mid 0.249642 0.249642)
							(end 0.2794 0.1778)
						)
						(arc
							(start 0.2794 -0.1778)
							(mid 0.249642 -0.249642)
							(end 0.1778 -0.2794)
						)
					)
					(width 0)
					(fill yes)
				)
			)
		)
		(pad "2" smd custom
			(at 0 0.4445 90)
			(size 0.1397 0.1397)
			(layers "F.Cu" "F.Mask" "F.Paste")
			(net "DRIVE_ACT_2")
			(options
				(clearance outline)
				(anchor circle)
			)
			(primitives
				(gr_poly
					(pts
						(arc
							(start -0.1778 -0.2794)
							(mid -0.249642 -0.249642)
							(end -0.2794 -0.1778)
						)
						(arc
							(start -0.2794 0.1778)
							(mid -0.249642 0.249642)
							(end -0.1778 0.2794)
						)
						(arc
							(start 0.1778 0.2794)
							(mid 0.249642 0.249642)
							(end 0.2794 0.1778)
						)
						(arc
							(start 0.2794 -0.1778)
							(mid 0.249642 -0.249642)
							(end 0.1778 -0.2794)
						)
					)
					(width 0)
					(fill yes)
				)
			)
		)
	)
	(footprint ""
		(layer "F.Cu")
		(at 214.2998 -79.2988)
		(property "Reference" "TP29"
			(at 0 0 0)
			(layer "F.SilkS")
			(hide yes)
			(effects
				(font
					(size 1.27 1.27)
				)
			)
		)
		(property "Value" "TPAD32-GP"
			(at 0 -3.166364 0)
			(unlocked yes)
			(layer "F.Fab")
			(hide yes)
			(effects
				(font
					(size 1.016 1.016)
					(thickness 0.1524)
				)
			)
		)
		(property "Device Type" "TPAD32"
			(at 0 -4.690618 0)
			(unlocked yes)
			(layer "F.Fab")
			(hide yes)
			(effects
				(font
					(size 1.016 1.016)
					(thickness 0.1524)
				)
			)
		)
		(duplicate_pad_numbers_are_jumpers no)
		(fp_poly
			(pts
				(arc
					(start 0.4064 0)
					(mid -0.4064 0)
					(end 0.4064 0)
				)
			)
			(stroke
				(width 0)
				(type default)
			)
			(fill no)
			(layer "F.CrtYd")
		)
		(fp_poly
			(pts
				(arc
					(start 0.7112 0)
					(mid -0.7112 0)
					(end 0.7112 0)
				)
			)
			(stroke
				(width 0)
				(type default)
			)
			(fill no)
			(layer "F.Fab")
		)
		(pad "1" smd circle
			(at 0 0)
			(size 0.8128 0.8128)
			(layers "F.Cu" "F.Mask" "F.Paste")
			(net "ACT_HDD4")
		)
	)
	(footprint ""
		(layer "F.Cu")
		(at 60.959746 -24.2697 -90)
		(property "Reference" "PR26"
			(at 0 0 270)
			(layer "F.SilkS")
			(hide yes)
			(effects
				(font
					(size 1.27 1.27)
				)
			)
		)
		(property "Value" "100KR2F-L1-GP"
			(at 0.064008 -3.993896 270)
			(unlocked yes)
			(layer "F.Fab")
			(hide yes)
			(effects
				(font
					(size 1.016 1.016)
					(thickness 0.1524)
				)
			)
		)
		(property "Device Type" "R402H16"
			(at 0.064008 -5.517896 270)
			(unlocked yes)
			(layer "F.Fab")
			(hide yes)
			(effects
				(font
					(size 1.016 1.016)
					(thickness 0.1524)
				)
			)
		)
		(duplicate_pad_numbers_are_jumpers no)
		(fp_line
			(start -0.508 -0.9398)
			(end -0.508 0.9398)
			(stroke
				(width 0.1524)
				(type default)
			)
			(layer "F.SilkS")
		)
		(fp_line
			(start 0.508 -0.9398)
			(end -0.508 -0.9398)
			(stroke
				(width 0.1524)
				(type default)
			)
			(layer "F.SilkS")
		)
		(fp_rect
			(start -0.508 0.9398)
			(end 0.508 -0.9398)
			(stroke
				(width 0)
				(type default)
			)
			(fill no)
			(layer "F.CrtYd")
		)
		(fp_rect
			(start -0.508 0.9398)
			(end 0.508 -0.9398)
			(stroke
				(width 0)
				(type default)
			)
			(fill no)
			(layer "F.Fab")
		)
		(pad "1" smd custom
			(at 0 -0.4445 270)
			(size 0.1397 0.1397)
			(layers "F.Cu" "F.Mask" "F.Paste")
			(net "P5VB_PGD")
			(options
				(clearance outline)
				(anchor circle)
			)
			(primitives
				(gr_poly
					(pts
						(arc
							(start -0.1778 -0.2794)
							(mid -0.249642 -0.249642)
							(end -0.2794 -0.1778)
						)
						(arc
							(start -0.2794 0.1778)
							(mid -0.249642 0.249642)
							(end -0.1778 0.2794)
						)
						(arc
							(start 0.1778 0.2794)
							(mid 0.249642 0.249642)
							(end 0.2794 0.1778)
						)
						(arc
							(start 0.2794 -0.1778)
							(mid 0.249642 -0.249642)
							(end 0.1778 -0.2794)
						)
					)
					(width 0)
					(fill yes)
				)
			)
		)
		(pad "2" smd custom
			(at 0 0.4445 270)
			(size 0.1397 0.1397)
			(layers "F.Cu" "F.Mask" "F.Paste")
			(net "P5VB_MODE_PG")
			(options
				(clearance outline)
				(anchor circle)
			)
			(primitives
				(gr_poly
					(pts
						(arc
							(start -0.1778 -0.2794)
							(mid -0.249642 -0.249642)
							(end -0.2794 -0.1778)
						)
						(arc
							(start -0.2794 0.1778)
							(mid -0.249642 0.249642)
							(end -0.1778 0.2794)
						)
						(arc
							(start 0.1778 0.2794)
							(mid 0.249642 0.249642)
							(end 0.2794 0.1778)
						)
						(arc
							(start 0.2794 -0.1778)
							(mid 0.249642 -0.249642)
							(end 0.1778 -0.2794)
						)
					)
					(width 0)
					(fill yes)
				)
			)
		)
	)
	(footprint ""
		(layer "F.Cu")
		(at 26.02103 -139.950952 90)
		(property "Reference" "C310"
			(at 0 0 90)
			(layer "F.SilkS")
			(hide yes)
			(effects
				(font
					(size 1.27 1.27)
				)
			)
		)
		(property "Value" "SCD01U50V2KX-1GP"
			(at 1.1811 -2.7051 90)
			(unlocked yes)
			(layer "F.Fab")
			(hide yes)
			(effects
				(font
					(size 1.016 1.016)
					(thickness 0.1524)
				)
			)
		)
		(property "Device Type" "C402H22"
			(at 1.1811 -4.2291 90)
			(unlocked yes)
			(layer "F.Fab")
			(hide yes)
			(effects
				(font
					(size 1.016 1.016)
					(thickness 0.1524)
				)
			)
		)
		(duplicate_pad_numbers_are_jumpers no)
		(fp_rect
			(start -0.4318 0.9525)
			(end 0.4318 -0.9525)
			(stroke
				(width 0)
				(type default)
			)
			(fill no)
			(layer "F.CrtYd")
		)
		(fp_rect
			(start -0.4318 0.9525)
			(end 0.4318 -0.9525)
			(stroke
				(width 0)
				(type default)
			)
			(fill no)
			(layer "F.Fab")
		)
		(pad "1" smd custom
			(at 0 -0.4445 90)
			(size 0.1524 0.1524)
			(layers "F.Cu" "F.Mask" "F.Paste")
			(net "SAS2X28_DRIVE_RX_N_A13")
			(options
				(clearance outline)
				(anchor circle)
			)
			(primitives
				(gr_poly
					(pts
						(arc
							(start 0.3048 -0.2032)
							(mid 0.275042 -0.275042)
							(end 0.2032 -0.3048)
						)
						(arc
							(start -0.2032 -0.3048)
							(mid -0.275042 -0.275042)
							(end -0.3048 -0.2032)
						)
						(arc
							(start -0.3048 0.2032)
							(mid -0.275042 0.275042)
							(end -0.2032 0.3048)
						)
						(arc
							(start 0.2032 0.3048)
							(mid 0.275042 0.275042)
							(end 0.3048 0.2032)
						)
					)
					(width 0)
					(fill yes)
				)
			)
		)
		(pad "2" smd custom
			(at 0 0.4445 90)
			(size 0.1524 0.1524)
			(layers "F.Cu" "F.Mask" "F.Paste")
			(net "SAS2X28_A_HDD13_RX_-")
			(options
				(clearance outline)
				(anchor circle)
			)
			(primitives
				(gr_poly
					(pts
						(arc
							(start 0.3048 -0.2032)
							(mid 0.275042 -0.275042)
							(end 0.2032 -0.3048)
						)
						(arc
							(start -0.2032 -0.3048)
							(mid -0.275042 -0.275042)
							(end -0.3048 -0.2032)
						)
						(arc
							(start -0.3048 0.2032)
							(mid -0.275042 0.275042)
							(end -0.2032 0.3048)
						)
						(arc
							(start 0.2032 0.3048)
							(mid 0.275042 0.275042)
							(end 0.3048 0.2032)
						)
					)
					(width 0)
					(fill yes)
				)
			)
		)
	)
	(footprint ""
		(layer "F.Cu")
		(at 29.362146 -373.4435 180)
		(property "Reference" "R313"
			(at 0 0 180)
			(layer "F.SilkS")
			(hide yes)
			(effects
				(font
					(size 1.27 1.27)
				)
			)
		)
		(property "Value" "4K7R2J-2-GP"
			(at 0.064008 -3.993896 180)
			(unlocked yes)
			(layer "F.Fab")
			(hide yes)
			(effects
				(font
					(size 1.016 1.016)
					(thickness 0.1524)
				)
			)
		)
		(property "Device Type" "R402H16"
			(at 0.064008 -5.517896 180)
			(unlocked yes)
			(layer "F.Fab")
			(hide yes)
			(effects
				(font
					(size 1.016 1.016)
					(thickness 0.1524)
				)
			)
		)
		(duplicate_pad_numbers_are_jumpers no)
		(fp_line
			(start 0.508 -0.9398)
			(end -0.508 -0.9398)
			(stroke
				(width 0.1524)
				(type default)
			)
			(layer "F.SilkS")
		)
		(fp_line
			(start -0.508 -0.9398)
			(end -0.508 0.9398)
			(stroke
				(width 0.1524)
				(type default)
			)
			(layer "F.SilkS")
		)
		(fp_rect
			(start -0.508 0.9398)
			(end 0.508 -0.9398)
			(stroke
				(width 0)
				(type default)
			)
			(fill no)
			(layer "F.CrtYd")
		)
		(fp_rect
			(start -0.508 0.9398)
			(end 0.508 -0.9398)
			(stroke
				(width 0)
				(type default)
			)
			(fill no)
			(layer "F.Fab")
		)
		(pad "1" smd custom
			(at 0 -0.4445 180)
			(size 0.1397 0.1397)
			(layers "F.Cu" "F.Mask" "F.Paste")
			(net "P3V3")
			(options
				(clearance outline)
				(anchor circle)
			)
			(primitives
				(gr_poly
					(pts
						(arc
							(start -0.1778 -0.2794)
							(mid -0.249642 -0.249642)
							(end -0.2794 -0.1778)
						)
						(arc
							(start -0.2794 0.1778)
							(mid -0.249642 0.249642)
							(end -0.1778 0.2794)
						)
						(arc
							(start 0.1778 0.2794)
							(mid 0.249642 0.249642)
							(end 0.2794 0.1778)
						)
						(arc
							(start 0.2794 -0.1778)
							(mid 0.249642 -0.249642)
							(end 0.1778 -0.2794)
						)
					)
					(width 0)
					(fill yes)
				)
			)
		)
		(pad "2" smd custom
			(at 0 0.4445 180)
			(size 0.1397 0.1397)
			(layers "F.Cu" "F.Mask" "F.Paste")
			(net "I2C_B_TMP1_A0")
			(options
				(clearance outline)
				(anchor circle)
			)
			(primitives
				(gr_poly
					(pts
						(arc
							(start -0.1778 -0.2794)
							(mid -0.249642 -0.249642)
							(end -0.2794 -0.1778)
						)
						(arc
							(start -0.2794 0.1778)
							(mid -0.249642 0.249642)
							(end -0.1778 0.2794)
						)
						(arc
							(start 0.1778 0.2794)
							(mid 0.249642 0.249642)
							(end 0.2794 0.1778)
						)
						(arc
							(start 0.2794 -0.1778)
							(mid 0.249642 -0.249642)
							(end 0.1778 -0.2794)
						)
					)
					(width 0)
					(fill yes)
				)
			)
		)
	)
	(footprint ""
		(layer "F.Cu")
		(at 217.799412 -57.130696 -90)
		(property "Reference" "C166"
			(at 0 0 270)
			(layer "F.SilkS")
			(hide yes)
			(effects
				(font
					(size 1.27 1.27)
				)
			)
		)
		(property "Value" "SCD01U50V2KX-1GP"
			(at 1.1811 -2.7051 270)
			(unlocked yes)
			(layer "F.Fab")
			(hide yes)
			(effects
				(font
					(size 1.016 1.016)
					(thickness 0.1524)
				)
			)
		)
		(property "Device Type" "C402H22"
			(at 1.1811 -4.2291 270)
			(unlocked yes)
			(layer "F.Fab")
			(hide yes)
			(effects
				(font
					(size 1.016 1.016)
					(thickness 0.1524)
				)
			)
		)
		(duplicate_pad_numbers_are_jumpers no)
		(fp_rect
			(start -0.4318 0.9525)
			(end 0.4318 -0.9525)
			(stroke
				(width 0)
				(type default)
			)
			(fill no)
			(layer "F.CrtYd")
		)
		(fp_rect
			(start -0.4318 0.9525)
			(end 0.4318 -0.9525)
			(stroke
				(width 0)
				(type default)
			)
			(fill no)
			(layer "F.Fab")
		)
		(pad "1" smd custom
			(at 0 -0.4445 270)
			(size 0.1524 0.1524)
			(layers "F.Cu" "F.Mask" "F.Paste")
			(net "SAS2X28_DRIVE_RX_N_A4")
			(options
				(clearance outline)
				(anchor circle)
			)
			(primitives
				(gr_poly
					(pts
						(arc
							(start 0.3048 -0.2032)
							(mid 0.275042 -0.275042)
							(end 0.2032 -0.3048)
						)
						(arc
							(start -0.2032 -0.3048)
							(mid -0.275042 -0.275042)
							(end -0.3048 -0.2032)
						)
						(arc
							(start -0.3048 0.2032)
							(mid -0.275042 0.275042)
							(end -0.2032 0.3048)
						)
						(arc
							(start 0.2032 0.3048)
							(mid 0.275042 0.275042)
							(end 0.3048 0.2032)
						)
					)
					(width 0)
					(fill yes)
				)
			)
		)
		(pad "2" smd custom
			(at 0 0.4445 270)
			(size 0.1524 0.1524)
			(layers "F.Cu" "F.Mask" "F.Paste")
			(net "SAS2X28_A_HDD4_RX_-")
			(options
				(clearance outline)
				(anchor circle)
			)
			(primitives
				(gr_poly
					(pts
						(arc
							(start 0.3048 -0.2032)
							(mid 0.275042 -0.275042)
							(end 0.2032 -0.3048)
						)
						(arc
							(start -0.2032 -0.3048)
							(mid -0.275042 -0.275042)
							(end -0.3048 -0.2032)
						)
						(arc
							(start -0.3048 0.2032)
							(mid -0.275042 0.275042)
							(end -0.2032 0.3048)
						)
						(arc
							(start 0.2032 0.3048)
							(mid 0.275042 0.275042)
							(end 0.3048 0.2032)
						)
					)
					(width 0)
					(fill yes)
				)
			)
		)
	)
	(footprint ""
		(layer "F.Cu")
		(at 2.500122 -105.998518 -90)
		(property "Reference" "CN2"
			(at 0 0 270)
			(layer "F.SilkS")
			(hide yes)
			(effects
				(font
					(size 1.27 1.27)
				)
			)
		)
		(property "Value" "PCISLT164-70-GP"
			(at -77.8764 -6.4262 270)
			(unlocked yes)
			(layer "F.Fab")
			(hide yes)
			(effects
				(font
					(size 1.016 1.016)
					(thickness 0.1524)
				)
			)
		)
		(property "Device Type" "G630EAA12048EU"
			(at -77.8764 -7.9502 270)
			(unlocked yes)
			(layer "F.Fab")
			(hide yes)
			(effects
				(font
					(size 1.016 1.016)
					(thickness 0.1524)
				)
			)
		)
		(duplicate_pad_numbers_are_jumpers no)
		(fp_line
			(start -79.6544 2.500122)
			(end -1.450086 2.500122)
			(stroke
				(width 0.1524)
				(type default)
			)
			(layer "F.SilkS")
		)
		(fp_line
			(start -1.450086 2.500122)
			(end -0.94996 1.999996)
			(stroke
				(width 0.1524)
				(type default)
			)
			(layer "F.SilkS")
		)
		(fp_line
			(start 1.450086 2.500122)
			(end 19.6596 2.500122)
			(stroke
				(width 0.1524)
				(type default)
			)
			(layer "F.SilkS")
		)
		(fp_line
			(start 19.6596 2.500122)
			(end 19.6596 -4.064)
			(stroke
				(width 0.1524)
				(type default)
			)
			(layer "F.SilkS")
		)
		(fp_line
			(start -0.94996 1.999996)
			(end -0.94996 -2.55016)
			(stroke
				(width 0.1524)
				(type default)
			)
			(layer "F.SilkS")
		)
		(fp_line
			(start 0.94996 1.999996)
			(end 1.450086 2.500122)
			(stroke
				(width 0.1524)
				(type default)
			)
			(layer "F.SilkS")
		)
		(fp_line
			(start 0.94996 -2.55016)
			(end 0.94996 1.999996)
			(stroke
				(width 0.1524)
				(type default)
			)
			(layer "F.SilkS")
		)
		(fp_line
			(start -72.644 -2.7432)
			(end -72.644 -4.064)
			(stroke
				(width 0.1524)
				(type default)
			)
			(layer "F.SilkS")
		)
		(fp_line
			(start 12.6492 -2.7432)
			(end -72.644 -2.7432)
			(stroke
				(width 0.1524)
				(type default)
			)
			(layer "F.SilkS")
		)
		(fp_line
			(start 11.0617 -2.8321)
			(end 11.9634 -2.8321)
			(stroke
				(width 0.3302)
				(type default)
			)
			(layer "F.SilkS")
		)
		(fp_line
			(start -79.6544 -4.064)
			(end -79.6544 2.500122)
			(stroke
				(width 0.1524)
				(type default)
			)
			(layer "F.SilkS")
		)
		(fp_line
			(start -72.644 -4.064)
			(end -79.6544 -4.064)
			(stroke
				(width 0.1524)
				(type default)
			)
			(layer "F.SilkS")
		)
		(fp_line
			(start 12.6492 -4.064)
			(end 12.6492 -2.7432)
			(stroke
				(width 0.1524)
				(type default)
			)
			(layer "F.SilkS")
		)
		(fp_line
			(start 19.6596 -4.064)
			(end 12.6492 -4.064)
			(stroke
				(width 0.1524)
				(type default)
			)
			(layer "F.SilkS")
		)
		(fp_arc
			(start -0.94996 -2.55016)
			(mid 0 -3.50012)
			(end 0.94996 -2.55016)
			(stroke
				(width 0.1524)
				(type default)
			)
			(layer "F.SilkS")
		)
		(fp_poly
			(pts
				(xy 12.0904 -3.4544) (xy 10.8204 -3.4544) (xy 11.4554 -2.8194)
			)
			(stroke
				(width 0)
				(type default)
			)
			(fill yes)
			(layer "F.SilkS")
		)
		(fp_poly
			(pts
				(xy -74.4982 12.7508) (xy -74.4982 4.8006) (xy -79.4004 4.8006) (xy -79.4004 -3.81) (xy -72.898 -3.81)
				(xy -72.898 -1.6002) (xy 12.9032 -1.6002) (xy 12.9032 -3.81) (xy 19.4056 -3.81) (xy 19.4056 4.8006)
				(xy 14.5034 4.8006) (xy 14.5034 12.7508)
			)
			(stroke
				(width 0)
				(type default)
			)
			(fill no)
			(layer "B.CrtYd")
		)
		(fp_poly
			(pts
				(xy -75.0062 13.2588) (xy -75.0062 5.3086) (xy -79.9084 5.3086) (xy -79.9084 -4.318) (xy -72.39 -4.318)
				(xy -72.39 -2.9972) (xy 12.3952 -2.9972) (xy 12.3952 -4.318) (xy 19.9136 -4.318) (xy 19.9136 -0.00254)
				(xy 19.4056 -0.00254) (xy 19.4056 -3.81) (xy 12.9032 -3.81) (xy 12.9032 -1.6002) (xy -72.898 -1.6002)
				(xy -72.898 -3.81) (xy -79.4004 -3.81) (xy -79.4004 4.8006) (xy -74.4982 4.8006) (xy -74.4982 12.7508)
				(xy 14.5034 12.7508) (xy 14.5034 4.8006) (xy 19.4056 4.8006) (xy 19.4056 0.00254) (xy 19.9136 0.00254)
				(xy 19.9136 5.3086) (xy 15.0114 5.3086) (xy 15.0114 13.2588)
			)
			(stroke
				(width 0)
				(type default)
			)
			(fill no)
			(layer "B.CrtYd")
		)
		(fp_poly
			(pts
				(xy -74.4982 12.7508) (xy -74.4982 4.8006) (xy -79.4004 4.8006) (xy -79.4004 -3.81) (xy -72.898 -3.81)
				(xy -72.898 -1.6002) (xy 12.9032 -1.6002) (xy 12.9032 -3.81) (xy 19.4056 -3.81) (xy 19.4056 4.8006)
				(xy 14.5034 4.8006) (xy 14.5034 12.7508)
			)
			(stroke
				(width 0)
				(type default)
			)
			(fill no)
			(layer "F.CrtYd")
		)
		(fp_poly
			(pts
				(xy -75.0062 13.2588) (xy -75.0062 5.3086) (xy -79.9084 5.3086) (xy -79.9084 -4.318) (xy -72.39 -4.318)
				(xy -72.39 -2.9972) (xy 12.3952 -2.9972) (xy 12.3952 -4.318) (xy 19.9136 -4.318) (xy 19.9136 -0.00254)
				(xy 19.4056 -0.00254) (xy 19.4056 -3.81) (xy 12.9032 -3.81) (xy 12.9032 -1.6002) (xy -72.898 -1.6002)
				(xy -72.898 -3.81) (xy -79.4004 -3.81) (xy -79.4004 4.8006) (xy -74.4982 4.8006) (xy -74.4982 12.7508)
				(xy 14.5034 12.7508) (xy 14.5034 4.8006) (xy 19.4056 4.8006) (xy 19.4056 0.00254) (xy 19.9136 0.00254)
				(xy 19.9136 5.3086) (xy 15.0114 5.3086) (xy 15.0114 13.2588)
			)
			(stroke
				(width 0)
				(type default)
			)
			(fill no)
			(layer "F.CrtYd")
		)
		(fp_poly
			(pts
				(xy -75.0062 13.2588) (xy -75.0062 5.3086) (xy -79.9084 5.3086) (xy -79.9084 -4.318) (xy -72.39 -4.318)
				(xy -72.39 -2.9972) (xy 12.3952 -2.9972) (xy 12.3952 -4.318) (xy 19.9136 -4.318) (xy 19.9136 5.3086)
				(xy 15.0114 5.3086) (xy 15.0114 13.2588)
			)
			(stroke
				(width 0)
				(type default)
			)
			(fill no)
			(layer "B.Fab")
		)
		(fp_poly
			(pts
				(xy -75.0062 13.2588) (xy -75.0062 5.3086) (xy -79.9084 5.3086) (xy -79.9084 -4.318) (xy -72.39 -4.318)
				(xy -72.39 -2.9972) (xy 12.3952 -2.9972) (xy 12.3952 -4.318) (xy 19.9136 -4.318) (xy 19.9136 5.3086)
				(xy 15.0114 5.3086) (xy 15.0114 13.2588)
			)
			(stroke
				(width 0)
				(type default)
			)
			(fill no)
			(layer "F.Fab")
		)
		(fp_text user "Slit"
			(at -25.4 5.17525 270)
			(unlocked yes)
			(layer "F.SilkS")
			(effects
				(font
					(size 0.635 0.635)
					(thickness 0.1524)
				)
				(justify left)
			)
		)
		(fp_text user "02 Do not mirror"
			(at -31.939484 -3.691128 90)
			(unlocked yes)
			(layer "F.Fab")
			(effects
				(font
					(size 0.635 0.635)
					(thickness 0.1524)
				)
				(justify left)
			)
		)
		(pad "" np_thru_hole circle
			(at -76.300076 0 270)
			(size 0.254 0.254)
			(drill 2.3114)
			(layers "*.Cu" "*.Mask")
			(clearance 1.3843)
			(thermal_gap 1.3843)
		)
		(pad "" np_thru_hole circle
			(at 16.299942 0 270)
			(size 0.254 0.254)
			(drill 2.3114)
			(layers "*.Cu" "*.Mask")
			(clearance 1.3843)
			(thermal_gap 1.3843)
		)
		(pad "A1" smd rect
			(at 11.500104 -0.311404 270)
			(size 0.7112 3.6068)
			(drill
				(offset 0 -0.381)
			)
			(layers "F.Cu" "F.Mask" "F.Paste")
			(net "GND")
		)
		(pad "A2" smd rect
			(at 10.500106 -0.311404 270)
			(size 0.7112 3.6068)
			(drill
				(offset 0 -0.381)
			)
			(layers "F.Cu" "F.Mask" "F.Paste")
			(net "SAS2X28_B_HDD14_RX_+")
		)
		(pad "A3" smd rect
			(at 9.500108 -0.311404 270)
			(size 0.7112 3.6068)
			(drill
				(offset 0 -0.381)
			)
			(layers "F.Cu" "F.Mask" "F.Paste")
			(net "SAS2X28_B_HDD14_RX_-")
		)
		(pad "A4" smd rect
			(at 8.50011 -0.311404 270)
			(size 0.7112 3.6068)
			(drill
				(offset 0 -0.381)
			)
			(layers "F.Cu" "F.Mask" "F.Paste")
			(net "GND")
		)
		(pad "A5" smd rect
			(at 7.500112 -0.311404 270)
			(size 0.7112 3.6068)
			(drill
				(offset 0 -0.381)
			)
			(layers "F.Cu" "F.Mask" "F.Paste")
			(net "GND")
		)
		(pad "A6" smd rect
			(at 6.500114 -0.311404 270)
			(size 0.7112 3.6068)
			(drill
				(offset 0 -0.381)
			)
			(layers "F.Cu" "F.Mask" "F.Paste")
			(net "SAS2X28_B_HDD4_RX_+")
		)
		(pad "A7" smd rect
			(at 5.500116 -0.311404 270)
			(size 0.7112 3.6068)
			(drill
				(offset 0 -0.381)
			)
			(layers "F.Cu" "F.Mask" "F.Paste")
			(net "SAS2X28_B_HDD4_RX_-")
		)
		(pad "A8" smd rect
			(at 4.500118 -0.311404 270)
			(size 0.7112 3.6068)
			(drill
				(offset 0 -0.381)
			)
			(layers "F.Cu" "F.Mask" "F.Paste")
			(net "GND")
		)
		(pad "A9" smd rect
			(at 3.50012 -0.311404 270)
			(size 0.7112 3.6068)
			(drill
				(offset 0 -0.381)
			)
			(layers "F.Cu" "F.Mask" "F.Paste")
			(net "GND")
		)
		(pad "A10" smd rect
			(at 2.500122 -0.311404 270)
			(size 0.7112 3.6068)
			(drill
				(offset 0 -0.381)
			)
			(layers "F.Cu" "F.Mask" "F.Paste")
			(net "SAS2X28_B_HDD9_RX_+")
		)
		(pad "A11" smd rect
			(at 1.500124 -0.311404 270)
			(size 0.7112 3.6068)
			(drill
				(offset 0 -0.381)
			)
			(layers "F.Cu" "F.Mask" "F.Paste")
			(net "SAS2X28_B_HDD9_RX_-")
		)
		(pad "A12" smd rect
			(at -1.500124 -0.311404 270)
			(size 0.7112 3.6068)
			(drill
				(offset 0 -0.381)
			)
			(layers "F.Cu" "F.Mask" "F.Paste")
			(net "TRAY_ID")
		)
		(pad "A13" smd rect
			(at -2.500376 -0.311404 270)
			(size 0.7112 3.6068)
			(drill
				(offset 0 -0.381)
			)
			(layers "F.Cu" "F.Mask" "F.Paste")
			(net "GND")
		)
		(pad "A14" smd rect
			(at -3.500374 -0.311404 270)
			(size 0.7112 3.6068)
			(drill
				(offset 0 -0.381)
			)
			(layers "F.Cu" "F.Mask" "F.Paste")
			(net "SAS2X28_B_HDD3_RX_+")
		)
		(pad "A15" smd rect
			(at -4.500372 -0.311404 270)
			(size 0.7112 3.6068)
			(drill
				(offset 0 -0.381)
			)
			(layers "F.Cu" "F.Mask" "F.Paste")
			(net "SAS2X28_B_HDD3_RX_-")
		)
		(pad "A16" smd rect
			(at -5.50037 -0.311404 270)
			(size 0.7112 3.6068)
			(drill
				(offset 0 -0.381)
			)
			(layers "F.Cu" "F.Mask" "F.Paste")
			(net "GND")
		)
		(pad "A17" smd rect
			(at -6.500368 -0.311404 270)
			(size 0.7112 3.6068)
			(drill
				(offset 0 -0.381)
			)
			(layers "F.Cu" "F.Mask" "F.Paste")
			(net "GND")
		)
		(pad "A18" smd rect
			(at -7.500366 -0.311404 270)
			(size 0.7112 3.6068)
			(drill
				(offset 0 -0.381)
			)
			(layers "F.Cu" "F.Mask" "F.Paste")
			(net "SAS2X28_B_HDD2_RX_+")
		)
		(pad "A19" smd rect
			(at -8.500364 -0.311404 270)
			(size 0.7112 3.6068)
			(drill
				(offset 0 -0.381)
			)
			(layers "F.Cu" "F.Mask" "F.Paste")
			(net "SAS2X28_B_HDD2_RX_-")
		)
		(pad "A20" smd rect
			(at -9.500362 -0.311404 270)
			(size 0.7112 3.6068)
			(drill
				(offset 0 -0.381)
			)
			(layers "F.Cu" "F.Mask" "F.Paste")
			(net "GND")
		)
		(pad "A21" smd rect
			(at -10.50036 -0.311404 270)
			(size 0.7112 3.6068)
			(drill
				(offset 0 -0.381)
			)
			(layers "F.Cu" "F.Mask" "F.Paste")
			(net "GND")
		)
		(pad "A22" smd rect
			(at -11.500358 -0.311404 270)
			(size 0.7112 3.6068)
			(drill
				(offset 0 -0.381)
			)
			(layers "F.Cu" "F.Mask" "F.Paste")
			(net "SAS2X28_B_HDD8_RX_+")
		)
		(pad "A23" smd rect
			(at -12.500356 -0.311404 270)
			(size 0.7112 3.6068)
			(drill
				(offset 0 -0.381)
			)
			(layers "F.Cu" "F.Mask" "F.Paste")
			(net "SAS2X28_B_HDD8_RX_-")
		)
		(pad "A24" smd rect
			(at -13.500354 -0.311404 270)
			(size 0.7112 3.6068)
			(drill
				(offset 0 -0.381)
			)
			(layers "F.Cu" "F.Mask" "F.Paste")
			(net "GND")
		)
		(pad "A25" smd rect
			(at -14.500352 -0.311404 270)
			(size 0.7112 3.6068)
			(drill
				(offset 0 -0.381)
			)
			(layers "F.Cu" "F.Mask" "F.Paste")
			(net "GND")
		)
		(pad "A26" smd rect
			(at -15.50035 -0.311404 270)
			(size 0.7112 3.6068)
			(drill
				(offset 0 -0.381)
			)
			(layers "F.Cu" "F.Mask" "F.Paste")
			(net "SAS2X28_B_HDD7_RX_+")
		)
		(pad "A27" smd rect
			(at -16.500348 -0.311404 270)
			(size 0.7112 3.6068)
			(drill
				(offset 0 -0.381)
			)
			(layers "F.Cu" "F.Mask" "F.Paste")
			(net "SAS2X28_B_HDD7_RX_-")
		)
		(pad "A28" smd rect
			(at -17.500346 -0.311404 270)
			(size 0.7112 3.6068)
			(drill
				(offset 0 -0.381)
			)
			(layers "F.Cu" "F.Mask" "F.Paste")
			(net "GND")
		)
		(pad "A29" smd rect
			(at -18.500344 -0.311404 270)
			(size 0.7112 3.6068)
			(drill
				(offset 0 -0.381)
			)
			(layers "F.Cu" "F.Mask" "F.Paste")
			(net "GND")
		)
		(pad "A30" smd rect
			(at -19.500342 -0.311404 270)
			(size 0.7112 3.6068)
			(drill
				(offset 0 -0.381)
			)
			(layers "F.Cu" "F.Mask" "F.Paste")
			(net "SAS2X28_B_HDD1_RX_+")
		)
		(pad "A31" smd rect
			(at -20.50034 -0.311404 270)
			(size 0.7112 3.6068)
			(drill
				(offset 0 -0.381)
			)
			(layers "F.Cu" "F.Mask" "F.Paste")
			(net "SAS2X28_B_HDD1_RX_-")
		)
		(pad "A32" smd rect
			(at -21.500338 -0.311404 270)
			(size 0.7112 3.6068)
			(drill
				(offset 0 -0.381)
			)
			(layers "F.Cu" "F.Mask" "F.Paste")
			(net "GND")
		)
		(pad "A33" smd rect
			(at -22.500336 -0.311404 270)
			(size 0.7112 3.6068)
			(drill
				(offset 0 -0.381)
			)
			(layers "F.Cu" "F.Mask" "F.Paste")
			(net "GND")
		)
		(pad "A34" smd rect
			(at -23.500334 -0.311404 270)
			(size 0.7112 3.6068)
			(drill
				(offset 0 -0.381)
			)
			(layers "F.Cu" "F.Mask" "F.Paste")
			(net "SAS2X28_B_HDD0_RX_+")
		)
		(pad "A35" smd rect
			(at -24.500332 -0.311404 270)
			(size 0.7112 3.6068)
			(drill
				(offset 0 -0.381)
			)
			(layers "F.Cu" "F.Mask" "F.Paste")
			(net "SAS2X28_B_HDD0_RX_-")
		)
		(pad "A36" smd rect
			(at -25.50033 -0.311404 270)
			(size 0.7112 3.6068)
			(drill
				(offset 0 -0.381)
			)
			(layers "F.Cu" "F.Mask" "F.Paste")
			(net "GND")
		)
		(pad "A37" smd rect
			(at -26.500328 -0.311404 270)
			(size 0.7112 3.6068)
			(drill
				(offset 0 -0.381)
			)
			(layers "F.Cu" "F.Mask" "F.Paste")
			(net "GND")
		)
		(pad "A38" smd rect
			(at -27.500326 -0.311404 270)
			(size 0.7112 3.6068)
			(drill
				(offset 0 -0.381)
			)
			(layers "F.Cu" "F.Mask" "F.Paste")
			(net "SAS2X28_B_HDD13_RX_+")
		)
		(pad "A39" smd rect
			(at -28.500324 -0.311404 270)
			(size 0.7112 3.6068)
			(drill
				(offset 0 -0.381)
			)
			(layers "F.Cu" "F.Mask" "F.Paste")
			(net "SAS2X28_B_HDD13_RX_-")
		)
		(pad "A40" smd rect
			(at -29.500322 -0.311404 270)
			(size 0.7112 3.6068)
			(drill
				(offset 0 -0.381)
			)
			(layers "F.Cu" "F.Mask" "F.Paste")
			(net "GND")
		)
		(pad "A41" smd rect
			(at -30.50032 -0.311404 270)
			(size 0.7112 3.6068)
			(drill
				(offset 0 -0.381)
			)
			(layers "F.Cu" "F.Mask" "F.Paste")
			(net "SD_LATCH_RELEASE")
		)
		(pad "A42" smd rect
			(at -31.500318 -0.311404 270)
			(size 0.7112 3.6068)
			(drill
				(offset 0 -0.381)
			)
			(layers "F.Cu" "F.Mask" "F.Paste")
			(net "SAS2X28_B_HDD4_FLT")
		)
		(pad "A43" smd rect
			(at -32.500316 -0.311404 270)
			(size 0.7112 3.6068)
			(drill
				(offset 0 -0.381)
			)
			(layers "F.Cu" "F.Mask" "F.Paste")
			(net "SAS2X28_B_HDD14_FLT")
		)
		(pad "A44" smd rect
			(at -33.500314 -0.311404 270)
			(size 0.7112 3.6068)
			(drill
				(offset 0 -0.381)
			)
			(layers "F.Cu" "F.Mask" "F.Paste")
			(net "SAS2X28_B_HDD9_FLT")
		)
		(pad "A45" smd rect
			(at -34.500312 -0.311404 270)
			(size 0.7112 3.6068)
			(drill
				(offset 0 -0.381)
			)
			(layers "F.Cu" "F.Mask" "F.Paste")
			(net "SAS2X28_B_HDD3_FLT")
		)
		(pad "A46" smd rect
			(at -35.50031 -0.311404 270)
			(size 0.7112 3.6068)
			(drill
				(offset 0 -0.381)
			)
			(layers "F.Cu" "F.Mask" "F.Paste")
			(net "SAS2X28_B_HDD2_FLT")
		)
		(pad "A47" smd rect
			(at -36.500308 -0.311404 270)
			(size 0.7112 3.6068)
			(drill
				(offset 0 -0.381)
			)
			(layers "F.Cu" "F.Mask" "F.Paste")
			(net "SAS2X28_B_HDD8_FLT")
		)
		(pad "A48" smd rect
			(at -37.500306 -0.311404 270)
			(size 0.7112 3.6068)
			(drill
				(offset 0 -0.381)
			)
			(layers "F.Cu" "F.Mask" "F.Paste")
			(net "SAS2X28_B_HDD7_FLT")
		)
		(pad "A49" smd rect
			(at -38.500304 -0.311404 270)
			(size 0.7112 3.6068)
			(drill
				(offset 0 -0.381)
			)
			(layers "F.Cu" "F.Mask" "F.Paste")
			(net "SAS2X28_B_HDD1_FLT")
		)
		(pad "A50" smd rect
			(at -39.500302 -0.311404 270)
			(size 0.7112 3.6068)
			(drill
				(offset 0 -0.381)
			)
			(layers "F.Cu" "F.Mask" "F.Paste")
			(net "SAS2X28_B_HDD0_FLT")
		)
		(pad "A51" smd rect
			(at -40.5003 -0.311404 270)
			(size 0.7112 3.6068)
			(drill
				(offset 0 -0.381)
			)
			(layers "F.Cu" "F.Mask" "F.Paste")
			(net "GND")
		)
		(pad "A52" smd rect
			(at -41.500298 -0.311404 270)
			(size 0.7112 3.6068)
			(drill
				(offset 0 -0.381)
			)
			(layers "F.Cu" "F.Mask" "F.Paste")
			(net "SAS2X28_B_HDD6_RX_+")
		)
		(pad "A53" smd rect
			(at -42.500296 -0.311404 270)
			(size 0.7112 3.6068)
			(drill
				(offset 0 -0.381)
			)
			(layers "F.Cu" "F.Mask" "F.Paste")
			(net "SAS2X28_B_HDD6_RX_-")
		)
		(pad "A54" smd rect
			(at -43.500294 -0.311404 270)
			(size 0.7112 3.6068)
			(drill
				(offset 0 -0.381)
			)
			(layers "F.Cu" "F.Mask" "F.Paste")
			(net "GND")
		)
		(pad "A55" smd rect
			(at -44.500292 -0.311404 270)
			(size 0.7112 3.6068)
			(drill
				(offset 0 -0.381)
			)
			(layers "F.Cu" "F.Mask" "F.Paste")
			(net "I2C_C_SCL_DAMP_B")
		)
		(pad "A56" smd rect
			(at -45.50029 -0.311404 270)
			(size 0.7112 3.6068)
			(drill
				(offset 0 -0.381)
			)
			(layers "F.Cu" "F.Mask" "F.Paste")
			(net "I2C_C_SDA_DAMP_B")
		)
		(pad "A57" smd rect
			(at -46.500288 -0.311404 270)
			(size 0.7112 3.6068)
			(drill
				(offset 0 -0.381)
			)
			(layers "F.Cu" "F.Mask" "F.Paste")
			(net "I2C_D_SCL_DAMP_B")
		)
		(pad "A58" smd rect
			(at -47.500286 -0.311404 270)
			(size 0.7112 3.6068)
			(drill
				(offset 0 -0.381)
			)
			(layers "F.Cu" "F.Mask" "F.Paste")
			(net "I2C_D_SDA_DAMP_B")
		)
		(pad "A59" smd rect
			(at -48.500284 -0.311404 270)
			(size 0.7112 3.6068)
			(drill
				(offset 0 -0.381)
			)
			(layers "F.Cu" "F.Mask" "F.Paste")
			(net "GND")
		)
		(pad "A60" smd rect
			(at -49.500282 -0.311404 270)
			(size 0.7112 3.6068)
			(drill
				(offset 0 -0.381)
			)
			(layers "F.Cu" "F.Mask" "F.Paste")
			(net "SAS2X28_B_HDD5_RX_+")
		)
		(pad "A61" smd rect
			(at -50.50028 -0.311404 270)
			(size 0.7112 3.6068)
			(drill
				(offset 0 -0.381)
			)
			(layers "F.Cu" "F.Mask" "F.Paste")
			(net "SAS2X28_B_HDD5_RX_-")
		)
		(pad "A62" smd rect
			(at -51.500278 -0.311404 270)
			(size 0.7112 3.6068)
			(drill
				(offset 0 -0.381)
			)
			(layers "F.Cu" "F.Mask" "F.Paste")
			(net "GND")
		)
		(pad "A63" smd rect
			(at -52.500276 -0.311404 270)
			(size 0.7112 3.6068)
			(drill
				(offset 0 -0.381)
			)
			(layers "F.Cu" "F.Mask" "F.Paste")
			(net "GND")
		)
		(pad "A64" smd rect
			(at -53.500274 -0.311404 270)
			(size 0.7112 3.6068)
			(drill
				(offset 0 -0.381)
			)
			(layers "F.Cu" "F.Mask" "F.Paste")
			(net "SAS2X28_B_HDD10_RX_+")
		)
		(pad "A65" smd rect
			(at -54.500272 -0.311404 270)
			(size 0.7112 3.6068)
			(drill
				(offset 0 -0.381)
			)
			(layers "F.Cu" "F.Mask" "F.Paste")
			(net "SAS2X28_B_HDD10_RX_-")
		)
		(pad "A66" smd rect
			(at -55.50027 -0.311404 270)
			(size 0.7112 3.6068)
			(drill
				(offset 0 -0.381)
			)
			(layers "F.Cu" "F.Mask" "F.Paste")
			(net "GND")
		)
		(pad "A67" smd rect
			(at -56.500268 -0.311404 270)
			(size 0.7112 3.6068)
			(drill
				(offset 0 -0.381)
			)
			(layers "F.Cu" "F.Mask" "F.Paste")
			(net "GND")
		)
		(pad "A68" smd rect
			(at -57.500266 -0.311404 270)
			(size 0.7112 3.6068)
			(drill
				(offset 0 -0.381)
			)
			(layers "F.Cu" "F.Mask" "F.Paste")
			(net "SAS2X28_B_HDD11_RX_+")
		)
		(pad "A69" smd rect
			(at -58.500264 -0.311404 270)
			(size 0.7112 3.6068)
			(drill
				(offset 0 -0.381)
			)
			(layers "F.Cu" "F.Mask" "F.Paste")
			(net "SAS2X28_B_HDD11_RX_-")
		)
		(pad "A70" smd rect
			(at -59.500262 -0.311404 270)
			(size 0.7112 3.6068)
			(drill
				(offset 0 -0.381)
			)
			(layers "F.Cu" "F.Mask" "F.Paste")
			(net "GND")
		)
		(pad "A71" smd rect
			(at -60.50026 -0.311404 270)
			(size 0.7112 3.6068)
			(drill
				(offset 0 -0.381)
			)
			(layers "F.Cu" "F.Mask" "F.Paste")
			(net "GND")
		)
		(pad "A72" smd rect
			(at -61.500258 -0.311404 270)
			(size 0.7112 3.6068)
			(drill
				(offset 0 -0.381)
			)
			(layers "F.Cu" "F.Mask" "F.Paste")
			(net "SAS2X28_B_HDD12_RX_+")
		)
		(pad "A73" smd rect
			(at -62.500256 -0.311404 270)
			(size 0.7112 3.6068)
			(drill
				(offset 0 -0.381)
			)
			(layers "F.Cu" "F.Mask" "F.Paste")
			(net "SAS2X28_B_HDD12_RX_-")
		)
		(pad "A74" smd rect
			(at -63.500254 -0.311404 270)
			(size 0.7112 3.6068)
			(drill
				(offset 0 -0.381)
			)
			(layers "F.Cu" "F.Mask" "F.Paste")
			(net "GND")
		)
		(pad "A75" smd rect
			(at -64.500252 -0.311404 270)
			(size 0.7112 3.6068)
			(drill
				(offset 0 -0.381)
			)
			(layers "F.Cu" "F.Mask" "F.Paste")
			(net "GND")
		)
		(pad "A76" smd rect
			(at -65.50025 -0.311404 270)
			(size 0.7112 3.6068)
			(drill
				(offset 0 -0.381)
			)
			(layers "F.Cu" "F.Mask" "F.Paste")
			(net "SEB_AB_RX+")
		)
		(pad "A77" smd rect
			(at -66.500248 -0.311404 270)
			(size 0.7112 3.6068)
			(drill
				(offset 0 -0.381)
			)
			(layers "F.Cu" "F.Mask" "F.Paste")
			(net "SEB_AB_RX-")
		)
		(pad "A78" smd rect
			(at -67.500246 -0.311404 270)
			(size 0.7112 3.6068)
			(drill
				(offset 0 -0.381)
			)
			(layers "F.Cu" "F.Mask" "F.Paste")
			(net "GND")
		)
		(pad "A79" smd rect
			(at -68.500244 -0.311404 270)
			(size 0.7112 3.6068)
			(drill
				(offset 0 -0.381)
			)
			(layers "F.Cu" "F.Mask" "F.Paste")
			(net "PEER_1B&2B_HB")
		)
		(pad "A80" smd rect
			(at -69.500242 -0.311404 270)
			(size 0.7112 3.6068)
			(drill
				(offset 0 -0.381)
			)
			(layers "F.Cu" "F.Mask" "F.Paste")
			(net "P12V")
		)
		(pad "A81" smd rect
			(at -70.50024 -0.311404 270)
			(size 0.7112 3.6068)
			(drill
				(offset 0 -0.381)
			)
			(layers "F.Cu" "F.Mask" "F.Paste")
			(net "P12V")
		)
		(pad "A82" smd rect
			(at -71.500238 -0.311404 270)
			(size 0.7112 3.6068)
			(drill
				(offset 0 -0.381)
			)
			(layers "F.Cu" "F.Mask" "F.Paste")
			(net "P12V")
		)
		(pad "B1" smd rect
			(at 11.500104 -0.692404 270)
			(size 0.7112 3.6068)
			(layers "F.Cu" "F.Mask" "F.Paste")
			(net "SAS2X28_B_PRSNT15")
		)
		(pad "B2" smd rect
			(at 10.500106 -0.692404 270)
			(size 0.7112 3.6068)
			(layers "F.Cu" "F.Mask" "F.Paste")
			(net "FCB_HW_REV")
		)
		(pad "B3" smd rect
			(at 9.500108 -0.692404 270)
			(size 0.7112 3.6068)
			(layers "F.Cu" "F.Mask" "F.Paste")
			(net "GND")
		)
		(pad "B4" smd rect
			(at 8.50011 -0.692404 270)
			(size 0.7112 3.6068)
			(layers "F.Cu" "F.Mask" "F.Paste")
			(net "SAS2X28_B_HDD14_TX_+")
		)
		(pad "B5" smd rect
			(at 7.500112 -0.692404 270)
			(size 0.7112 3.6068)
			(layers "F.Cu" "F.Mask" "F.Paste")
			(net "SAS2X28_B_HDD14_TX_-")
		)
		(pad "B6" smd rect
			(at 6.500114 -0.692404 270)
			(size 0.7112 3.6068)
			(layers "F.Cu" "F.Mask" "F.Paste")
			(net "GND")
		)
		(pad "B7" smd rect
			(at 5.500116 -0.692404 270)
			(size 0.7112 3.6068)
			(layers "F.Cu" "F.Mask" "F.Paste")
			(net "GND")
		)
		(pad "B8" smd rect
			(at 4.500118 -0.692404 270)
			(size 0.7112 3.6068)
			(layers "F.Cu" "F.Mask" "F.Paste")
			(net "SAS2X28_B_HDD4_TX_+")
		)
		(pad "B9" smd rect
			(at 3.50012 -0.692404 270)
			(size 0.7112 3.6068)
			(layers "F.Cu" "F.Mask" "F.Paste")
			(net "SAS2X28_B_HDD4_TX_-")
		)
		(pad "B10" smd rect
			(at 2.500122 -0.692404 270)
			(size 0.7112 3.6068)
			(layers "F.Cu" "F.Mask" "F.Paste")
			(net "GND")
		)
		(pad "B11" smd rect
			(at 1.500124 -0.692404 270)
			(size 0.7112 3.6068)
			(layers "F.Cu" "F.Mask" "F.Paste")
			(net "DPB_HW_REV")
		)
		(pad "B12" smd rect
			(at -1.500124 -0.692404 270)
			(size 0.7112 3.6068)
			(layers "F.Cu" "F.Mask" "F.Paste")
			(net "SAS2X28_B_HDD9_TX_+")
		)
		(pad "B13" smd rect
			(at -2.500376 -0.692404 270)
			(size 0.7112 3.6068)
			(layers "F.Cu" "F.Mask" "F.Paste")
			(net "SAS2X28_B_HDD9_TX_-")
		)
		(pad "B14" smd rect
			(at -3.500374 -0.692404 270)
			(size 0.7112 3.6068)
			(layers "F.Cu" "F.Mask" "F.Paste")
			(net "GND")
		)
		(pad "B15" smd rect
			(at -4.500372 -0.692404 270)
			(size 0.7112 3.6068)
			(layers "F.Cu" "F.Mask" "F.Paste")
			(net "GND")
		)
		(pad "B16" smd rect
			(at -5.50037 -0.692404 270)
			(size 0.7112 3.6068)
			(layers "F.Cu" "F.Mask" "F.Paste")
			(net "SAS2X28_B_HDD3_TX_+")
		)
		(pad "B17" smd rect
			(at -6.500368 -0.692404 270)
			(size 0.7112 3.6068)
			(layers "F.Cu" "F.Mask" "F.Paste")
			(net "SAS2X28_B_HDD3_TX_-")
		)
		(pad "B18" smd rect
			(at -7.500366 -0.692404 270)
			(size 0.7112 3.6068)
			(layers "F.Cu" "F.Mask" "F.Paste")
			(net "GND")
		)
		(pad "B19" smd rect
			(at -8.500364 -0.692404 270)
			(size 0.7112 3.6068)
			(layers "F.Cu" "F.Mask" "F.Paste")
			(net "GND")
		)
		(pad "B20" smd rect
			(at -9.500362 -0.692404 270)
			(size 0.7112 3.6068)
			(layers "F.Cu" "F.Mask" "F.Paste")
			(net "SAS2X28_B_HDD2_TX_+")
		)
		(pad "B21" smd rect
			(at -10.50036 -0.692404 270)
			(size 0.7112 3.6068)
			(layers "F.Cu" "F.Mask" "F.Paste")
			(net "SAS2X28_B_HDD2_TX_-")
		)
		(pad "B22" smd rect
			(at -11.500358 -0.692404 270)
			(size 0.7112 3.6068)
			(layers "F.Cu" "F.Mask" "F.Paste")
			(net "GND")
		)
		(pad "B23" smd rect
			(at -12.500356 -0.692404 270)
			(size 0.7112 3.6068)
			(layers "F.Cu" "F.Mask" "F.Paste")
			(net "GND")
		)
		(pad "B24" smd rect
			(at -13.500354 -0.692404 270)
			(size 0.7112 3.6068)
			(layers "F.Cu" "F.Mask" "F.Paste")
			(net "SAS2X28_B_HDD8_TX_+")
		)
		(pad "B25" smd rect
			(at -14.500352 -0.692404 270)
			(size 0.7112 3.6068)
			(layers "F.Cu" "F.Mask" "F.Paste")
			(net "SAS2X28_B_HDD8_TX_-")
		)
		(pad "B26" smd rect
			(at -15.50035 -0.692404 270)
			(size 0.7112 3.6068)
			(layers "F.Cu" "F.Mask" "F.Paste")
			(net "GND")
		)
		(pad "B27" smd rect
			(at -16.500348 -0.692404 270)
			(size 0.7112 3.6068)
			(layers "F.Cu" "F.Mask" "F.Paste")
			(net "GND")
		)
		(pad "B28" smd rect
			(at -17.500346 -0.692404 270)
			(size 0.7112 3.6068)
			(layers "F.Cu" "F.Mask" "F.Paste")
			(net "SAS2X28_B_HDD7_TX_+")
		)
		(pad "B29" smd rect
			(at -18.500344 -0.692404 270)
			(size 0.7112 3.6068)
			(layers "F.Cu" "F.Mask" "F.Paste")
			(net "SAS2X28_B_HDD7_TX_-")
		)
		(pad "B30" smd rect
			(at -19.500342 -0.692404 270)
			(size 0.7112 3.6068)
			(layers "F.Cu" "F.Mask" "F.Paste")
			(net "GND")
		)
		(pad "B31" smd rect
			(at -20.50034 -0.692404 270)
			(size 0.7112 3.6068)
			(layers "F.Cu" "F.Mask" "F.Paste")
			(net "GND")
		)
		(pad "B32" smd rect
			(at -21.500338 -0.692404 270)
			(size 0.7112 3.6068)
			(layers "F.Cu" "F.Mask" "F.Paste")
			(net "SAS2X28_B_HDD1_TX_+")
		)
		(pad "B33" smd rect
			(at -22.500336 -0.692404 270)
			(size 0.7112 3.6068)
			(layers "F.Cu" "F.Mask" "F.Paste")
			(net "SAS2X28_B_HDD1_TX_-")
		)
		(pad "B34" smd rect
			(at -23.500334 -0.692404 270)
			(size 0.7112 3.6068)
			(layers "F.Cu" "F.Mask" "F.Paste")
			(net "GND")
		)
		(pad "B35" smd rect
			(at -24.500332 -0.692404 270)
			(size 0.7112 3.6068)
			(layers "F.Cu" "F.Mask" "F.Paste")
			(net "GND")
		)
		(pad "B36" smd rect
			(at -25.50033 -0.692404 270)
			(size 0.7112 3.6068)
			(layers "F.Cu" "F.Mask" "F.Paste")
			(net "SAS2X28_B_HDD0_TX_+")
		)
		(pad "B37" smd rect
			(at -26.500328 -0.692404 270)
			(size 0.7112 3.6068)
			(layers "F.Cu" "F.Mask" "F.Paste")
			(net "SAS2X28_B_HDD0_TX_-")
		)
		(pad "B38" smd rect
			(at -27.500326 -0.692404 270)
			(size 0.7112 3.6068)
			(layers "F.Cu" "F.Mask" "F.Paste")
			(net "GND")
		)
		(pad "B39" smd rect
			(at -28.500324 -0.692404 270)
			(size 0.7112 3.6068)
			(layers "F.Cu" "F.Mask" "F.Paste")
			(net "GND")
		)
		(pad "B40" smd rect
			(at -29.500322 -0.692404 270)
			(size 0.7112 3.6068)
			(layers "F.Cu" "F.Mask" "F.Paste")
			(net "SAS2X28_B_HDD13_TX_+")
		)
		(pad "B41" smd rect
			(at -30.50032 -0.692404 270)
			(size 0.7112 3.6068)
			(layers "F.Cu" "F.Mask" "F.Paste")
			(net "SAS2X28_B_HDD13_TX_-")
		)
		(pad "B42" smd rect
			(at -31.500318 -0.692404 270)
			(size 0.7112 3.6068)
			(layers "F.Cu" "F.Mask" "F.Paste")
			(net "GND")
		)
		(pad "B43" smd rect
			(at -32.500316 -0.692404 270)
			(size 0.7112 3.6068)
			(layers "F.Cu" "F.Mask" "F.Paste")
			(net "SAS2X28_B_HDD13_FLT")
		)
		(pad "B44" smd rect
			(at -33.500314 -0.692404 270)
			(size 0.7112 3.6068)
			(layers "F.Cu" "F.Mask" "F.Paste")
			(net "SAS2X28_B_HDD6_FLT")
		)
		(pad "B45" smd rect
			(at -34.500312 -0.692404 270)
			(size 0.7112 3.6068)
			(layers "F.Cu" "F.Mask" "F.Paste")
			(net "SAS2X28_B_HDD5_FLT")
		)
		(pad "B46" smd rect
			(at -35.50031 -0.692404 270)
			(size 0.7112 3.6068)
			(layers "F.Cu" "F.Mask" "F.Paste")
			(net "SAS2X28_B_HDD10_FLT")
		)
		(pad "B47" smd rect
			(at -36.500308 -0.692404 270)
			(size 0.7112 3.6068)
			(layers "F.Cu" "F.Mask" "F.Paste")
			(net "SAS2X28_B_HDD11_FLT")
		)
		(pad "B48" smd rect
			(at -37.500306 -0.692404 270)
			(size 0.7112 3.6068)
			(layers "F.Cu" "F.Mask" "F.Paste")
			(net "GND")
		)
		(pad "B49" smd rect
			(at -38.500304 -0.692404 270)
			(size 0.7112 3.6068)
			(layers "F.Cu" "F.Mask" "F.Paste")
			(net "SAS2X28_B_HDD6_TX_+")
		)
		(pad "B50" smd rect
			(at -39.500302 -0.692404 270)
			(size 0.7112 3.6068)
			(layers "F.Cu" "F.Mask" "F.Paste")
			(net "SAS2X28_B_HDD6_TX_-")
		)
		(pad "B51" smd rect
			(at -40.5003 -0.692404 270)
			(size 0.7112 3.6068)
			(layers "F.Cu" "F.Mask" "F.Paste")
			(net "GND")
		)
		(pad "B52" smd rect
			(at -41.500298 -0.692404 270)
			(size 0.7112 3.6068)
			(layers "F.Cu" "F.Mask" "F.Paste")
			(net "SAS2X28_B_HDD12_FLT")
		)
		(pad "B53" smd rect
			(at -42.500296 -0.692404 270)
			(size 0.7112 3.6068)
			(layers "F.Cu" "F.Mask" "F.Paste")
			(net "SAS2X28_B_HDD15_FLT")
		)
		(pad "B54" smd rect
			(at -43.500294 -0.692404 270)
			(size 0.7112 3.6068)
			(layers "F.Cu" "F.Mask" "F.Paste")
			(net "SELF_1B&2B_HB")
		)
		(pad "B55" smd rect
			(at -44.500292 -0.692404 270)
			(size 0.7112 3.6068)
			(layers "F.Cu" "F.Mask" "F.Paste")
			(net "HB_EXP_B_INPUT")
		)
		(pad "B56" smd rect
			(at -45.50029 -0.692404 270)
			(size 0.7112 3.6068)
			(layers "F.Cu" "F.Mask" "F.Paste")
			(net "I2C_B_SCL_DAMP_B")
		)
		(pad "B57" smd rect
			(at -46.500288 -0.692404 270)
			(size 0.7112 3.6068)
			(layers "F.Cu" "F.Mask" "F.Paste")
			(net "I2C_B_SDA_DAMP_B")
		)
		(pad "B58" smd rect
			(at -47.500286 -0.692404 270)
			(size 0.7112 3.6068)
			(layers "F.Cu" "F.Mask" "F.Paste")
			(net "TEMP_SENSOR_B_ADDR0&ID")
		)
		(pad "B59" smd rect
			(at -48.500284 -0.692404 270)
			(size 0.7112 3.6068)
			(layers "F.Cu" "F.Mask" "F.Paste")
			(net "PWM_EXP_B")
		)
		(pad "B60" smd rect
			(at -49.500282 -0.692404 270)
			(size 0.7112 3.6068)
			(layers "F.Cu" "F.Mask" "F.Paste")
			(net "PEER_1A&2A_HB")
		)
		(pad "B61" smd rect
			(at -50.50028 -0.692404 270)
			(size 0.7112 3.6068)
			(layers "F.Cu" "F.Mask" "F.Paste")
			(net "GND")
		)
		(pad "B62" smd rect
			(at -51.500278 -0.692404 270)
			(size 0.7112 3.6068)
			(layers "F.Cu" "F.Mask" "F.Paste")
			(net "SAS2X28_B_HDD5_TX_+")
		)
		(pad "B63" smd rect
			(at -52.500276 -0.692404 270)
			(size 0.7112 3.6068)
			(layers "F.Cu" "F.Mask" "F.Paste")
			(net "SAS2X28_B_HDD5_TX_-")
		)
		(pad "B64" smd rect
			(at -53.500274 -0.692404 270)
			(size 0.7112 3.6068)
			(layers "F.Cu" "F.Mask" "F.Paste")
			(net "GND")
		)
		(pad "B65" smd rect
			(at -54.500272 -0.692404 270)
			(size 0.7112 3.6068)
			(layers "F.Cu" "F.Mask" "F.Paste")
			(net "GND")
		)
		(pad "B66" smd rect
			(at -55.50027 -0.692404 270)
			(size 0.7112 3.6068)
			(layers "F.Cu" "F.Mask" "F.Paste")
			(net "SAS2X28_B_HDD10_TX_+")
		)
		(pad "B67" smd rect
			(at -56.500268 -0.692404 270)
			(size 0.7112 3.6068)
			(layers "F.Cu" "F.Mask" "F.Paste")
			(net "SAS2X28_B_HDD10_TX_-")
		)
		(pad "B68" smd rect
			(at -57.500266 -0.692404 270)
			(size 0.7112 3.6068)
			(layers "F.Cu" "F.Mask" "F.Paste")
			(net "GND")
		)
		(pad "B69" smd rect
			(at -58.500264 -0.692404 270)
			(size 0.7112 3.6068)
			(layers "F.Cu" "F.Mask" "F.Paste")
			(net "GND")
		)
		(pad "B70" smd rect
			(at -59.500262 -0.692404 270)
			(size 0.7112 3.6068)
			(layers "F.Cu" "F.Mask" "F.Paste")
			(net "SAS2X28_B_HDD11_TX_+")
		)
		(pad "B71" smd rect
			(at -60.50026 -0.692404 270)
			(size 0.7112 3.6068)
			(layers "F.Cu" "F.Mask" "F.Paste")
			(net "SAS2X28_B_HDD11_TX_-")
		)
		(pad "B72" smd rect
			(at -61.500258 -0.692404 270)
			(size 0.7112 3.6068)
			(layers "F.Cu" "F.Mask" "F.Paste")
			(net "GND")
		)
		(pad "B73" smd rect
			(at -62.500256 -0.692404 270)
			(size 0.7112 3.6068)
			(layers "F.Cu" "F.Mask" "F.Paste")
			(net "GND")
		)
		(pad "B74" smd rect
			(at -63.500254 -0.692404 270)
			(size 0.7112 3.6068)
			(layers "F.Cu" "F.Mask" "F.Paste")
			(net "SAS2X28_B_HDD12_TX_+")
		)
		(pad "B75" smd rect
			(at -64.500252 -0.692404 270)
			(size 0.7112 3.6068)
			(layers "F.Cu" "F.Mask" "F.Paste")
			(net "SAS2X28_B_HDD12_TX_-")
		)
		(pad "B76" smd rect
			(at -65.50025 -0.692404 270)
			(size 0.7112 3.6068)
			(layers "F.Cu" "F.Mask" "F.Paste")
			(net "GND")
		)
		(pad "B77" smd rect
			(at -66.500248 -0.692404 270)
			(size 0.7112 3.6068)
			(layers "F.Cu" "F.Mask" "F.Paste")
			(net "GND")
		)
		(pad "B78" smd rect
			(at -67.500246 -0.692404 270)
			(size 0.7112 3.6068)
			(layers "F.Cu" "F.Mask" "F.Paste")
			(net "SEB_BA_TX+")
		)
		(pad "B79" smd rect
			(at -68.500244 -0.692404 270)
			(size 0.7112 3.6068)
			(layers "F.Cu" "F.Mask" "F.Paste")
			(net "SEB_BA_TX-")
		)
		(pad "B80" smd rect
			(at -69.500242 -0.692404 270)
			(size 0.7112 3.6068)
			(layers "F.Cu" "F.Mask" "F.Paste")
			(net "GND")
		)
		(pad "B81" smd rect
			(at -70.50024 -0.692404 270)
			(size 0.7112 3.6068)
			(layers "F.Cu" "F.Mask" "F.Paste")
			(net "GND")
		)
		(pad "B82" smd rect
			(at -71.500238 -0.692404 270)
			(size 0.7112 3.6068)
			(layers "F.Cu" "F.Mask" "F.Paste")
			(net "GND")
		)
		(zone
			(layers "F.Cu" "B.Cu" "In1.Cu" "In2.Cu" "In3.Cu" "In4.Cu" "In5.Cu" "In6.Cu")
			(hatch none 0.5)
			(connect_pads
				(clearance 0)
			)
			(min_thickness 0.25)
			(keepout
				(tracks not_allowed)
				(vias allowed)
				(pads allowed)
				(copperpour not_allowed)
				(footprints allowed)
			)
			(placement
				(enabled no)
				(sheetname "")
			)
			(fill
				(thermal_gap 0.5)
				(thermal_bridge_width 0.5)
				(island_removal_mode 0)
			)
			(polygon
				(pts
					(arc
						(start 3.960622 -182.298594)
						(mid 1.039622 -182.298594)
						(end 3.960622 -182.298594)
					)
				)
			)
		)
		(zone
			(layers "F.Cu" "B.Cu" "In1.Cu" "In2.Cu" "In3.Cu" "In4.Cu" "In5.Cu" "In6.Cu")
			(hatch none 0.5)
			(connect_pads
				(clearance 0)
			)
			(min_thickness 0.25)
			(keepout
				(tracks not_allowed)
				(vias allowed)
				(pads allowed)
				(copperpour not_allowed)
				(footprints allowed)
			)
			(placement
				(enabled no)
				(sheetname "")
			)
			(fill
				(thermal_gap 0.5)
				(thermal_bridge_width 0.5)
				(island_removal_mode 0)
			)
			(polygon
				(pts
					(arc
						(start 3.960622 -89.698576)
						(mid 1.039622 -89.698576)
						(end 3.960622 -89.698576)
					)
				)
			)
		)
	)
	(footprint ""
		(layer "F.Cu")
		(at 73.603358 -500.047514 90)
		(property "Reference" "U17"
			(at 0 0 90)
			(layer "F.SilkS")
			(hide yes)
			(effects
				(font
					(size 1.27 1.27)
				)
			)
		)
		(property "Value" "P2003EVG-GP"
			(at 0 -11.1252 90)
			(unlocked yes)
			(layer "F.Fab")
			(hide yes)
			(effects
				(font
					(size 1.016 1.016)
					(thickness 0.1524)
				)
			)
		)
		(property "Device Type" "SOIC8H79"
			(at 0 -12.6492 90)
			(unlocked yes)
			(layer "F.Fab")
			(hide yes)
			(effects
				(font
					(size 1.016 1.016)
					(thickness 0.1524)
				)
			)
		)
		(duplicate_pad_numbers_are_jumpers no)
		(fp_line
			(start 2.1336 -1.4224)
			(end -2.7432 -1.4224)
			(stroke
				(width 0.1524)
				(type default)
			)
			(layer "F.SilkS")
		)
		(fp_line
			(start -2.7432 -1.4224)
			(end -2.7432 1.4224)
			(stroke
				(width 0.1524)
				(type default)
			)
			(layer "F.SilkS")
		)
		(fp_line
			(start -2.7432 -0.508)
			(end -2.2352 0)
			(stroke
				(width 0.1524)
				(type default)
			)
			(layer "F.SilkS")
		)
		(fp_line
			(start -2.2352 0)
			(end -2.7432 0.508)
			(stroke
				(width 0.1524)
				(type default)
			)
			(layer "F.SilkS")
		)
		(fp_line
			(start 2.1336 1.4224)
			(end 2.1336 -1.4224)
			(stroke
				(width 0.1524)
				(type default)
			)
			(layer "F.SilkS")
		)
		(fp_line
			(start -2.7432 1.4224)
			(end 2.1336 1.4224)
			(stroke
				(width 0.1524)
				(type default)
			)
			(layer "F.SilkS")
		)
		(fp_line
			(start -2.6162 3.429)
			(end -2.6162 1.4732)
			(stroke
				(width 0.4064)
				(type default)
			)
			(layer "F.SilkS")
		)
		(fp_poly
			(pts
				(xy 2.2098 -1.4224) (xy 2.2098 1.4224) (xy -2.2225 1.4224) (xy -2.2225 -1.4224)
			)
			(stroke
				(width 0)
				(type default)
			)
			(fill yes)
			(layer "F.SilkS")
		)
		(fp_rect
			(start -2.4511 2.9972)
			(end 2.4511 -2.9972)
			(stroke
				(width 0)
				(type default)
			)
			(fill no)
			(layer "F.CrtYd")
		)
		(fp_poly
			(pts
				(xy -2.8194 3.6322) (xy -2.8194 -3.6322) (xy 2.8194 -3.6322) (xy 2.8194 -2.2987) (xy 2.4511 -2.2987)
				(xy 2.4511 -2.9972) (xy -2.4511 -2.9972) (xy -2.4511 2.9972) (xy 2.4511 2.9972) (xy 2.4511 -2.286)
				(xy 2.8194 -2.286) (xy 2.8194 3.6322)
			)
			(stroke
				(width 0)
				(type default)
			)
			(fill no)
			(layer "F.CrtYd")
		)
		(fp_rect
			(start -2.8194 3.6322)
			(end 2.8194 -3.6322)
			(stroke
				(width 0)
				(type default)
			)
			(fill no)
			(layer "F.Fab")
		)
		(pad "1" smd rect
			(at -1.905 2.54 90)
			(size 0.635 1.651)
			(layers "F.Cu" "F.Mask" "F.Paste")
			(net "P12V")
		)
		(pad "2" smd rect
			(at -0.635 2.54 90)
			(size 0.635 1.651)
			(layers "F.Cu" "F.Mask" "F.Paste")
			(net "P12V")
		)
		(pad "3" smd rect
			(at 0.635 2.54 90)
			(size 0.635 1.651)
			(layers "F.Cu" "F.Mask" "F.Paste")
			(net "P12V")
		)
		(pad "4" smd rect
			(at 1.905 2.54 90)
			(size 0.635 1.651)
			(layers "F.Cu" "F.Mask" "F.Paste")
			(net "SW_HDD5_N")
		)
		(pad "5" smd rect
			(at 1.905 -2.54 90)
			(size 0.635 1.651)
			(layers "F.Cu" "F.Mask" "F.Paste")
			(net "P12V_HDD5")
		)
		(pad "6" smd rect
			(at 0.635 -2.54 90)
			(size 0.635 1.651)
			(layers "F.Cu" "F.Mask" "F.Paste")
			(net "P12V_HDD5")
		)
		(pad "7" smd rect
			(at -0.635 -2.54 90)
			(size 0.635 1.651)
			(layers "F.Cu" "F.Mask" "F.Paste")
			(net "P12V_HDD5")
		)
		(pad "8" smd rect
			(at -1.905 -2.54 90)
			(size 0.635 1.651)
			(layers "F.Cu" "F.Mask" "F.Paste")
			(net "P12V_HDD5")
		)
	)
	(footprint ""
		(layer "F.Cu")
		(at 193.167 -281.686)
		(property "Reference" "C141"
			(at 0 0 0)
			(layer "F.SilkS")
			(hide yes)
			(effects
				(font
					(size 1.27 1.27)
				)
			)
		)
		(property "Value" "SCD1U10V2KX-5GP"
			(at 1.1811 -2.7051 0)
			(unlocked yes)
			(layer "F.Fab")
			(hide yes)
			(effects
				(font
					(size 1.016 1.016)
					(thickness 0.1524)
				)
			)
		)
		(property "Device Type" "C402H22"
			(at 1.1811 -4.2291 0)
			(unlocked yes)
			(layer "F.Fab")
			(hide yes)
			(effects
				(font
					(size 1.016 1.016)
					(thickness 0.1524)
				)
			)
		)
		(duplicate_pad_numbers_are_jumpers no)
		(fp_rect
			(start -0.4318 0.9525)
			(end 0.4318 -0.9525)
			(stroke
				(width 0)
				(type default)
			)
			(fill no)
			(layer "F.CrtYd")
		)
		(fp_rect
			(start -0.4318 0.9525)
			(end 0.4318 -0.9525)
			(stroke
				(width 0)
				(type default)
			)
			(fill no)
			(layer "F.Fab")
		)
		(pad "1" smd custom
			(at 0 -0.4445)
			(size 0.1524 0.1524)
			(layers "F.Cu" "F.Mask" "F.Paste")
			(net "P3V3")
			(options
				(clearance outline)
				(anchor circle)
			)
			(primitives
				(gr_poly
					(pts
						(arc
							(start 0.3048 -0.2032)
							(mid 0.275042 -0.275042)
							(end 0.2032 -0.3048)
						)
						(arc
							(start -0.2032 -0.3048)
							(mid -0.275042 -0.275042)
							(end -0.3048 -0.2032)
						)
						(arc
							(start -0.3048 0.2032)
							(mid -0.275042 0.275042)
							(end -0.2032 0.3048)
						)
						(arc
							(start 0.2032 0.3048)
							(mid 0.275042 0.275042)
							(end 0.3048 0.2032)
						)
					)
					(width 0)
					(fill yes)
				)
			)
		)
		(pad "2" smd custom
			(at 0 0.4445)
			(size 0.1524 0.1524)
			(layers "F.Cu" "F.Mask" "F.Paste")
			(net "GND")
			(options
				(clearance outline)
				(anchor circle)
			)
			(primitives
				(gr_poly
					(pts
						(arc
							(start 0.3048 -0.2032)
							(mid 0.275042 -0.275042)
							(end 0.2032 -0.3048)
						)
						(arc
							(start -0.2032 -0.3048)
							(mid -0.275042 -0.275042)
							(end -0.3048 -0.2032)
						)
						(arc
							(start -0.3048 0.2032)
							(mid -0.275042 0.275042)
							(end -0.2032 0.3048)
						)
						(arc
							(start 0.2032 0.3048)
							(mid 0.275042 0.275042)
							(end 0.3048 0.2032)
						)
					)
					(width 0)
					(fill yes)
				)
			)
		)
	)
	(footprint ""
		(layer "F.Cu")
		(at 51.891946 -349.7072 90)
		(property "Reference" "Q40"
			(at 0 0 90)
			(layer "F.SilkS")
			(hide yes)
			(effects
				(font
					(size 1.27 1.27)
				)
			)
		)
		(property "Value" "PMBS3904-1-GP"
			(at 0 -9.0932 90)
			(unlocked yes)
			(layer "F.Fab")
			(hide yes)
			(effects
				(font
					(size 1.016 1.016)
					(thickness 0.1524)
				)
			)
		)
		(property "Device Type" "SOT-23-10H44"
			(at 0 -10.6172 90)
			(unlocked yes)
			(layer "F.Fab")
			(hide yes)
			(effects
				(font
					(size 1.016 1.016)
					(thickness 0.1524)
				)
			)
		)
		(duplicate_pad_numbers_are_jumpers no)
		(fp_line
			(start 1.651 -1.778)
			(end -1.651 -1.778)
			(stroke
				(width 0.1524)
				(type default)
			)
			(layer "F.SilkS")
		)
		(fp_line
			(start -1.651 -1.778)
			(end -1.651 1.778)
			(stroke
				(width 0.1524)
				(type default)
			)
			(layer "F.SilkS")
		)
		(fp_line
			(start 1.651 1.778)
			(end 1.651 -1.778)
			(stroke
				(width 0.1524)
				(type default)
			)
			(layer "F.SilkS")
		)
		(fp_line
			(start -1.651 1.778)
			(end 1.651 1.778)
			(stroke
				(width 0.1524)
				(type default)
			)
			(layer "F.SilkS")
		)
		(fp_line
			(start -0.9906 1.86309)
			(end -0.701294 2.15265)
			(stroke
				(width 0.0127)
				(type default)
			)
			(layer "F.SilkS")
		)
		(fp_line
			(start -0.994156 1.8669)
			(end -0.987044 1.8669)
			(stroke
				(width 0.0127)
				(type default)
			)
			(layer "F.SilkS")
		)
		(fp_line
			(start -1.003808 1.876552)
			(end -0.977646 1.876552)
			(stroke
				(width 0.0127)
				(type default)
			)
			(layer "F.SilkS")
		)
		(fp_line
			(start -0.635 1.8796)
			(end -1.7526 1.8796)
			(stroke
				(width 0.3302)
				(type default)
			)
			(layer "F.SilkS")
		)
		(fp_line
			(start -1.7526 1.8796)
			(end -1.7526 0.9906)
			(stroke
				(width 0.3302)
				(type default)
			)
			(layer "F.SilkS")
		)
		(fp_line
			(start -1.013206 1.88595)
			(end -0.967994 1.88595)
			(stroke
				(width 0.0127)
				(type default)
			)
			(layer "F.SilkS")
		)
		(fp_line
			(start -1.022858 1.895602)
			(end -0.958596 1.895602)
			(stroke
				(width 0.0127)
				(type default)
			)
			(layer "F.SilkS")
		)
		(fp_line
			(start -1.032256 1.905)
			(end -0.948944 1.905)
			(stroke
				(width 0.0127)
				(type default)
			)
			(layer "F.SilkS")
		)
		(fp_line
			(start -1.041908 1.914652)
			(end -0.939546 1.914652)
			(stroke
				(width 0.0127)
				(type default)
			)
			(layer "F.SilkS")
		)
		(fp_line
			(start -1.051306 1.92405)
			(end -0.929894 1.92405)
			(stroke
				(width 0.0127)
				(type default)
			)
			(layer "F.SilkS")
		)
		(fp_line
			(start -1.060958 1.933702)
			(end -0.920496 1.933702)
			(stroke
				(width 0.0127)
				(type default)
			)
			(layer "F.SilkS")
		)
		(fp_line
			(start -1.070356 1.9431)
			(end -0.910844 1.9431)
			(stroke
				(width 0.0127)
				(type default)
			)
			(layer "F.SilkS")
		)
		(fp_line
			(start -1.080008 1.952752)
			(end -0.901446 1.952752)
			(stroke
				(width 0.0127)
				(type default)
			)
			(layer "F.SilkS")
		)
		(fp_line
			(start -1.089406 1.96215)
			(end -0.891794 1.96215)
			(stroke
				(width 0.0127)
				(type default)
			)
			(layer "F.SilkS")
		)
		(fp_line
			(start -1.099058 1.971802)
			(end -0.882396 1.971802)
			(stroke
				(width 0.0127)
				(type default)
			)
			(layer "F.SilkS")
		)
		(fp_line
			(start -1.108456 1.9812)
			(end -0.872744 1.9812)
			(stroke
				(width 0.0127)
				(type default)
			)
			(layer "F.SilkS")
		)
		(fp_line
			(start -1.118108 1.990852)
			(end -0.863346 1.990852)
			(stroke
				(width 0.0127)
				(type default)
			)
			(layer "F.SilkS")
		)
		(fp_line
			(start -1.127506 2.00025)
			(end -0.853694 2.00025)
			(stroke
				(width 0.0127)
				(type default)
			)
			(layer "F.SilkS")
		)
		(fp_line
			(start -1.137158 2.009902)
			(end -0.844296 2.009902)
			(stroke
				(width 0.0127)
				(type default)
			)
			(layer "F.SilkS")
		)
		(fp_line
			(start -1.146556 2.0193)
			(end -0.834644 2.0193)
			(stroke
				(width 0.0127)
				(type default)
			)
			(layer "F.SilkS")
		)
		(fp_line
			(start -1.156208 2.028952)
			(end -0.825246 2.028952)
			(stroke
				(width 0.0127)
				(type default)
			)
			(layer "F.SilkS")
		)
		(fp_line
			(start -1.165606 2.03835)
			(end -0.815594 2.03835)
			(stroke
				(width 0.0127)
				(type default)
			)
			(layer "F.SilkS")
		)
		(fp_line
			(start -1.175258 2.048002)
			(end -0.806196 2.048002)
			(stroke
				(width 0.0127)
				(type default)
			)
			(layer "F.SilkS")
		)
		(fp_line
			(start -1.184656 2.0574)
			(end -0.796544 2.0574)
			(stroke
				(width 0.0127)
				(type default)
			)
			(layer "F.SilkS")
		)
		(fp_line
			(start -1.194308 2.067052)
			(end -0.787146 2.067052)
			(stroke
				(width 0.0127)
				(type default)
			)
			(layer "F.SilkS")
		)
		(fp_line
			(start -1.203706 2.07645)
			(end -0.777494 2.07645)
			(stroke
				(width 0.0127)
				(type default)
			)
			(layer "F.SilkS")
		)
		(fp_line
			(start -1.213358 2.086102)
			(end -0.768096 2.086102)
			(stroke
				(width 0.0127)
				(type default)
			)
			(layer "F.SilkS")
		)
		(fp_line
			(start -1.222756 2.0955)
			(end -0.758444 2.0955)
			(stroke
				(width 0.0127)
				(type default)
			)
			(layer "F.SilkS")
		)
		(fp_line
			(start -1.232408 2.105152)
			(end -0.749046 2.105152)
			(stroke
				(width 0.0127)
				(type default)
			)
			(layer "F.SilkS")
		)
		(fp_line
			(start -1.241806 2.11455)
			(end -0.739394 2.11455)
			(stroke
				(width 0.0127)
				(type default)
			)
			(layer "F.SilkS")
		)
		(fp_line
			(start -1.251458 2.124202)
			(end -0.729996 2.124202)
			(stroke
				(width 0.0127)
				(type default)
			)
			(layer "F.SilkS")
		)
		(fp_line
			(start -1.260856 2.1336)
			(end -0.720344 2.1336)
			(stroke
				(width 0.0127)
				(type default)
			)
			(layer "F.SilkS")
		)
		(fp_line
			(start -0.719074 2.145538)
			(end -1.265936 2.14122)
			(stroke
				(width 0.0127)
				(type default)
			)
			(layer "F.SilkS")
		)
		(fp_line
			(start -1.279398 2.152142)
			(end -0.9906 1.86309)
			(stroke
				(width 0.0127)
				(type default)
			)
			(layer "F.SilkS")
		)
		(fp_line
			(start -0.71628 2.15265)
			(end -1.26492 2.15265)
			(stroke
				(width 0.0127)
				(type default)
			)
			(layer "F.SilkS")
		)
		(fp_line
			(start -1.279144 2.15265)
			(end -0.701294 2.15265)
			(stroke
				(width 0.0127)
				(type default)
			)
			(layer "F.SilkS")
		)
		(fp_poly
			(pts
				(xy -1.285748 2.159) (xy -1.285748 1.8796) (xy -1.778 1.8796) (xy -1.778 -1.8796) (xy 1.778 -1.8796)
				(xy 1.778 1.8796) (xy -0.694944 1.8796) (xy -0.694944 2.159)
			)
			(stroke
				(width 0)
				(type default)
			)
			(fill no)
			(layer "F.CrtYd")
		)
		(fp_poly
			(pts
				(xy -1.285748 2.159) (xy -1.285748 1.8796) (xy -1.778 1.8796) (xy -1.778 -1.8796) (xy 1.778 -1.8796)
				(xy 1.778 1.8796) (xy -0.694944 1.8796) (xy -0.694944 2.159)
			)
			(stroke
				(width 0)
				(type default)
			)
			(fill no)
			(layer "F.Fab")
		)
		(pad "1" smd rect
			(at -0.98425 0.9525 90)
			(size 0.762 1.143)
			(layers "F.Cu" "F.Mask" "F.Paste")
			(net "FLT_HDD6_B")
		)
		(pad "2" smd rect
			(at 0.98425 0.9525 90)
			(size 0.762 1.143)
			(layers "F.Cu" "F.Mask" "F.Paste")
			(net "GND")
		)
		(pad "3" smd rect
			(at 0 -0.9525 90)
			(size 0.762 1.143)
			(layers "F.Cu" "F.Mask" "F.Paste")
			(net "DRIVE_ACT_6")
		)
	)
	(footprint ""
		(layer "F.Cu")
		(at 190.373 -497.84)
		(property "Reference" "R109"
			(at 0 0 0)
			(layer "F.SilkS")
			(hide yes)
			(effects
				(font
					(size 1.27 1.27)
				)
			)
		)
		(property "Value" "200KR2F-L-GP"
			(at 0.064008 -3.993896 0)
			(unlocked yes)
			(layer "F.Fab")
			(hide yes)
			(effects
				(font
					(size 1.016 1.016)
					(thickness 0.1524)
				)
			)
		)
		(property "Device Type" "R402H16"
			(at 0.064008 -5.517896 0)
			(unlocked yes)
			(layer "F.Fab")
			(hide yes)
			(effects
				(font
					(size 1.016 1.016)
					(thickness 0.1524)
				)
			)
		)
		(duplicate_pad_numbers_are_jumpers no)
		(fp_line
			(start -0.508 -0.9398)
			(end -0.508 0.9398)
			(stroke
				(width 0.1524)
				(type default)
			)
			(layer "F.SilkS")
		)
		(fp_line
			(start 0.508 -0.9398)
			(end -0.508 -0.9398)
			(stroke
				(width 0.1524)
				(type default)
			)
			(layer "F.SilkS")
		)
		(fp_rect
			(start -0.508 0.9398)
			(end 0.508 -0.9398)
			(stroke
				(width 0)
				(type default)
			)
			(fill no)
			(layer "F.CrtYd")
		)
		(fp_rect
			(start -0.508 0.9398)
			(end 0.508 -0.9398)
			(stroke
				(width 0)
				(type default)
			)
			(fill no)
			(layer "F.Fab")
		)
		(pad "1" smd custom
			(at 0 -0.4445)
			(size 0.1397 0.1397)
			(layers "F.Cu" "F.Mask" "F.Paste")
			(net "P12V")
			(options
				(clearance outline)
				(anchor circle)
			)
			(primitives
				(gr_poly
					(pts
						(arc
							(start -0.1778 -0.2794)
							(mid -0.249642 -0.249642)
							(end -0.2794 -0.1778)
						)
						(arc
							(start -0.2794 0.1778)
							(mid -0.249642 0.249642)
							(end -0.1778 0.2794)
						)
						(arc
							(start 0.1778 0.2794)
							(mid 0.249642 0.249642)
							(end 0.2794 0.1778)
						)
						(arc
							(start 0.2794 -0.1778)
							(mid 0.249642 -0.249642)
							(end 0.1778 -0.2794)
						)
					)
					(width 0)
					(fill yes)
				)
			)
		)
		(pad "2" smd custom
			(at 0 0.4445)
			(size 0.1397 0.1397)
			(layers "F.Cu" "F.Mask" "F.Paste")
			(net "SW_HDD0_P")
			(options
				(clearance outline)
				(anchor circle)
			)
			(primitives
				(gr_poly
					(pts
						(arc
							(start -0.1778 -0.2794)
							(mid -0.249642 -0.249642)
							(end -0.2794 -0.1778)
						)
						(arc
							(start -0.2794 0.1778)
							(mid -0.249642 0.249642)
							(end -0.1778 0.2794)
						)
						(arc
							(start 0.1778 0.2794)
							(mid 0.249642 0.249642)
							(end 0.2794 0.1778)
						)
						(arc
							(start 0.2794 -0.1778)
							(mid 0.249642 -0.249642)
							(end 0.1778 -0.2794)
						)
					)
					(width 0)
					(fill yes)
				)
			)
		)
	)
	(footprint ""
		(layer "F.Cu")
		(at 217.635582 -275.816568)
		(property "Reference" "C147"
			(at 0 0 0)
			(layer "F.SilkS")
			(hide yes)
			(effects
				(font
					(size 1.27 1.27)
				)
			)
		)
		(property "Value" "SCD01U50V2KX-1GP"
			(at 1.1811 -2.7051 0)
			(unlocked yes)
			(layer "F.Fab")
			(hide yes)
			(effects
				(font
					(size 1.016 1.016)
					(thickness 0.1524)
				)
			)
		)
		(property "Device Type" "C402H22"
			(at 1.1811 -4.2291 0)
			(unlocked yes)
			(layer "F.Fab")
			(hide yes)
			(effects
				(font
					(size 1.016 1.016)
					(thickness 0.1524)
				)
			)
		)
		(duplicate_pad_numbers_are_jumpers no)
		(fp_rect
			(start -0.4318 0.9525)
			(end 0.4318 -0.9525)
			(stroke
				(width 0)
				(type default)
			)
			(fill no)
			(layer "F.CrtYd")
		)
		(fp_rect
			(start -0.4318 0.9525)
			(end 0.4318 -0.9525)
			(stroke
				(width 0)
				(type default)
			)
			(fill no)
			(layer "F.Fab")
		)
		(pad "1" smd custom
			(at 0 -0.4445)
			(size 0.1524 0.1524)
			(layers "F.Cu" "F.Mask" "F.Paste")
			(net "HDD_PRSNT_NET2")
			(options
				(clearance outline)
				(anchor circle)
			)
			(primitives
				(gr_poly
					(pts
						(arc
							(start 0.3048 -0.2032)
							(mid 0.275042 -0.275042)
							(end 0.2032 -0.3048)
						)
						(arc
							(start -0.2032 -0.3048)
							(mid -0.275042 -0.275042)
							(end -0.3048 -0.2032)
						)
						(arc
							(start -0.3048 0.2032)
							(mid -0.275042 0.275042)
							(end -0.2032 0.3048)
						)
						(arc
							(start 0.2032 0.3048)
							(mid 0.275042 0.275042)
							(end 0.3048 0.2032)
						)
					)
					(width 0)
					(fill yes)
				)
			)
		)
		(pad "2" smd custom
			(at 0 0.4445)
			(size 0.1524 0.1524)
			(layers "F.Cu" "F.Mask" "F.Paste")
			(net "GND")
			(options
				(clearance outline)
				(anchor circle)
			)
			(primitives
				(gr_poly
					(pts
						(arc
							(start 0.3048 -0.2032)
							(mid 0.275042 -0.275042)
							(end 0.2032 -0.3048)
						)
						(arc
							(start -0.2032 -0.3048)
							(mid -0.275042 -0.275042)
							(end -0.3048 -0.2032)
						)
						(arc
							(start -0.3048 0.2032)
							(mid -0.275042 0.275042)
							(end -0.2032 0.3048)
						)
						(arc
							(start 0.2032 0.3048)
							(mid 0.275042 0.275042)
							(end 0.3048 0.2032)
						)
					)
					(width 0)
					(fill yes)
				)
			)
		)
	)
	(footprint ""
		(layer "F.Cu")
		(at 166.509446 -461.552036)
		(property "Reference" "R381"
			(at 0 0 0)
			(layer "F.SilkS")
			(hide yes)
			(effects
				(font
					(size 1.27 1.27)
				)
			)
		)
		(property "Value" "4K7R2J-2-GP"
			(at 0.064008 -3.993896 0)
			(unlocked yes)
			(layer "F.Fab")
			(hide yes)
			(effects
				(font
					(size 1.016 1.016)
					(thickness 0.1524)
				)
			)
		)
		(property "Device Type" "R402H16"
			(at 0.064008 -5.517896 0)
			(unlocked yes)
			(layer "F.Fab")
			(hide yes)
			(effects
				(font
					(size 1.016 1.016)
					(thickness 0.1524)
				)
			)
		)
		(duplicate_pad_numbers_are_jumpers no)
		(fp_line
			(start -0.508 -0.9398)
			(end -0.508 0.9398)
			(stroke
				(width 0.1524)
				(type default)
			)
			(layer "F.SilkS")
		)
		(fp_line
			(start 0.508 -0.9398)
			(end -0.508 -0.9398)
			(stroke
				(width 0.1524)
				(type default)
			)
			(layer "F.SilkS")
		)
		(fp_rect
			(start -0.508 0.9398)
			(end 0.508 -0.9398)
			(stroke
				(width 0)
				(type default)
			)
			(fill no)
			(layer "F.CrtYd")
		)
		(fp_rect
			(start -0.508 0.9398)
			(end 0.508 -0.9398)
			(stroke
				(width 0)
				(type default)
			)
			(fill no)
			(layer "F.Fab")
		)
		(pad "1" smd custom
			(at 0 -0.4445)
			(size 0.1397 0.1397)
			(layers "F.Cu" "F.Mask" "F.Paste")
			(net "VOL_SEN_ADDR")
			(options
				(clearance outline)
				(anchor circle)
			)
			(primitives
				(gr_poly
					(pts
						(arc
							(start -0.1778 -0.2794)
							(mid -0.249642 -0.249642)
							(end -0.2794 -0.1778)
						)
						(arc
							(start -0.2794 0.1778)
							(mid -0.249642 0.249642)
							(end -0.1778 0.2794)
						)
						(arc
							(start 0.1778 0.2794)
							(mid 0.249642 0.249642)
							(end 0.2794 0.1778)
						)
						(arc
							(start 0.2794 -0.1778)
							(mid 0.249642 -0.249642)
							(end 0.1778 -0.2794)
						)
					)
					(width 0)
					(fill yes)
				)
			)
		)
		(pad "2" smd custom
			(at 0 0.4445)
			(size 0.1397 0.1397)
			(layers "F.Cu" "F.Mask" "F.Paste")
			(net "GND")
			(options
				(clearance outline)
				(anchor circle)
			)
			(primitives
				(gr_poly
					(pts
						(arc
							(start -0.1778 -0.2794)
							(mid -0.249642 -0.249642)
							(end -0.2794 -0.1778)
						)
						(arc
							(start -0.2794 0.1778)
							(mid -0.249642 0.249642)
							(end -0.1778 0.2794)
						)
						(arc
							(start 0.1778 0.2794)
							(mid 0.249642 0.249642)
							(end 0.2794 0.1778)
						)
						(arc
							(start 0.2794 -0.1778)
							(mid 0.249642 -0.249642)
							(end 0.1778 -0.2794)
						)
					)
					(width 0)
					(fill yes)
				)
			)
		)
	)
	(footprint ""
		(layer "F.Cu")
		(at 45.482256 -451.767702 90)
		(property "Reference" "R174"
			(at 0 0 90)
			(layer "F.SilkS")
			(hide yes)
			(effects
				(font
					(size 1.27 1.27)
				)
			)
		)
		(property "Value" "0R2J-2-GP"
			(at 0.064008 -3.993896 90)
			(unlocked yes)
			(layer "F.Fab")
			(hide yes)
			(effects
				(font
					(size 1.016 1.016)
					(thickness 0.1524)
				)
			)
		)
		(property "Device Type" "R402H16"
			(at 0.064008 -5.517896 90)
			(unlocked yes)
			(layer "F.Fab")
			(hide yes)
			(effects
				(font
					(size 1.016 1.016)
					(thickness 0.1524)
				)
			)
		)
		(duplicate_pad_numbers_are_jumpers no)
		(fp_line
			(start 0.508 -0.9398)
			(end -0.508 -0.9398)
			(stroke
				(width 0.1524)
				(type default)
			)
			(layer "F.SilkS")
		)
		(fp_line
			(start -0.508 -0.9398)
			(end -0.508 0.9398)
			(stroke
				(width 0.1524)
				(type default)
			)
			(layer "F.SilkS")
		)
		(fp_rect
			(start -0.508 0.9398)
			(end 0.508 -0.9398)
			(stroke
				(width 0)
				(type default)
			)
			(fill no)
			(layer "F.CrtYd")
		)
		(fp_rect
			(start -0.508 0.9398)
			(end 0.508 -0.9398)
			(stroke
				(width 0)
				(type default)
			)
			(fill no)
			(layer "F.Fab")
		)
		(pad "1" smd custom
			(at 0 -0.4445 90)
			(size 0.1397 0.1397)
			(layers "F.Cu" "F.Mask" "F.Paste")
			(net "FLT_NET_HDD5")
			(options
				(clearance outline)
				(anchor circle)
			)
			(primitives
				(gr_poly
					(pts
						(arc
							(start -0.1778 -0.2794)
							(mid -0.249642 -0.249642)
							(end -0.2794 -0.1778)
						)
						(arc
							(start -0.2794 0.1778)
							(mid -0.249642 0.249642)
							(end -0.1778 0.2794)
						)
						(arc
							(start 0.1778 0.2794)
							(mid 0.249642 0.249642)
							(end 0.2794 0.1778)
						)
						(arc
							(start 0.2794 -0.1778)
							(mid 0.249642 -0.249642)
							(end 0.1778 -0.2794)
						)
					)
					(width 0)
					(fill yes)
				)
			)
		)
		(pad "2" smd custom
			(at 0 0.4445 90)
			(size 0.1397 0.1397)
			(layers "F.Cu" "F.Mask" "F.Paste")
			(net "FLT_HDD5_DRIVE")
			(options
				(clearance outline)
				(anchor circle)
			)
			(primitives
				(gr_poly
					(pts
						(arc
							(start -0.1778 -0.2794)
							(mid -0.249642 -0.249642)
							(end -0.2794 -0.1778)
						)
						(arc
							(start -0.2794 0.1778)
							(mid -0.249642 0.249642)
							(end -0.1778 0.2794)
						)
						(arc
							(start 0.1778 0.2794)
							(mid 0.249642 0.249642)
							(end 0.2794 0.1778)
						)
						(arc
							(start 0.2794 -0.1778)
							(mid 0.249642 -0.249642)
							(end 0.1778 -0.2794)
						)
					)
					(width 0)
					(fill yes)
				)
			)
		)
	)
	(footprint ""
		(layer "F.Cu")
		(at 227.499926 -41.159938 180)
		(property "Reference" "LED5"
			(at 0 0 180)
			(layer "F.SilkS")
			(hide yes)
			(effects
				(font
					(size 1.27 1.27)
				)
			)
		)
		(property "Value" "LED-RB-4-GP"
			(at 5.88899 1.80848 180)
			(unlocked yes)
			(layer "F.Fab")
			(hide yes)
			(effects
				(font
					(size 1.016 1.016)
					(thickness 0.1524)
				)
			)
		)
		(property "Device Type" "LED1613-4PH20"
			(at 5.88899 0.28448 180)
			(unlocked yes)
			(layer "F.Fab")
			(hide yes)
			(effects
				(font
					(size 1.016 1.016)
					(thickness 0.1524)
				)
			)
		)
		(duplicate_pad_numbers_are_jumpers no)
		(fp_line
			(start 1.4478 0.9652)
			(end -1.4478 0.9652)
			(stroke
				(width 0.1524)
				(type default)
			)
			(layer "F.SilkS")
		)
		(fp_line
			(start 1.4478 -0.9652)
			(end 1.4478 0.9652)
			(stroke
				(width 0.1524)
				(type default)
			)
			(layer "F.SilkS")
		)
		(fp_line
			(start -1.4478 0.9652)
			(end -1.4478 -0.9652)
			(stroke
				(width 0.1524)
				(type default)
			)
			(layer "F.SilkS")
		)
		(fp_line
			(start -1.4478 0.9652)
			(end -1.4478 -0.9652)
			(stroke
				(width 0.508)
				(type default)
			)
			(layer "F.SilkS")
		)
		(fp_line
			(start -1.4478 -0.9652)
			(end 1.4478 -0.9652)
			(stroke
				(width 0.1524)
				(type default)
			)
			(layer "F.SilkS")
		)
		(fp_rect
			(start -0.8001 0.6477)
			(end 0.8001 -0.6477)
			(stroke
				(width 0)
				(type default)
			)
			(fill no)
			(layer "F.CrtYd")
		)
		(fp_poly
			(pts
				(xy -1.7018 1.2192) (xy -1.7018 -0.06223) (xy -0.8001 -0.06223) (xy -0.8001 0.6477) (xy 0.8001 0.6477)
				(xy 0.8001 -0.6477) (xy -0.8001 -0.6477) (xy -0.8001 -0.0635) (xy -1.7018 -0.0635) (xy -1.7018 -1.2192)
				(xy 1.7018 -1.2192) (xy 1.7018 1.2192)
			)
			(stroke
				(width 0)
				(type default)
			)
			(fill no)
			(layer "F.CrtYd")
		)
		(fp_rect
			(start -1.7018 1.2192)
			(end 1.7018 -1.2192)
			(stroke
				(width 0)
				(type default)
			)
			(fill no)
			(layer "F.Fab")
		)
		(pad "1" smd rect
			(at -0.73025 0.4064 180)
			(size 0.9144 0.6096)
			(layers "F.Cu" "F.Mask" "F.Paste")
			(net "DRV_ACT_NET4")
		)
		(pad "2" smd rect
			(at -0.73025 -0.4064 180)
			(size 0.9144 0.6096)
			(layers "F.Cu" "F.Mask" "F.Paste")
			(net "FLT_NET_HDD4")
		)
		(pad "3" smd rect
			(at 0.73025 -0.4064 180)
			(size 0.9144 0.6096)
			(layers "F.Cu" "F.Mask" "F.Paste")
			(net "FLT_HDD4")
		)
		(pad "4" smd rect
			(at 0.73025 0.4064 180)
			(size 0.9144 0.6096)
			(layers "F.Cu" "F.Mask" "F.Paste")
			(net "DRV_ACT_4")
		)
	)
	(footprint ""
		(layer "F.Cu")
		(at 79.781146 -7.013702)
		(property "Reference" "C334"
			(at 0 0 0)
			(layer "F.SilkS")
			(hide yes)
			(effects
				(font
					(size 1.27 1.27)
				)
			)
		)
		(property "Value" "SC10U25V6KX-1GP"
			(at -0.0762 -5.1308 0)
			(unlocked yes)
			(layer "F.Fab")
			(hide yes)
			(effects
				(font
					(size 1.016 1.016)
					(thickness 0.1524)
				)
			)
		)
		(property "Device Type" "C1206H71"
			(at -0.127 -6.6548 0)
			(unlocked yes)
			(layer "F.Fab")
			(hide yes)
			(effects
				(font
					(size 1.016 1.016)
					(thickness 0.1524)
				)
			)
		)
		(duplicate_pad_numbers_are_jumpers no)
		(fp_line
			(start -1.016 -2.2352)
			(end 1.016 -2.2352)
			(stroke
				(width 0.1524)
				(type default)
			)
			(layer "F.SilkS")
		)
		(fp_line
			(start -1.016 -0.8382)
			(end -1.016 -2.2352)
			(stroke
				(width 0.1524)
				(type default)
			)
			(layer "F.SilkS")
		)
		(fp_line
			(start -1.016 2.2352)
			(end -1.016 0.8382)
			(stroke
				(width 0.1524)
				(type default)
			)
			(layer "F.SilkS")
		)
		(fp_line
			(start 1.016 -2.2352)
			(end 1.016 -0.8382)
			(stroke
				(width 0.1524)
				(type default)
			)
			(layer "F.SilkS")
		)
		(fp_line
			(start 1.016 0.8382)
			(end 1.016 2.2352)
			(stroke
				(width 0.1524)
				(type default)
			)
			(layer "F.SilkS")
		)
		(fp_line
			(start 1.016 2.2352)
			(end -1.016 2.2352)
			(stroke
				(width 0.1524)
				(type default)
			)
			(layer "F.SilkS")
		)
		(fp_rect
			(start -1.0922 2.3114)
			(end 1.0922 -2.3114)
			(stroke
				(width 0)
				(type default)
			)
			(fill no)
			(layer "F.CrtYd")
		)
		(fp_poly
			(pts
				(xy 1.0922 -2.3114) (xy 1.0922 2.3114) (xy -1.0922 2.3114) (xy -1.0922 -2.3114)
			)
			(stroke
				(width 0)
				(type default)
			)
			(fill no)
			(layer "F.Fab")
		)
		(pad "1" smd rect
			(at 0 -1.397)
			(size 1.651 1.27)
			(layers "F.Cu" "F.Mask" "F.Paste")
			(net "P12V_HDD14")
		)
		(pad "2" smd rect
			(at 0 1.397)
			(size 1.651 1.27)
			(layers "F.Cu" "F.Mask" "F.Paste")
			(net "GND")
		)
	)
	(footprint ""
		(layer "F.Cu")
		(at 214.9348 -172.1358 -90)
		(property "Reference" "R369"
			(at 0 0 270)
			(layer "F.SilkS")
			(hide yes)
			(effects
				(font
					(size 1.27 1.27)
				)
			)
		)
		(property "Value" "0R2J-2-GP"
			(at 0.064008 -3.993896 270)
			(unlocked yes)
			(layer "F.Fab")
			(hide yes)
			(effects
				(font
					(size 1.016 1.016)
					(thickness 0.1524)
				)
			)
		)
		(property "Device Type" "R402H16"
			(at 0.064008 -5.517896 270)
			(unlocked yes)
			(layer "F.Fab")
			(hide yes)
			(effects
				(font
					(size 1.016 1.016)
					(thickness 0.1524)
				)
			)
		)
		(duplicate_pad_numbers_are_jumpers no)
		(fp_line
			(start -0.508 -0.9398)
			(end -0.508 0.9398)
			(stroke
				(width 0.1524)
				(type default)
			)
			(layer "F.SilkS")
		)
		(fp_line
			(start 0.508 -0.9398)
			(end -0.508 -0.9398)
			(stroke
				(width 0.1524)
				(type default)
			)
			(layer "F.SilkS")
		)
		(fp_rect
			(start -0.508 0.9398)
			(end 0.508 -0.9398)
			(stroke
				(width 0)
				(type default)
			)
			(fill no)
			(layer "F.CrtYd")
		)
		(fp_rect
			(start -0.508 0.9398)
			(end 0.508 -0.9398)
			(stroke
				(width 0)
				(type default)
			)
			(fill no)
			(layer "F.Fab")
		)
		(pad "1" smd custom
			(at 0 -0.4445 270)
			(size 0.1397 0.1397)
			(layers "F.Cu" "F.Mask" "F.Paste")
			(net "HDD_PRSNT_NET3")
			(options
				(clearance outline)
				(anchor circle)
			)
			(primitives
				(gr_poly
					(pts
						(arc
							(start -0.1778 -0.2794)
							(mid -0.249642 -0.249642)
							(end -0.2794 -0.1778)
						)
						(arc
							(start -0.2794 0.1778)
							(mid -0.249642 0.249642)
							(end -0.1778 0.2794)
						)
						(arc
							(start 0.1778 0.2794)
							(mid 0.249642 0.249642)
							(end 0.2794 0.1778)
						)
						(arc
							(start 0.2794 -0.1778)
							(mid 0.249642 -0.249642)
							(end 0.1778 -0.2794)
						)
					)
					(width 0)
					(fill yes)
				)
			)
		)
		(pad "2" smd custom
			(at 0 0.4445 270)
			(size 0.1397 0.1397)
			(layers "F.Cu" "F.Mask" "F.Paste")
			(net "HDD3_LED_B")
			(options
				(clearance outline)
				(anchor circle)
			)
			(primitives
				(gr_poly
					(pts
						(arc
							(start -0.1778 -0.2794)
							(mid -0.249642 -0.249642)
							(end -0.2794 -0.1778)
						)
						(arc
							(start -0.2794 0.1778)
							(mid -0.249642 0.249642)
							(end -0.1778 0.2794)
						)
						(arc
							(start 0.1778 0.2794)
							(mid 0.249642 0.249642)
							(end 0.2794 0.1778)
						)
						(arc
							(start 0.2794 -0.1778)
							(mid 0.249642 -0.249642)
							(end 0.1778 -0.2794)
						)
					)
					(width 0)
					(fill yes)
				)
			)
		)
	)
	(footprint ""
		(layer "F.Cu")
		(at 24.129746 -286.6517 90)
		(property "Reference" "U23"
			(at 0 0 90)
			(layer "F.SilkS")
			(hide yes)
			(effects
				(font
					(size 1.27 1.27)
				)
			)
		)
		(property "Value" "P2003EVG-GP"
			(at 0 -11.1252 90)
			(unlocked yes)
			(layer "F.Fab")
			(hide yes)
			(effects
				(font
					(size 1.016 1.016)
					(thickness 0.1524)
				)
			)
		)
		(property "Device Type" "SOIC8H79"
			(at 0 -12.6492 90)
			(unlocked yes)
			(layer "F.Fab")
			(hide yes)
			(effects
				(font
					(size 1.016 1.016)
					(thickness 0.1524)
				)
			)
		)
		(duplicate_pad_numbers_are_jumpers no)
		(fp_line
			(start 2.1336 -1.4224)
			(end -2.7432 -1.4224)
			(stroke
				(width 0.1524)
				(type default)
			)
			(layer "F.SilkS")
		)
		(fp_line
			(start -2.7432 -1.4224)
			(end -2.7432 1.4224)
			(stroke
				(width 0.1524)
				(type default)
			)
			(layer "F.SilkS")
		)
		(fp_line
			(start -2.7432 -0.508)
			(end -2.2352 0)
			(stroke
				(width 0.1524)
				(type default)
			)
			(layer "F.SilkS")
		)
		(fp_line
			(start -2.2352 0)
			(end -2.7432 0.508)
			(stroke
				(width 0.1524)
				(type default)
			)
			(layer "F.SilkS")
		)
		(fp_line
			(start 2.1336 1.4224)
			(end 2.1336 -1.4224)
			(stroke
				(width 0.1524)
				(type default)
			)
			(layer "F.SilkS")
		)
		(fp_line
			(start -2.7432 1.4224)
			(end 2.1336 1.4224)
			(stroke
				(width 0.1524)
				(type default)
			)
			(layer "F.SilkS")
		)
		(fp_line
			(start -2.6162 3.429)
			(end -2.6162 1.4732)
			(stroke
				(width 0.4064)
				(type default)
			)
			(layer "F.SilkS")
		)
		(fp_poly
			(pts
				(xy 2.2098 -1.4224) (xy 2.2098 1.4224) (xy -2.2225 1.4224) (xy -2.2225 -1.4224)
			)
			(stroke
				(width 0)
				(type default)
			)
			(fill yes)
			(layer "F.SilkS")
		)
		(fp_rect
			(start -2.4511 2.9972)
			(end 2.4511 -2.9972)
			(stroke
				(width 0)
				(type default)
			)
			(fill no)
			(layer "F.CrtYd")
		)
		(fp_poly
			(pts
				(xy -2.8194 3.6322) (xy -2.8194 -3.6322) (xy 2.8194 -3.6322) (xy 2.8194 -2.2987) (xy 2.4511 -2.2987)
				(xy 2.4511 -2.9972) (xy -2.4511 -2.9972) (xy -2.4511 2.9972) (xy 2.4511 2.9972) (xy 2.4511 -2.286)
				(xy 2.8194 -2.286) (xy 2.8194 3.6322)
			)
			(stroke
				(width 0)
				(type default)
			)
			(fill no)
			(layer "F.CrtYd")
		)
		(fp_rect
			(start -2.8194 3.6322)
			(end 2.8194 -3.6322)
			(stroke
				(width 0)
				(type default)
			)
			(fill no)
			(layer "F.Fab")
		)
		(pad "1" smd rect
			(at -1.905 2.54 90)
			(size 0.635 1.651)
			(layers "F.Cu" "F.Mask" "F.Paste")
			(net "P12V")
		)
		(pad "2" smd rect
			(at -0.635 2.54 90)
			(size 0.635 1.651)
			(layers "F.Cu" "F.Mask" "F.Paste")
			(net "P12V")
		)
		(pad "3" smd rect
			(at 0.635 2.54 90)
			(size 0.635 1.651)
			(layers "F.Cu" "F.Mask" "F.Paste")
			(net "P12V")
		)
		(pad "4" smd rect
			(at 1.905 2.54 90)
			(size 0.635 1.651)
			(layers "F.Cu" "F.Mask" "F.Paste")
			(net "SW_HDD7_N")
		)
		(pad "5" smd rect
			(at 1.905 -2.54 90)
			(size 0.635 1.651)
			(layers "F.Cu" "F.Mask" "F.Paste")
			(net "P12V_HDD7")
		)
		(pad "6" smd rect
			(at 0.635 -2.54 90)
			(size 0.635 1.651)
			(layers "F.Cu" "F.Mask" "F.Paste")
			(net "P12V_HDD7")
		)
		(pad "7" smd rect
			(at -0.635 -2.54 90)
			(size 0.635 1.651)
			(layers "F.Cu" "F.Mask" "F.Paste")
			(net "P12V_HDD7")
		)
		(pad "8" smd rect
			(at -1.905 -2.54 90)
			(size 0.635 1.651)
			(layers "F.Cu" "F.Mask" "F.Paste")
			(net "P12V_HDD7")
		)
	)
	(footprint ""
		(layer "F.Cu")
		(at 35.940746 -112.296702 180)
		(property "Reference" "R287"
			(at 0 0 180)
			(layer "F.SilkS")
			(hide yes)
			(effects
				(font
					(size 1.27 1.27)
				)
			)
		)
		(property "Value" "1KR2F-3-GP"
			(at 0.064008 -3.993896 180)
			(unlocked yes)
			(layer "F.Fab")
			(hide yes)
			(effects
				(font
					(size 1.016 1.016)
					(thickness 0.1524)
				)
			)
		)
		(property "Device Type" "R402H16"
			(at 0.064008 -5.517896 180)
			(unlocked yes)
			(layer "F.Fab")
			(hide yes)
			(effects
				(font
					(size 1.016 1.016)
					(thickness 0.1524)
				)
			)
		)
		(duplicate_pad_numbers_are_jumpers no)
		(fp_line
			(start 0.508 -0.9398)
			(end -0.508 -0.9398)
			(stroke
				(width 0.1524)
				(type default)
			)
			(layer "F.SilkS")
		)
		(fp_line
			(start -0.508 -0.9398)
			(end -0.508 0.9398)
			(stroke
				(width 0.1524)
				(type default)
			)
			(layer "F.SilkS")
		)
		(fp_rect
			(start -0.508 0.9398)
			(end 0.508 -0.9398)
			(stroke
				(width 0)
				(type default)
			)
			(fill no)
			(layer "F.CrtYd")
		)
		(fp_rect
			(start -0.508 0.9398)
			(end 0.508 -0.9398)
			(stroke
				(width 0)
				(type default)
			)
			(fill no)
			(layer "F.Fab")
		)
		(pad "1" smd custom
			(at 0 -0.4445 180)
			(size 0.1397 0.1397)
			(layers "F.Cu" "F.Mask" "F.Paste")
			(net "P3V3")
			(options
				(clearance outline)
				(anchor circle)
			)
			(primitives
				(gr_poly
					(pts
						(arc
							(start -0.1778 -0.2794)
							(mid -0.249642 -0.249642)
							(end -0.2794 -0.1778)
						)
						(arc
							(start -0.2794 0.1778)
							(mid -0.249642 0.249642)
							(end -0.1778 0.2794)
						)
						(arc
							(start 0.1778 0.2794)
							(mid 0.249642 0.249642)
							(end 0.2794 0.1778)
						)
						(arc
							(start 0.2794 -0.1778)
							(mid 0.249642 -0.249642)
							(end 0.1778 -0.2794)
						)
					)
					(width 0)
					(fill yes)
				)
			)
		)
		(pad "2" smd custom
			(at 0 0.4445 180)
			(size 0.1397 0.1397)
			(layers "F.Cu" "F.Mask" "F.Paste")
			(net "SW_PWR_HDD13")
			(options
				(clearance outline)
				(anchor circle)
			)
			(primitives
				(gr_poly
					(pts
						(arc
							(start -0.1778 -0.2794)
							(mid -0.249642 -0.249642)
							(end -0.2794 -0.1778)
						)
						(arc
							(start -0.2794 0.1778)
							(mid -0.249642 0.249642)
							(end -0.1778 0.2794)
						)
						(arc
							(start 0.1778 0.2794)
							(mid 0.249642 0.249642)
							(end 0.2794 0.1778)
						)
						(arc
							(start 0.2794 -0.1778)
							(mid 0.249642 -0.249642)
							(end 0.1778 -0.2794)
						)
					)
					(width 0)
					(fill yes)
				)
			)
		)
	)
	(footprint ""
		(layer "F.Cu")
		(at 192.786 -90.297 90)
		(property "Reference" "R553"
			(at 0 0 90)
			(layer "F.SilkS")
			(hide yes)
			(effects
				(font
					(size 1.27 1.27)
				)
			)
		)
		(property "Value" "200KR2F-L-GP"
			(at 0.064008 -3.993896 90)
			(unlocked yes)
			(layer "F.Fab")
			(hide yes)
			(effects
				(font
					(size 1.016 1.016)
					(thickness 0.1524)
				)
			)
		)
		(property "Device Type" "R402H16"
			(at 0.064008 -5.517896 90)
			(unlocked yes)
			(layer "F.Fab")
			(hide yes)
			(effects
				(font
					(size 1.016 1.016)
					(thickness 0.1524)
				)
			)
		)
		(duplicate_pad_numbers_are_jumpers no)
		(fp_line
			(start 0.508 -0.9398)
			(end -0.508 -0.9398)
			(stroke
				(width 0.1524)
				(type default)
			)
			(layer "F.SilkS")
		)
		(fp_line
			(start -0.508 -0.9398)
			(end -0.508 0.9398)
			(stroke
				(width 0.1524)
				(type default)
			)
			(layer "F.SilkS")
		)
		(fp_rect
			(start -0.508 0.9398)
			(end 0.508 -0.9398)
			(stroke
				(width 0)
				(type default)
			)
			(fill no)
			(layer "F.CrtYd")
		)
		(fp_rect
			(start -0.508 0.9398)
			(end 0.508 -0.9398)
			(stroke
				(width 0)
				(type default)
			)
			(fill no)
			(layer "F.Fab")
		)
		(pad "1" smd custom
			(at 0 -0.4445 90)
			(size 0.1397 0.1397)
			(layers "F.Cu" "F.Mask" "F.Paste")
			(net "SW_HDD4_R")
			(options
				(clearance outline)
				(anchor circle)
			)
			(primitives
				(gr_poly
					(pts
						(arc
							(start -0.1778 -0.2794)
							(mid -0.249642 -0.249642)
							(end -0.2794 -0.1778)
						)
						(arc
							(start -0.2794 0.1778)
							(mid -0.249642 0.249642)
							(end -0.1778 0.2794)
						)
						(arc
							(start 0.1778 0.2794)
							(mid 0.249642 0.249642)
							(end 0.2794 0.1778)
						)
						(arc
							(start 0.2794 -0.1778)
							(mid 0.249642 -0.249642)
							(end 0.1778 -0.2794)
						)
					)
					(width 0)
					(fill yes)
				)
			)
		)
		(pad "2" smd custom
			(at 0 0.4445 90)
			(size 0.1397 0.1397)
			(layers "F.Cu" "F.Mask" "F.Paste")
			(net "SW_HDD4_N")
			(options
				(clearance outline)
				(anchor circle)
			)
			(primitives
				(gr_poly
					(pts
						(arc
							(start -0.1778 -0.2794)
							(mid -0.249642 -0.249642)
							(end -0.2794 -0.1778)
						)
						(arc
							(start -0.2794 0.1778)
							(mid -0.249642 0.249642)
							(end -0.1778 0.2794)
						)
						(arc
							(start 0.1778 0.2794)
							(mid 0.249642 0.249642)
							(end 0.2794 0.1778)
						)
						(arc
							(start 0.2794 -0.1778)
							(mid 0.249642 -0.249642)
							(end 0.1778 -0.2794)
						)
					)
					(width 0)
					(fill yes)
				)
			)
		)
	)
	(footprint ""
		(layer "F.Cu")
		(at 4.445 -281.686 90)
		(property "Reference" "PC46"
			(at 0 0 90)
			(layer "F.SilkS")
			(hide yes)
			(effects
				(font
					(size 1.27 1.27)
				)
			)
		)
		(property "Value" "SC22U25V5MX-GP"
			(at -0.0762 -6.1214 90)
			(unlocked yes)
			(layer "F.Fab")
			(hide yes)
			(effects
				(font
					(size 1.016 1.016)
					(thickness 0.1524)
				)
			)
		)
		(property "Device Type" "C805H58"
			(at -0.0762 -8.1534 90)
			(unlocked yes)
			(layer "F.Fab")
			(hide yes)
			(effects
				(font
					(size 1.016 1.016)
					(thickness 0.1524)
				)
			)
		)
		(duplicate_pad_numbers_are_jumpers no)
		(fp_line
			(start 0.635 0)
			(end -0.635 0)
			(stroke
				(width 0.508)
				(type default)
			)
			(layer "F.SilkS")
		)
		(fp_rect
			(start -0.9652 1.778)
			(end 0.9652 -1.778)
			(stroke
				(width 0)
				(type default)
			)
			(fill no)
			(layer "F.CrtYd")
		)
		(fp_poly
			(pts
				(xy -0.9652 -1.778) (xy 0.9652 -1.778) (xy 0.9652 1.778) (xy -0.9652 1.778)
			)
			(stroke
				(width 0)
				(type default)
			)
			(fill no)
			(layer "F.Fab")
		)
		(pad "1" smd rect
			(at 0 -0.9652 90)
			(size 1.397 1.143)
			(layers "F.Cu" "F.Mask" "F.Paste")
			(net "P12V")
		)
		(pad "2" smd rect
			(at 0 0.9652 90)
			(size 1.397 1.143)
			(layers "F.Cu" "F.Mask" "F.Paste")
			(net "GND")
		)
	)
	(footprint ""
		(layer "F.Cu")
		(at 42.8244 -106.7562 90)
		(property "Reference" "R290"
			(at 0 0 90)
			(layer "F.SilkS")
			(hide yes)
			(effects
				(font
					(size 1.27 1.27)
				)
			)
		)
		(property "Value" "4K7R2J-2-GP"
			(at 0.064008 -3.993896 90)
			(unlocked yes)
			(layer "F.Fab")
			(hide yes)
			(effects
				(font
					(size 1.016 1.016)
					(thickness 0.1524)
				)
			)
		)
		(property "Device Type" "R402H16"
			(at 0.064008 -5.517896 90)
			(unlocked yes)
			(layer "F.Fab")
			(hide yes)
			(effects
				(font
					(size 1.016 1.016)
					(thickness 0.1524)
				)
			)
		)
		(duplicate_pad_numbers_are_jumpers no)
		(fp_line
			(start 0.508 -0.9398)
			(end -0.508 -0.9398)
			(stroke
				(width 0.1524)
				(type default)
			)
			(layer "F.SilkS")
		)
		(fp_line
			(start -0.508 -0.9398)
			(end -0.508 0.9398)
			(stroke
				(width 0.1524)
				(type default)
			)
			(layer "F.SilkS")
		)
		(fp_rect
			(start -0.508 0.9398)
			(end 0.508 -0.9398)
			(stroke
				(width 0)
				(type default)
			)
			(fill no)
			(layer "F.CrtYd")
		)
		(fp_rect
			(start -0.508 0.9398)
			(end 0.508 -0.9398)
			(stroke
				(width 0)
				(type default)
			)
			(fill no)
			(layer "F.Fab")
		)
		(pad "1" smd custom
			(at 0 -0.4445 90)
			(size 0.1397 0.1397)
			(layers "F.Cu" "F.Mask" "F.Paste")
			(net "P12V")
			(options
				(clearance outline)
				(anchor circle)
			)
			(primitives
				(gr_poly
					(pts
						(arc
							(start -0.1778 -0.2794)
							(mid -0.249642 -0.249642)
							(end -0.2794 -0.1778)
						)
						(arc
							(start -0.2794 0.1778)
							(mid -0.249642 0.249642)
							(end -0.1778 0.2794)
						)
						(arc
							(start 0.1778 0.2794)
							(mid 0.249642 0.249642)
							(end 0.2794 0.1778)
						)
						(arc
							(start 0.2794 -0.1778)
							(mid 0.249642 -0.249642)
							(end 0.1778 -0.2794)
						)
					)
					(width 0)
					(fill yes)
				)
			)
		)
		(pad "2" smd custom
			(at 0 0.4445 90)
			(size 0.1397 0.1397)
			(layers "F.Cu" "F.Mask" "F.Paste")
			(net "SW_HDD13_R")
			(options
				(clearance outline)
				(anchor circle)
			)
			(primitives
				(gr_poly
					(pts
						(arc
							(start -0.1778 -0.2794)
							(mid -0.249642 -0.249642)
							(end -0.2794 -0.1778)
						)
						(arc
							(start -0.2794 0.1778)
							(mid -0.249642 0.249642)
							(end -0.1778 0.2794)
						)
						(arc
							(start 0.1778 0.2794)
							(mid 0.249642 0.249642)
							(end 0.2794 0.1778)
						)
						(arc
							(start 0.2794 -0.1778)
							(mid 0.249642 -0.249642)
							(end 0.1778 -0.2794)
						)
					)
					(width 0)
					(fill yes)
				)
			)
		)
	)
	(footprint ""
		(layer "F.Cu")
		(at 217.757756 -489.105702 180)
		(property "Reference" "C106"
			(at 0 0 180)
			(layer "F.SilkS")
			(hide yes)
			(effects
				(font
					(size 1.27 1.27)
				)
			)
		)
		(property "Value" "SC1U16V3KX-5GP"
			(at 0 -2.8194 180)
			(unlocked yes)
			(layer "F.Fab")
			(hide yes)
			(effects
				(font
					(size 1.016 1.016)
					(thickness 0.1524)
				)
			)
		)
		(property "Device Type" "C603H36"
			(at 0 -4.3434 180)
			(unlocked yes)
			(layer "F.Fab")
			(hide yes)
			(effects
				(font
					(size 1.016 1.016)
					(thickness 0.1524)
				)
			)
		)
		(duplicate_pad_numbers_are_jumpers no)
		(fp_line
			(start 0.508 0)
			(end -0.508 0)
			(stroke
				(width 0.2032)
				(type default)
			)
			(layer "F.SilkS")
		)
		(fp_rect
			(start -0.5842 1.3335)
			(end 0.5842 -1.3335)
			(stroke
				(width 0)
				(type default)
			)
			(fill no)
			(layer "F.CrtYd")
		)
		(fp_rect
			(start -0.5842 1.3335)
			(end 0.5842 -1.3335)
			(stroke
				(width 0)
				(type default)
			)
			(fill no)
			(layer "F.Fab")
		)
		(pad "1" smd custom
			(at 0 -0.762 180)
			(size 0.2159 0.2159)
			(layers "F.Cu" "F.Mask" "F.Paste")
			(net "P5V_HDD0")
			(options
				(clearance outline)
				(anchor circle)
			)
			(primitives
				(gr_poly
					(pts
						(arc
							(start -0.3302 -0.4318)
							(mid -0.402042 -0.402042)
							(end -0.4318 -0.3302)
						)
						(arc
							(start -0.4318 0.3302)
							(mid -0.402042 0.402042)
							(end -0.3302 0.4318)
						)
						(arc
							(start 0.3302 0.4318)
							(mid 0.402042 0.402042)
							(end 0.4318 0.3302)
						)
						(arc
							(start 0.4318 -0.3302)
							(mid 0.402042 -0.402042)
							(end 0.3302 -0.4318)
						)
					)
					(width 0)
					(fill yes)
				)
			)
		)
		(pad "2" smd custom
			(at 0 0.762 180)
			(size 0.2159 0.2159)
			(layers "F.Cu" "F.Mask" "F.Paste")
			(net "GND")
			(options
				(clearance outline)
				(anchor circle)
			)
			(primitives
				(gr_poly
					(pts
						(arc
							(start -0.3302 -0.4318)
							(mid -0.402042 -0.402042)
							(end -0.4318 -0.3302)
						)
						(arc
							(start -0.4318 0.3302)
							(mid -0.402042 0.402042)
							(end -0.3302 0.4318)
						)
						(arc
							(start 0.3302 0.4318)
							(mid 0.402042 0.402042)
							(end 0.4318 0.3302)
						)
						(arc
							(start 0.4318 -0.3302)
							(mid 0.402042 -0.402042)
							(end 0.3302 -0.4318)
						)
					)
					(width 0)
					(fill yes)
				)
			)
		)
	)
	(footprint ""
		(layer "F.Cu")
		(at 27.812746 -308.257702 180)
		(property "Reference" "U36"
			(at 0 0 180)
			(layer "F.SilkS")
			(hide yes)
			(effects
				(font
					(size 1.27 1.27)
				)
			)
		)
		(property "Value" "74LVC1G08GW-1-GP"
			(at -2.3368 -8.6868 180)
			(unlocked yes)
			(layer "F.Fab")
			(hide yes)
			(effects
				(font
					(size 1.016 1.016)
					(thickness 0.1524)
				)
			)
		)
		(property "Device Type" "SC70-5H44"
			(at -2.3114 -10.414 180)
			(unlocked yes)
			(layer "F.Fab")
			(hide yes)
			(effects
				(font
					(size 1.016 1.016)
					(thickness 0.1524)
				)
			)
		)
		(duplicate_pad_numbers_are_jumpers no)
		(fp_line
			(start 1.3843 -1.8034)
			(end 1.3843 -1.1176)
			(stroke
				(width 0.3302)
				(type default)
			)
			(layer "F.SilkS")
		)
		(fp_line
			(start 1.27 1.7018)
			(end -1.27 1.7018)
			(stroke
				(width 0.1524)
				(type default)
			)
			(layer "F.SilkS")
		)
		(fp_line
			(start 1.27 -1.7018)
			(end 1.27 1.7018)
			(stroke
				(width 0.1524)
				(type default)
			)
			(layer "F.SilkS")
		)
		(fp_line
			(start 0.6604 -1.8034)
			(end 1.3843 -1.8034)
			(stroke
				(width 0.3302)
				(type default)
			)
			(layer "F.SilkS")
		)
		(fp_line
			(start -1.27 1.7018)
			(end -1.27 -1.7018)
			(stroke
				(width 0.1524)
				(type default)
			)
			(layer "F.SilkS")
		)
		(fp_line
			(start -1.27 -1.7018)
			(end 1.27 -1.7018)
			(stroke
				(width 0.1524)
				(type default)
			)
			(layer "F.SilkS")
		)
		(fp_rect
			(start -1.524 1.9558)
			(end 1.524 -1.9558)
			(stroke
				(width 0)
				(type default)
			)
			(fill no)
			(layer "F.CrtYd")
		)
		(fp_poly
			(pts
				(xy -1.524 -1.9558) (xy 1.524 -1.9558) (xy 1.524 1.9558) (xy -1.524 1.9558)
			)
			(stroke
				(width 0)
				(type default)
			)
			(fill no)
			(layer "F.Fab")
		)
		(pad "1" smd rect
			(at 0.65024 -0.8255 180)
			(size 0.4064 1.2192)
			(layers "F.Cu" "F.Mask" "F.Paste")
			(net "SAS_EXP_B_PWR11")
		)
		(pad "2" smd rect
			(at 0 -0.8255 180)
			(size 0.4064 1.2192)
			(layers "F.Cu" "F.Mask" "F.Paste")
			(net "SAS_EXP_A_PWR11")
		)
		(pad "3" smd rect
			(at -0.65024 -0.8255 180)
			(size 0.4064 1.2192)
			(layers "F.Cu" "F.Mask" "F.Paste")
			(net "GND")
		)
		(pad "4" smd rect
			(at -0.65024 0.8255 180)
			(size 0.4064 1.2192)
			(layers "F.Cu" "F.Mask" "F.Paste")
			(net "DRIVE_PWR11")
		)
		(pad "5" smd rect
			(at 0.65024 0.8255 180)
			(size 0.4064 1.2192)
			(layers "F.Cu" "F.Mask" "F.Paste")
			(net "P3V3")
		)
	)
	(footprint ""
		(layer "F.Cu")
		(at 27.634946 -417.452302)
		(property "Reference" "C275"
			(at 0 0 0)
			(layer "F.SilkS")
			(hide yes)
			(effects
				(font
					(size 1.27 1.27)
				)
			)
		)
		(property "Value" "SC10U25V6KX-1GP"
			(at -0.0762 -5.1308 0)
			(unlocked yes)
			(layer "F.Fab")
			(hide yes)
			(effects
				(font
					(size 1.016 1.016)
					(thickness 0.1524)
				)
			)
		)
		(property "Device Type" "C1206H71"
			(at -0.127 -6.6548 0)
			(unlocked yes)
			(layer "F.Fab")
			(hide yes)
			(effects
				(font
					(size 1.016 1.016)
					(thickness 0.1524)
				)
			)
		)
		(duplicate_pad_numbers_are_jumpers no)
		(fp_line
			(start -1.016 -2.2352)
			(end 1.016 -2.2352)
			(stroke
				(width 0.1524)
				(type default)
			)
			(layer "F.SilkS")
		)
		(fp_line
			(start -1.016 -0.8382)
			(end -1.016 -2.2352)
			(stroke
				(width 0.1524)
				(type default)
			)
			(layer "F.SilkS")
		)
		(fp_line
			(start -1.016 2.2352)
			(end -1.016 0.8382)
			(stroke
				(width 0.1524)
				(type default)
			)
			(layer "F.SilkS")
		)
		(fp_line
			(start 1.016 -2.2352)
			(end 1.016 -0.8382)
			(stroke
				(width 0.1524)
				(type default)
			)
			(layer "F.SilkS")
		)
		(fp_line
			(start 1.016 0.8382)
			(end 1.016 2.2352)
			(stroke
				(width 0.1524)
				(type default)
			)
			(layer "F.SilkS")
		)
		(fp_line
			(start 1.016 2.2352)
			(end -1.016 2.2352)
			(stroke
				(width 0.1524)
				(type default)
			)
			(layer "F.SilkS")
		)
		(fp_rect
			(start -1.0922 2.3114)
			(end 1.0922 -2.3114)
			(stroke
				(width 0)
				(type default)
			)
			(fill no)
			(layer "F.CrtYd")
		)
		(fp_poly
			(pts
				(xy 1.0922 -2.3114) (xy 1.0922 2.3114) (xy -1.0922 2.3114) (xy -1.0922 -2.3114)
			)
			(stroke
				(width 0)
				(type default)
			)
			(fill no)
			(layer "F.Fab")
		)
		(pad "1" smd rect
			(at 0 -1.397)
			(size 1.651 1.27)
			(layers "F.Cu" "F.Mask" "F.Paste")
			(net "P12V_HDD10")
		)
		(pad "2" smd rect
			(at 0 1.397)
			(size 1.651 1.27)
			(layers "F.Cu" "F.Mask" "F.Paste")
			(net "GND")
		)
	)
	(footprint ""
		(layer "F.Cu")
		(at 43.179746 -217.706702)
		(property "Reference" "C306"
			(at 0 0 0)
			(layer "F.SilkS")
			(hide yes)
			(effects
				(font
					(size 1.27 1.27)
				)
			)
		)
		(property "Value" "SC10U25V6KX-1GP"
			(at -0.0762 -5.1308 0)
			(unlocked yes)
			(layer "F.Fab")
			(hide yes)
			(effects
				(font
					(size 1.016 1.016)
					(thickness 0.1524)
				)
			)
		)
		(property "Device Type" "C1206H71"
			(at -0.127 -6.6548 0)
			(unlocked yes)
			(layer "F.Fab")
			(hide yes)
			(effects
				(font
					(size 1.016 1.016)
					(thickness 0.1524)
				)
			)
		)
		(duplicate_pad_numbers_are_jumpers no)
		(fp_line
			(start -1.016 -2.2352)
			(end 1.016 -2.2352)
			(stroke
				(width 0.1524)
				(type default)
			)
			(layer "F.SilkS")
		)
		(fp_line
			(start -1.016 -0.8382)
			(end -1.016 -2.2352)
			(stroke
				(width 0.1524)
				(type default)
			)
			(layer "F.SilkS")
		)
		(fp_line
			(start -1.016 2.2352)
			(end -1.016 0.8382)
			(stroke
				(width 0.1524)
				(type default)
			)
			(layer "F.SilkS")
		)
		(fp_line
			(start 1.016 -2.2352)
			(end 1.016 -0.8382)
			(stroke
				(width 0.1524)
				(type default)
			)
			(layer "F.SilkS")
		)
		(fp_line
			(start 1.016 0.8382)
			(end 1.016 2.2352)
			(stroke
				(width 0.1524)
				(type default)
			)
			(layer "F.SilkS")
		)
		(fp_line
			(start 1.016 2.2352)
			(end -1.016 2.2352)
			(stroke
				(width 0.1524)
				(type default)
			)
			(layer "F.SilkS")
		)
		(fp_rect
			(start -1.0922 2.3114)
			(end 1.0922 -2.3114)
			(stroke
				(width 0)
				(type default)
			)
			(fill no)
			(layer "F.CrtYd")
		)
		(fp_poly
			(pts
				(xy 1.0922 -2.3114) (xy 1.0922 2.3114) (xy -1.0922 2.3114) (xy -1.0922 -2.3114)
			)
			(stroke
				(width 0)
				(type default)
			)
			(fill no)
			(layer "F.Fab")
		)
		(pad "1" smd rect
			(at 0 -1.397)
			(size 1.651 1.27)
			(layers "F.Cu" "F.Mask" "F.Paste")
			(net "P12V_HDD12")
		)
		(pad "2" smd rect
			(at 0 1.397)
			(size 1.651 1.27)
			(layers "F.Cu" "F.Mask" "F.Paste")
			(net "GND")
		)
	)
	(footprint ""
		(layer "F.Cu")
		(at 102.234746 -14.2367 90)
		(property "Reference" "R305"
			(at 0 0 90)
			(layer "F.SilkS")
			(hide yes)
			(effects
				(font
					(size 1.27 1.27)
				)
			)
		)
		(property "Value" "1KR2F-3-GP"
			(at 0.064008 -3.993896 90)
			(unlocked yes)
			(layer "F.Fab")
			(hide yes)
			(effects
				(font
					(size 1.016 1.016)
					(thickness 0.1524)
				)
			)
		)
		(property "Device Type" "R402H16"
			(at 0.064008 -5.517896 90)
			(unlocked yes)
			(layer "F.Fab")
			(hide yes)
			(effects
				(font
					(size 1.016 1.016)
					(thickness 0.1524)
				)
			)
		)
		(duplicate_pad_numbers_are_jumpers no)
		(fp_line
			(start 0.508 -0.9398)
			(end -0.508 -0.9398)
			(stroke
				(width 0.1524)
				(type default)
			)
			(layer "F.SilkS")
		)
		(fp_line
			(start -0.508 -0.9398)
			(end -0.508 0.9398)
			(stroke
				(width 0.1524)
				(type default)
			)
			(layer "F.SilkS")
		)
		(fp_rect
			(start -0.508 0.9398)
			(end 0.508 -0.9398)
			(stroke
				(width 0)
				(type default)
			)
			(fill no)
			(layer "F.CrtYd")
		)
		(fp_rect
			(start -0.508 0.9398)
			(end 0.508 -0.9398)
			(stroke
				(width 0)
				(type default)
			)
			(fill no)
			(layer "F.Fab")
		)
		(pad "1" smd custom
			(at 0 -0.4445 90)
			(size 0.1397 0.1397)
			(layers "F.Cu" "F.Mask" "F.Paste")
			(net "P3V3")
			(options
				(clearance outline)
				(anchor circle)
			)
			(primitives
				(gr_poly
					(pts
						(arc
							(start -0.1778 -0.2794)
							(mid -0.249642 -0.249642)
							(end -0.2794 -0.1778)
						)
						(arc
							(start -0.2794 0.1778)
							(mid -0.249642 0.249642)
							(end -0.1778 0.2794)
						)
						(arc
							(start 0.1778 0.2794)
							(mid 0.249642 0.249642)
							(end 0.2794 0.1778)
						)
						(arc
							(start 0.2794 -0.1778)
							(mid 0.249642 -0.249642)
							(end 0.1778 -0.2794)
						)
					)
					(width 0)
					(fill yes)
				)
			)
		)
		(pad "2" smd custom
			(at 0 0.4445 90)
			(size 0.1397 0.1397)
			(layers "F.Cu" "F.Mask" "F.Paste")
			(net "SW_PWR_HDD14")
			(options
				(clearance outline)
				(anchor circle)
			)
			(primitives
				(gr_poly
					(pts
						(arc
							(start -0.1778 -0.2794)
							(mid -0.249642 -0.249642)
							(end -0.2794 -0.1778)
						)
						(arc
							(start -0.2794 0.1778)
							(mid -0.249642 0.249642)
							(end -0.1778 0.2794)
						)
						(arc
							(start 0.1778 0.2794)
							(mid 0.249642 0.249642)
							(end 0.2794 0.1778)
						)
						(arc
							(start 0.2794 -0.1778)
							(mid 0.249642 -0.249642)
							(end 0.1778 -0.2794)
						)
					)
					(width 0)
					(fill yes)
				)
			)
		)
	)
	(footprint ""
		(layer "F.Cu")
		(at 27.304746 -436.019702 90)
		(property "Reference" "R460"
			(at 0 0 90)
			(layer "F.SilkS")
			(hide yes)
			(effects
				(font
					(size 1.27 1.27)
				)
			)
		)
		(property "Value" "4K7R2J-2-GP"
			(at 0.064008 -3.993896 90)
			(unlocked yes)
			(layer "F.Fab")
			(hide yes)
			(effects
				(font
					(size 1.016 1.016)
					(thickness 0.1524)
				)
			)
		)
		(property "Device Type" "R402H16"
			(at 0.064008 -5.517896 90)
			(unlocked yes)
			(layer "F.Fab")
			(hide yes)
			(effects
				(font
					(size 1.016 1.016)
					(thickness 0.1524)
				)
			)
		)
		(duplicate_pad_numbers_are_jumpers no)
		(fp_line
			(start 0.508 -0.9398)
			(end -0.508 -0.9398)
			(stroke
				(width 0.1524)
				(type default)
			)
			(layer "F.SilkS")
		)
		(fp_line
			(start -0.508 -0.9398)
			(end -0.508 0.9398)
			(stroke
				(width 0.1524)
				(type default)
			)
			(layer "F.SilkS")
		)
		(fp_rect
			(start -0.508 0.9398)
			(end 0.508 -0.9398)
			(stroke
				(width 0)
				(type default)
			)
			(fill no)
			(layer "F.CrtYd")
		)
		(fp_rect
			(start -0.508 0.9398)
			(end 0.508 -0.9398)
			(stroke
				(width 0)
				(type default)
			)
			(fill no)
			(layer "F.Fab")
		)
		(pad "1" smd custom
			(at 0 -0.4445 90)
			(size 0.1397 0.1397)
			(layers "F.Cu" "F.Mask" "F.Paste")
			(net "P3V3")
			(options
				(clearance outline)
				(anchor circle)
			)
			(primitives
				(gr_poly
					(pts
						(arc
							(start -0.1778 -0.2794)
							(mid -0.249642 -0.249642)
							(end -0.2794 -0.1778)
						)
						(arc
							(start -0.2794 0.1778)
							(mid -0.249642 0.249642)
							(end -0.1778 0.2794)
						)
						(arc
							(start 0.1778 0.2794)
							(mid 0.249642 0.249642)
							(end 0.2794 0.1778)
						)
						(arc
							(start 0.2794 -0.1778)
							(mid 0.249642 -0.249642)
							(end 0.1778 -0.2794)
						)
					)
					(width 0)
					(fill yes)
				)
			)
		)
		(pad "2" smd custom
			(at 0 0.4445 90)
			(size 0.1397 0.1397)
			(layers "F.Cu" "F.Mask" "F.Paste")
			(net "SAS2X28_A_HDD10_FLT")
			(options
				(clearance outline)
				(anchor circle)
			)
			(primitives
				(gr_poly
					(pts
						(arc
							(start -0.1778 -0.2794)
							(mid -0.249642 -0.249642)
							(end -0.2794 -0.1778)
						)
						(arc
							(start -0.2794 0.1778)
							(mid -0.249642 0.249642)
							(end -0.1778 0.2794)
						)
						(arc
							(start 0.1778 0.2794)
							(mid 0.249642 0.249642)
							(end 0.2794 0.1778)
						)
						(arc
							(start 0.2794 -0.1778)
							(mid 0.249642 -0.249642)
							(end 0.1778 -0.2794)
						)
					)
					(width 0)
					(fill yes)
				)
			)
		)
	)
	(footprint ""
		(layer "F.Cu")
		(at 208.026 -478.79 -90)
		(property "Reference" "Q31"
			(at 0 0 270)
			(layer "F.SilkS")
			(hide yes)
			(effects
				(font
					(size 1.27 1.27)
				)
			)
		)
		(property "Value" "2N7002DW-7F-GP"
			(at -2.3622 -8.2042 270)
			(unlocked yes)
			(layer "F.Fab")
			(hide yes)
			(effects
				(font
					(size 1.016 1.016)
					(thickness 0.1524)
				)
			)
		)
		(property "Device Type" "SOT-363H44"
			(at -2.3622 -10.1092 270)
			(unlocked yes)
			(layer "F.Fab")
			(hide yes)
			(effects
				(font
					(size 1.016 1.016)
					(thickness 0.1524)
				)
			)
		)
		(duplicate_pad_numbers_are_jumpers no)
		(fp_line
			(start -1.4478 1.7018)
			(end 1.4478 1.7018)
			(stroke
				(width 0.1524)
				(type default)
			)
			(layer "F.SilkS")
		)
		(fp_line
			(start 1.4478 1.7018)
			(end 1.4478 -1.7018)
			(stroke
				(width 0.1524)
				(type default)
			)
			(layer "F.SilkS")
		)
		(fp_line
			(start -1.27 1.524)
			(end -1.27 0.6604)
			(stroke
				(width 0.4826)
				(type default)
			)
			(layer "F.SilkS")
		)
		(fp_line
			(start -1.4478 -1.7018)
			(end -1.4478 1.7018)
			(stroke
				(width 0.1524)
				(type default)
			)
			(layer "F.SilkS")
		)
		(fp_line
			(start 1.4478 -1.7018)
			(end -1.4478 -1.7018)
			(stroke
				(width 0.1524)
				(type default)
			)
			(layer "F.SilkS")
		)
		(fp_poly
			(pts
				(xy -1.524 -1.778) (xy 1.524 -1.778) (xy 1.524 1.778) (xy -1.524 1.778)
			)
			(stroke
				(width 0)
				(type default)
			)
			(fill no)
			(layer "F.CrtYd")
		)
		(fp_poly
			(pts
				(xy -1.524 -1.778) (xy 1.524 -1.778) (xy 1.524 1.778) (xy -1.524 1.778)
			)
			(stroke
				(width 0)
				(type default)
			)
			(fill no)
			(layer "F.Fab")
		)
		(pad "1" smd rect
			(at -0.65024 0.9398 270)
			(size 0.4064 1.016)
			(layers "F.Cu" "F.Mask" "F.Paste")
			(net "P3V3_HDD0_LED")
		)
		(pad "2" smd rect
			(at 0 0.9398 270)
			(size 0.4064 1.016)
			(layers "F.Cu" "F.Mask" "F.Paste")
			(net "HDD0_LED_G")
		)
		(pad "3" smd rect
			(at 0.65024 0.9398 270)
			(size 0.4064 1.016)
			(layers "F.Cu" "F.Mask" "F.Paste")
			(net "P5VA")
		)
		(pad "4" smd rect
			(at 0.65024 -0.9398 270)
			(size 0.4064 1.016)
			(layers "F.Cu" "F.Mask" "F.Paste")
			(net "P5VA_HDD0_LED")
		)
		(pad "5" smd rect
			(at 0 -0.9398 270)
			(size 0.4064 1.016)
			(layers "F.Cu" "F.Mask" "F.Paste")
			(net "HDD0_LED_G")
		)
		(pad "6" smd rect
			(at -0.65024 -0.9398 270)
			(size 0.4064 1.016)
			(layers "F.Cu" "F.Mask" "F.Paste")
			(net "P3V3")
		)
	)
	(footprint ""
		(layer "F.Cu")
		(at 193.167 -193.421 90)
		(property "Reference" "D18"
			(at 0 0 90)
			(layer "F.SilkS")
			(hide yes)
			(effects
				(font
					(size 1.27 1.27)
				)
			)
		)
		(property "Value" "RB551V30-1-GP"
			(at 0 -6.7818 90)
			(unlocked yes)
			(layer "F.Fab")
			(hide yes)
			(effects
				(font
					(size 1.016 1.016)
					(thickness 0.1524)
				)
			)
		)
		(property "Device Type" "SOD323AKH44"
			(at 0 -8.6868 90)
			(unlocked yes)
			(layer "F.Fab")
			(hide yes)
			(effects
				(font
					(size 1.016 1.016)
					(thickness 0.1524)
				)
			)
		)
		(duplicate_pad_numbers_are_jumpers no)
		(fp_line
			(start 0.889 -1.9304)
			(end 0.889 2.159)
			(stroke
				(width 0.1524)
				(type default)
			)
			(layer "F.SilkS")
		)
		(fp_line
			(start -0.889 -1.9304)
			(end 0.889 -1.9304)
			(stroke
				(width 0.1524)
				(type default)
			)
			(layer "F.SilkS")
		)
		(fp_line
			(start 0.762 2.0574)
			(end -0.762 2.0574)
			(stroke
				(width 0.508)
				(type default)
			)
			(layer "F.SilkS")
		)
		(fp_line
			(start 0.889 2.159)
			(end -0.889 2.159)
			(stroke
				(width 0.1524)
				(type default)
			)
			(layer "F.SilkS")
		)
		(fp_line
			(start -0.889 2.159)
			(end -0.889 -1.9304)
			(stroke
				(width 0.1524)
				(type default)
			)
			(layer "F.SilkS")
		)
		(fp_rect
			(start -1.016 2.3114)
			(end 1.016 -2.0066)
			(stroke
				(width 0)
				(type default)
			)
			(fill no)
			(layer "F.CrtYd")
		)
		(fp_poly
			(pts
				(xy -1.016 -2.0066) (xy 1.016 -2.0066) (xy 1.016 2.3114) (xy -1.016 2.3114)
			)
			(stroke
				(width 0)
				(type default)
			)
			(fill no)
			(layer "F.Fab")
		)
		(pad "A" smd rect
			(at 0 -1.143 90)
			(size 0.5588 1.016)
			(layers "F.Cu" "F.Mask" "F.Paste")
			(net "SW_HDD3_R")
		)
		(pad "K" smd rect
			(at 0 1.143 90)
			(size 0.5588 1.016)
			(layers "F.Cu" "F.Mask" "F.Paste")
			(net "SW_HDD3_N")
		)
	)
	(footprint ""
		(layer "F.Cu")
		(at 194.183 -77.851)
		(property "Reference" "C171"
			(at 0 0 0)
			(layer "F.SilkS")
			(hide yes)
			(effects
				(font
					(size 1.27 1.27)
				)
			)
		)
		(property "Value" "SCD1U10V2KX-5GP"
			(at 1.1811 -2.7051 0)
			(unlocked yes)
			(layer "F.Fab")
			(hide yes)
			(effects
				(font
					(size 1.016 1.016)
					(thickness 0.1524)
				)
			)
		)
		(property "Device Type" "C402H22"
			(at 1.1811 -4.2291 0)
			(unlocked yes)
			(layer "F.Fab")
			(hide yes)
			(effects
				(font
					(size 1.016 1.016)
					(thickness 0.1524)
				)
			)
		)
		(duplicate_pad_numbers_are_jumpers no)
		(fp_rect
			(start -0.4318 0.9525)
			(end 0.4318 -0.9525)
			(stroke
				(width 0)
				(type default)
			)
			(fill no)
			(layer "F.CrtYd")
		)
		(fp_rect
			(start -0.4318 0.9525)
			(end 0.4318 -0.9525)
			(stroke
				(width 0)
				(type default)
			)
			(fill no)
			(layer "F.Fab")
		)
		(pad "1" smd custom
			(at 0 -0.4445)
			(size 0.1524 0.1524)
			(layers "F.Cu" "F.Mask" "F.Paste")
			(net "P3V3")
			(options
				(clearance outline)
				(anchor circle)
			)
			(primitives
				(gr_poly
					(pts
						(arc
							(start 0.3048 -0.2032)
							(mid 0.275042 -0.275042)
							(end 0.2032 -0.3048)
						)
						(arc
							(start -0.2032 -0.3048)
							(mid -0.275042 -0.275042)
							(end -0.3048 -0.2032)
						)
						(arc
							(start -0.3048 0.2032)
							(mid -0.275042 0.275042)
							(end -0.2032 0.3048)
						)
						(arc
							(start 0.2032 0.3048)
							(mid 0.275042 0.275042)
							(end 0.3048 0.2032)
						)
					)
					(width 0)
					(fill yes)
				)
			)
		)
		(pad "2" smd custom
			(at 0 0.4445)
			(size 0.1524 0.1524)
			(layers "F.Cu" "F.Mask" "F.Paste")
			(net "GND")
			(options
				(clearance outline)
				(anchor circle)
			)
			(primitives
				(gr_poly
					(pts
						(arc
							(start 0.3048 -0.2032)
							(mid 0.275042 -0.275042)
							(end 0.2032 -0.3048)
						)
						(arc
							(start -0.2032 -0.3048)
							(mid -0.275042 -0.275042)
							(end -0.3048 -0.2032)
						)
						(arc
							(start -0.3048 0.2032)
							(mid -0.275042 0.275042)
							(end -0.2032 0.3048)
						)
						(arc
							(start 0.2032 0.3048)
							(mid 0.275042 0.275042)
							(end 0.3048 0.2032)
						)
					)
					(width 0)
					(fill yes)
				)
			)
		)
	)
	(footprint ""
		(layer "F.Cu")
		(at 51.180746 -25.2857 180)
		(property "Reference" "PR17"
			(at 0 0 180)
			(layer "F.SilkS")
			(hide yes)
			(effects
				(font
					(size 1.27 1.27)
				)
			)
		)
		(property "Value" "2K49R2F-GP"
			(at 0.064008 -3.993896 180)
			(unlocked yes)
			(layer "F.Fab")
			(hide yes)
			(effects
				(font
					(size 1.016 1.016)
					(thickness 0.1524)
				)
			)
		)
		(property "Device Type" "R402H16"
			(at 0.064008 -5.517896 180)
			(unlocked yes)
			(layer "F.Fab")
			(hide yes)
			(effects
				(font
					(size 1.016 1.016)
					(thickness 0.1524)
				)
			)
		)
		(duplicate_pad_numbers_are_jumpers no)
		(fp_line
			(start 0.508 -0.9398)
			(end -0.508 -0.9398)
			(stroke
				(width 0.1524)
				(type default)
			)
			(layer "F.SilkS")
		)
		(fp_line
			(start -0.508 -0.9398)
			(end -0.508 0.9398)
			(stroke
				(width 0.1524)
				(type default)
			)
			(layer "F.SilkS")
		)
		(fp_rect
			(start -0.508 0.9398)
			(end 0.508 -0.9398)
			(stroke
				(width 0)
				(type default)
			)
			(fill no)
			(layer "F.CrtYd")
		)
		(fp_rect
			(start -0.508 0.9398)
			(end 0.508 -0.9398)
			(stroke
				(width 0)
				(type default)
			)
			(fill no)
			(layer "F.Fab")
		)
		(pad "1" smd custom
			(at 0 -0.4445 180)
			(size 0.1397 0.1397)
			(layers "F.Cu" "F.Mask" "F.Paste")
			(net "P5VB_EN")
			(options
				(clearance outline)
				(anchor circle)
			)
			(primitives
				(gr_poly
					(pts
						(arc
							(start -0.1778 -0.2794)
							(mid -0.249642 -0.249642)
							(end -0.2794 -0.1778)
						)
						(arc
							(start -0.2794 0.1778)
							(mid -0.249642 0.249642)
							(end -0.1778 0.2794)
						)
						(arc
							(start 0.1778 0.2794)
							(mid 0.249642 0.249642)
							(end 0.2794 0.1778)
						)
						(arc
							(start 0.2794 -0.1778)
							(mid 0.249642 -0.249642)
							(end 0.1778 -0.2794)
						)
					)
					(width 0)
					(fill yes)
				)
			)
		)
		(pad "2" smd custom
			(at 0 0.4445 180)
			(size 0.1397 0.1397)
			(layers "F.Cu" "F.Mask" "F.Paste")
			(net "GND")
			(options
				(clearance outline)
				(anchor circle)
			)
			(primitives
				(gr_poly
					(pts
						(arc
							(start -0.1778 -0.2794)
							(mid -0.249642 -0.249642)
							(end -0.2794 -0.1778)
						)
						(arc
							(start -0.2794 0.1778)
							(mid -0.249642 0.249642)
							(end -0.1778 0.2794)
						)
						(arc
							(start 0.1778 0.2794)
							(mid 0.249642 0.249642)
							(end 0.2794 0.1778)
						)
						(arc
							(start 0.2794 -0.1778)
							(mid 0.249642 -0.249642)
							(end 0.1778 -0.2794)
						)
					)
					(width 0)
					(fill yes)
				)
			)
		)
	)
	(footprint ""
		(layer "F.Cu")
		(at 74.421746 -22.380702 180)
		(property "Reference" "C332"
			(at 0 0 180)
			(layer "F.SilkS")
			(hide yes)
			(effects
				(font
					(size 1.27 1.27)
				)
			)
		)
		(property "Value" "SCD01U50V2KX-1GP"
			(at 1.1811 -2.7051 180)
			(unlocked yes)
			(layer "F.Fab")
			(hide yes)
			(effects
				(font
					(size 1.016 1.016)
					(thickness 0.1524)
				)
			)
		)
		(property "Device Type" "C402H22"
			(at 1.1811 -4.2291 180)
			(unlocked yes)
			(layer "F.Fab")
			(hide yes)
			(effects
				(font
					(size 1.016 1.016)
					(thickness 0.1524)
				)
			)
		)
		(duplicate_pad_numbers_are_jumpers no)
		(fp_rect
			(start -0.4318 0.9525)
			(end 0.4318 -0.9525)
			(stroke
				(width 0)
				(type default)
			)
			(fill no)
			(layer "F.CrtYd")
		)
		(fp_rect
			(start -0.4318 0.9525)
			(end 0.4318 -0.9525)
			(stroke
				(width 0)
				(type default)
			)
			(fill no)
			(layer "F.Fab")
		)
		(pad "1" smd custom
			(at 0 -0.4445 180)
			(size 0.1524 0.1524)
			(layers "F.Cu" "F.Mask" "F.Paste")
			(net "HDD_PRSNT_NET14")
			(options
				(clearance outline)
				(anchor circle)
			)
			(primitives
				(gr_poly
					(pts
						(arc
							(start 0.3048 -0.2032)
							(mid 0.275042 -0.275042)
							(end 0.2032 -0.3048)
						)
						(arc
							(start -0.2032 -0.3048)
							(mid -0.275042 -0.275042)
							(end -0.3048 -0.2032)
						)
						(arc
							(start -0.3048 0.2032)
							(mid -0.275042 0.275042)
							(end -0.2032 0.3048)
						)
						(arc
							(start 0.2032 0.3048)
							(mid 0.275042 0.275042)
							(end 0.3048 0.2032)
						)
					)
					(width 0)
					(fill yes)
				)
			)
		)
		(pad "2" smd custom
			(at 0 0.4445 180)
			(size 0.1524 0.1524)
			(layers "F.Cu" "F.Mask" "F.Paste")
			(net "GND")
			(options
				(clearance outline)
				(anchor circle)
			)
			(primitives
				(gr_poly
					(pts
						(arc
							(start 0.3048 -0.2032)
							(mid 0.275042 -0.275042)
							(end 0.2032 -0.3048)
						)
						(arc
							(start -0.2032 -0.3048)
							(mid -0.275042 -0.275042)
							(end -0.3048 -0.2032)
						)
						(arc
							(start -0.3048 0.2032)
							(mid -0.275042 0.275042)
							(end -0.2032 0.3048)
						)
						(arc
							(start 0.2032 0.3048)
							(mid 0.275042 0.275042)
							(end 0.3048 0.2032)
						)
					)
					(width 0)
					(fill yes)
				)
			)
		)
	)
	(footprint ""
		(layer "F.Cu")
		(at 218.185746 -78.4987 180)
		(property "Reference" "C172"
			(at 0 0 180)
			(layer "F.SilkS")
			(hide yes)
			(effects
				(font
					(size 1.27 1.27)
				)
			)
		)
		(property "Value" "SC1U16V3KX-5GP"
			(at 0 -2.8194 180)
			(unlocked yes)
			(layer "F.Fab")
			(hide yes)
			(effects
				(font
					(size 1.016 1.016)
					(thickness 0.1524)
				)
			)
		)
		(property "Device Type" "C603H36"
			(at 0 -4.3434 180)
			(unlocked yes)
			(layer "F.Fab")
			(hide yes)
			(effects
				(font
					(size 1.016 1.016)
					(thickness 0.1524)
				)
			)
		)
		(duplicate_pad_numbers_are_jumpers no)
		(fp_line
			(start 0.508 0)
			(end -0.508 0)
			(stroke
				(width 0.2032)
				(type default)
			)
			(layer "F.SilkS")
		)
		(fp_rect
			(start -0.5842 1.3335)
			(end 0.5842 -1.3335)
			(stroke
				(width 0)
				(type default)
			)
			(fill no)
			(layer "F.CrtYd")
		)
		(fp_rect
			(start -0.5842 1.3335)
			(end 0.5842 -1.3335)
			(stroke
				(width 0)
				(type default)
			)
			(fill no)
			(layer "F.Fab")
		)
		(pad "1" smd custom
			(at 0 -0.762 180)
			(size 0.2159 0.2159)
			(layers "F.Cu" "F.Mask" "F.Paste")
			(net "P5V_HDD4")
			(options
				(clearance outline)
				(anchor circle)
			)
			(primitives
				(gr_poly
					(pts
						(arc
							(start -0.3302 -0.4318)
							(mid -0.402042 -0.402042)
							(end -0.4318 -0.3302)
						)
						(arc
							(start -0.4318 0.3302)
							(mid -0.402042 0.402042)
							(end -0.3302 0.4318)
						)
						(arc
							(start 0.3302 0.4318)
							(mid 0.402042 0.402042)
							(end 0.4318 0.3302)
						)
						(arc
							(start 0.4318 -0.3302)
							(mid 0.402042 -0.402042)
							(end 0.3302 -0.4318)
						)
					)
					(width 0)
					(fill yes)
				)
			)
		)
		(pad "2" smd custom
			(at 0 0.762 180)
			(size 0.2159 0.2159)
			(layers "F.Cu" "F.Mask" "F.Paste")
			(net "GND")
			(options
				(clearance outline)
				(anchor circle)
			)
			(primitives
				(gr_poly
					(pts
						(arc
							(start -0.3302 -0.4318)
							(mid -0.402042 -0.402042)
							(end -0.4318 -0.3302)
						)
						(arc
							(start -0.4318 0.3302)
							(mid -0.402042 0.402042)
							(end -0.3302 0.4318)
						)
						(arc
							(start 0.3302 0.4318)
							(mid 0.402042 0.402042)
							(end 0.4318 0.3302)
						)
						(arc
							(start 0.4318 -0.3302)
							(mid 0.402042 -0.402042)
							(end 0.3302 -0.4318)
						)
					)
					(width 0)
					(fill yes)
				)
			)
		)
	)
	(footprint ""
		(layer "F.Cu")
		(at 57.276746 -183.0197 180)
		(property "Reference" "C237"
			(at 0 0 180)
			(layer "F.SilkS")
			(hide yes)
			(effects
				(font
					(size 1.27 1.27)
				)
			)
		)
		(property "Value" "SC10U16V6KX-2GP"
			(at -0.0762 -5.1308 180)
			(unlocked yes)
			(layer "F.Fab")
			(hide yes)
			(effects
				(font
					(size 1.016 1.016)
					(thickness 0.1524)
				)
			)
		)
		(property "Device Type" "C1206H71"
			(at -0.127 -6.6548 180)
			(unlocked yes)
			(layer "F.Fab")
			(hide yes)
			(effects
				(font
					(size 1.016 1.016)
					(thickness 0.1524)
				)
			)
		)
		(duplicate_pad_numbers_are_jumpers no)
		(fp_line
			(start 1.016 2.2352)
			(end -1.016 2.2352)
			(stroke
				(width 0.1524)
				(type default)
			)
			(layer "F.SilkS")
		)
		(fp_line
			(start 1.016 0.8382)
			(end 1.016 2.2352)
			(stroke
				(width 0.1524)
				(type default)
			)
			(layer "F.SilkS")
		)
		(fp_line
			(start 1.016 -2.2352)
			(end 1.016 -0.8382)
			(stroke
				(width 0.1524)
				(type default)
			)
			(layer "F.SilkS")
		)
		(fp_line
			(start -1.016 2.2352)
			(end -1.016 0.8382)
			(stroke
				(width 0.1524)
				(type default)
			)
			(layer "F.SilkS")
		)
		(fp_line
			(start -1.016 -0.8382)
			(end -1.016 -2.2352)
			(stroke
				(width 0.1524)
				(type default)
			)
			(layer "F.SilkS")
		)
		(fp_line
			(start -1.016 -2.2352)
			(end 1.016 -2.2352)
			(stroke
				(width 0.1524)
				(type default)
			)
			(layer "F.SilkS")
		)
		(fp_rect
			(start -1.0922 2.3114)
			(end 1.0922 -2.3114)
			(stroke
				(width 0)
				(type default)
			)
			(fill no)
			(layer "F.CrtYd")
		)
		(fp_poly
			(pts
				(xy 1.0922 -2.3114) (xy 1.0922 2.3114) (xy -1.0922 2.3114) (xy -1.0922 -2.3114)
			)
			(stroke
				(width 0)
				(type default)
			)
			(fill no)
			(layer "F.Fab")
		)
		(pad "1" smd rect
			(at 0 -1.397 180)
			(size 1.651 1.27)
			(layers "F.Cu" "F.Mask" "F.Paste")
			(net "P5V_HDD8")
		)
		(pad "2" smd rect
			(at 0 1.397 180)
			(size 1.651 1.27)
			(layers "F.Cu" "F.Mask" "F.Paste")
			(net "GND")
		)
	)
	(footprint ""
		(layer "F.Cu")
		(at 240.918746 -27.9527)
		(property "Reference" "PR7"
			(at 0 0 0)
			(layer "F.SilkS")
			(hide yes)
			(effects
				(font
					(size 1.27 1.27)
				)
			)
		)
		(property "Value" "0R2J-2-GP"
			(at 0.064008 -3.993896 0)
			(unlocked yes)
			(layer "F.Fab")
			(hide yes)
			(effects
				(font
					(size 1.016 1.016)
					(thickness 0.1524)
				)
			)
		)
		(property "Device Type" "R402H16"
			(at 0.064008 -5.517896 0)
			(unlocked yes)
			(layer "F.Fab")
			(hide yes)
			(effects
				(font
					(size 1.016 1.016)
					(thickness 0.1524)
				)
			)
		)
		(duplicate_pad_numbers_are_jumpers no)
		(fp_line
			(start -0.508 -0.9398)
			(end -0.508 0.9398)
			(stroke
				(width 0.1524)
				(type default)
			)
			(layer "F.SilkS")
		)
		(fp_line
			(start 0.508 -0.9398)
			(end -0.508 -0.9398)
			(stroke
				(width 0.1524)
				(type default)
			)
			(layer "F.SilkS")
		)
		(fp_rect
			(start -0.508 0.9398)
			(end 0.508 -0.9398)
			(stroke
				(width 0)
				(type default)
			)
			(fill no)
			(layer "F.CrtYd")
		)
		(fp_rect
			(start -0.508 0.9398)
			(end 0.508 -0.9398)
			(stroke
				(width 0)
				(type default)
			)
			(fill no)
			(layer "F.Fab")
		)
		(pad "1" smd custom
			(at 0 -0.4445)
			(size 0.1397 0.1397)
			(layers "F.Cu" "F.Mask" "F.Paste")
			(net "P5VA_MODE_PG")
			(options
				(clearance outline)
				(anchor circle)
			)
			(primitives
				(gr_poly
					(pts
						(arc
							(start -0.1778 -0.2794)
							(mid -0.249642 -0.249642)
							(end -0.2794 -0.1778)
						)
						(arc
							(start -0.2794 0.1778)
							(mid -0.249642 0.249642)
							(end -0.1778 0.2794)
						)
						(arc
							(start 0.1778 0.2794)
							(mid 0.249642 0.249642)
							(end 0.2794 0.1778)
						)
						(arc
							(start 0.2794 -0.1778)
							(mid 0.249642 -0.249642)
							(end 0.1778 -0.2794)
						)
					)
					(width 0)
					(fill yes)
				)
			)
		)
		(pad "2" smd custom
			(at 0 0.4445)
			(size 0.1397 0.1397)
			(layers "F.Cu" "F.Mask" "F.Paste")
			(net "P5VA_MODE")
			(options
				(clearance outline)
				(anchor circle)
			)
			(primitives
				(gr_poly
					(pts
						(arc
							(start -0.1778 -0.2794)
							(mid -0.249642 -0.249642)
							(end -0.2794 -0.1778)
						)
						(arc
							(start -0.2794 0.1778)
							(mid -0.249642 0.249642)
							(end -0.1778 0.2794)
						)
						(arc
							(start 0.1778 0.2794)
							(mid 0.249642 0.249642)
							(end 0.2794 0.1778)
						)
						(arc
							(start 0.2794 -0.1778)
							(mid 0.249642 -0.249642)
							(end 0.1778 -0.2794)
						)
					)
					(width 0)
					(fill yes)
				)
			)
		)
	)
	(footprint ""
		(layer "F.Cu")
		(at 212.5218 -68.8848 180)
		(property "Reference" "Q55"
			(at 0 0 180)
			(layer "F.SilkS")
			(hide yes)
			(effects
				(font
					(size 1.27 1.27)
				)
			)
		)
		(property "Value" "2N7002-11-GP"
			(at 0.127 -8.9662 180)
			(unlocked yes)
			(layer "F.Fab")
			(hide yes)
			(effects
				(font
					(size 1.016 1.016)
					(thickness 0.1524)
				)
			)
		)
		(property "Device Type" "SOT23DGS2D4H44"
			(at 0.127 -10.4902 180)
			(unlocked yes)
			(layer "F.Fab")
			(hide yes)
			(effects
				(font
					(size 1.016 1.016)
					(thickness 0.1524)
				)
			)
		)
		(duplicate_pad_numbers_are_jumpers no)
		(fp_line
			(start 1.651 1.778)
			(end 1.651 -1.778)
			(stroke
				(width 0.1524)
				(type default)
			)
			(layer "F.SilkS")
		)
		(fp_line
			(start 1.651 -1.778)
			(end -1.651 -1.778)
			(stroke
				(width 0.1524)
				(type default)
			)
			(layer "F.SilkS")
		)
		(fp_line
			(start -1.651 1.778)
			(end 1.651 1.778)
			(stroke
				(width 0.1524)
				(type default)
			)
			(layer "F.SilkS")
		)
		(fp_line
			(start -1.651 -1.778)
			(end -1.651 1.778)
			(stroke
				(width 0.1524)
				(type default)
			)
			(layer "F.SilkS")
		)
		(fp_poly
			(pts
				(xy -1.778 1.8796) (xy -1.778 -1.8796) (xy 1.778 -1.8796) (xy 1.778 1.8796)
			)
			(stroke
				(width 0)
				(type default)
			)
			(fill no)
			(layer "F.CrtYd")
		)
		(fp_poly
			(pts
				(xy -1.778 1.8796) (xy -1.778 -1.8796) (xy 1.778 -1.8796) (xy 1.778 1.8796)
			)
			(stroke
				(width 0)
				(type default)
			)
			(fill no)
			(layer "F.Fab")
		)
		(pad "D" smd custom
			(at 0 -0.9525 180)
			(size 0.1905 0.1905)
			(layers "F.Cu" "F.Mask" "F.Paste")
			(net "HDD4_LED_G")
			(options
				(clearance outline)
				(anchor circle)
			)
			(primitives
				(gr_poly
					(pts
						(arc
							(start -0.1778 0.5715)
							(mid -0.321484 0.511984)
							(end -0.381 0.3683)
						)
						(arc
							(start -0.381 -0.3683)
							(mid -0.321484 -0.511984)
							(end -0.1778 -0.5715)
						)
						(arc
							(start 0.1778 -0.5715)
							(mid 0.321484 -0.511984)
							(end 0.381 -0.3683)
						)
						(arc
							(start 0.381 0.3683)
							(mid 0.321484 0.511984)
							(end 0.1778 0.5715)
						)
					)
					(width 0)
					(fill yes)
				)
			)
		)
		(pad "G" smd custom
			(at -0.98425 0.9525 180)
			(size 0.1905 0.1905)
			(layers "F.Cu" "F.Mask" "F.Paste")
			(net "HDD4_LED_B")
			(options
				(clearance outline)
				(anchor circle)
			)
			(primitives
				(gr_poly
					(pts
						(arc
							(start -0.1778 0.5715)
							(mid -0.321484 0.511984)
							(end -0.381 0.3683)
						)
						(arc
							(start -0.381 -0.3683)
							(mid -0.321484 -0.511984)
							(end -0.1778 -0.5715)
						)
						(arc
							(start 0.1778 -0.5715)
							(mid 0.321484 -0.511984)
							(end 0.381 -0.3683)
						)
						(arc
							(start 0.381 0.3683)
							(mid 0.321484 0.511984)
							(end 0.1778 0.5715)
						)
					)
					(width 0)
					(fill yes)
				)
			)
		)
		(pad "S" smd custom
			(at 0.98425 0.9525 180)
			(size 0.1905 0.1905)
			(layers "F.Cu" "F.Mask" "F.Paste")
			(net "GND")
			(options
				(clearance outline)
				(anchor circle)
			)
			(primitives
				(gr_poly
					(pts
						(arc
							(start -0.1778 0.5715)
							(mid -0.321484 0.511984)
							(end -0.381 0.3683)
						)
						(arc
							(start -0.381 -0.3683)
							(mid -0.321484 -0.511984)
							(end -0.1778 -0.5715)
						)
						(arc
							(start 0.1778 -0.5715)
							(mid 0.321484 -0.511984)
							(end 0.381 -0.3683)
						)
						(arc
							(start 0.381 0.3683)
							(mid 0.321484 0.511984)
							(end 0.1778 0.5715)
						)
					)
					(width 0)
					(fill yes)
				)
			)
		)
	)
	(footprint ""
		(layer "F.Cu")
		(at 52.832 -206.375 90)
		(property "Reference" "D27"
			(at 0 0 90)
			(layer "F.SilkS")
			(hide yes)
			(effects
				(font
					(size 1.27 1.27)
				)
			)
		)
		(property "Value" "RB551V30-1-GP"
			(at 0 -6.7818 90)
			(unlocked yes)
			(layer "F.Fab")
			(hide yes)
			(effects
				(font
					(size 1.016 1.016)
					(thickness 0.1524)
				)
			)
		)
		(property "Device Type" "SOD323AKH44"
			(at 0 -8.6868 90)
			(unlocked yes)
			(layer "F.Fab")
			(hide yes)
			(effects
				(font
					(size 1.016 1.016)
					(thickness 0.1524)
				)
			)
		)
		(duplicate_pad_numbers_are_jumpers no)
		(fp_line
			(start 0.889 -1.9304)
			(end 0.889 2.159)
			(stroke
				(width 0.1524)
				(type default)
			)
			(layer "F.SilkS")
		)
		(fp_line
			(start -0.889 -1.9304)
			(end 0.889 -1.9304)
			(stroke
				(width 0.1524)
				(type default)
			)
			(layer "F.SilkS")
		)
		(fp_line
			(start 0.762 2.0574)
			(end -0.762 2.0574)
			(stroke
				(width 0.508)
				(type default)
			)
			(layer "F.SilkS")
		)
		(fp_line
			(start 0.889 2.159)
			(end -0.889 2.159)
			(stroke
				(width 0.1524)
				(type default)
			)
			(layer "F.SilkS")
		)
		(fp_line
			(start -0.889 2.159)
			(end -0.889 -1.9304)
			(stroke
				(width 0.1524)
				(type default)
			)
			(layer "F.SilkS")
		)
		(fp_rect
			(start -1.016 2.3114)
			(end 1.016 -2.0066)
			(stroke
				(width 0)
				(type default)
			)
			(fill no)
			(layer "F.CrtYd")
		)
		(fp_poly
			(pts
				(xy -1.016 -2.0066) (xy 1.016 -2.0066) (xy 1.016 2.3114) (xy -1.016 2.3114)
			)
			(stroke
				(width 0)
				(type default)
			)
			(fill no)
			(layer "F.Fab")
		)
		(pad "A" smd rect
			(at 0 -1.143 90)
			(size 0.5588 1.016)
			(layers "F.Cu" "F.Mask" "F.Paste")
			(net "SW_HDD12_R")
		)
		(pad "K" smd rect
			(at 0 1.143 90)
			(size 0.5588 1.016)
			(layers "F.Cu" "F.Mask" "F.Paste")
			(net "SW_HDD12_N")
		)
	)
	(footprint ""
		(layer "F.Cu")
		(at 35.941 -306.324 -90)
		(property "Reference" "C390"
			(at 0 0 270)
			(layer "F.SilkS")
			(hide yes)
			(effects
				(font
					(size 1.27 1.27)
				)
			)
		)
		(property "Value" "SCD033U25V2KX-GP"
			(at 1.1811 -2.7051 270)
			(unlocked yes)
			(layer "F.Fab")
			(hide yes)
			(effects
				(font
					(size 1.016 1.016)
					(thickness 0.1524)
				)
			)
		)
		(property "Device Type" "C402H22"
			(at 1.1811 -4.2291 270)
			(unlocked yes)
			(layer "F.Fab")
			(hide yes)
			(effects
				(font
					(size 1.016 1.016)
					(thickness 0.1524)
				)
			)
		)
		(duplicate_pad_numbers_are_jumpers no)
		(fp_rect
			(start -0.4318 0.9525)
			(end 0.4318 -0.9525)
			(stroke
				(width 0)
				(type default)
			)
			(fill no)
			(layer "F.CrtYd")
		)
		(fp_rect
			(start -0.4318 0.9525)
			(end 0.4318 -0.9525)
			(stroke
				(width 0)
				(type default)
			)
			(fill no)
			(layer "F.Fab")
		)
		(pad "1" smd custom
			(at 0 -0.4445 270)
			(size 0.1524 0.1524)
			(layers "F.Cu" "F.Mask" "F.Paste")
			(net "P12V")
			(options
				(clearance outline)
				(anchor circle)
			)
			(primitives
				(gr_poly
					(pts
						(arc
							(start 0.3048 -0.2032)
							(mid 0.275042 -0.275042)
							(end 0.2032 -0.3048)
						)
						(arc
							(start -0.2032 -0.3048)
							(mid -0.275042 -0.275042)
							(end -0.3048 -0.2032)
						)
						(arc
							(start -0.3048 0.2032)
							(mid -0.275042 0.275042)
							(end -0.2032 0.3048)
						)
						(arc
							(start 0.2032 0.3048)
							(mid 0.275042 0.275042)
							(end 0.3048 0.2032)
						)
					)
					(width 0)
					(fill yes)
				)
			)
		)
		(pad "2" smd custom
			(at 0 0.4445 270)
			(size 0.1524 0.1524)
			(layers "F.Cu" "F.Mask" "F.Paste")
			(net "SW_HDD11_N")
			(options
				(clearance outline)
				(anchor circle)
			)
			(primitives
				(gr_poly
					(pts
						(arc
							(start 0.3048 -0.2032)
							(mid 0.275042 -0.275042)
							(end 0.2032 -0.3048)
						)
						(arc
							(start -0.2032 -0.3048)
							(mid -0.275042 -0.275042)
							(end -0.3048 -0.2032)
						)
						(arc
							(start -0.3048 0.2032)
							(mid -0.275042 0.275042)
							(end -0.2032 0.3048)
						)
						(arc
							(start 0.2032 0.3048)
							(mid 0.275042 0.275042)
							(end 0.3048 0.2032)
						)
					)
					(width 0)
					(fill yes)
				)
			)
		)
	)
	(footprint ""
		(layer "F.Cu")
		(at 31.242 -288.29 180)
		(property "Reference" "C386"
			(at 0 0 180)
			(layer "F.SilkS")
			(hide yes)
			(effects
				(font
					(size 1.27 1.27)
				)
			)
		)
		(property "Value" "SCD033U25V2KX-GP"
			(at 1.1811 -2.7051 180)
			(unlocked yes)
			(layer "F.Fab")
			(hide yes)
			(effects
				(font
					(size 1.016 1.016)
					(thickness 0.1524)
				)
			)
		)
		(property "Device Type" "C402H22"
			(at 1.1811 -4.2291 180)
			(unlocked yes)
			(layer "F.Fab")
			(hide yes)
			(effects
				(font
					(size 1.016 1.016)
					(thickness 0.1524)
				)
			)
		)
		(duplicate_pad_numbers_are_jumpers no)
		(fp_rect
			(start -0.4318 0.9525)
			(end 0.4318 -0.9525)
			(stroke
				(width 0)
				(type default)
			)
			(fill no)
			(layer "F.CrtYd")
		)
		(fp_rect
			(start -0.4318 0.9525)
			(end 0.4318 -0.9525)
			(stroke
				(width 0)
				(type default)
			)
			(fill no)
			(layer "F.Fab")
		)
		(pad "1" smd custom
			(at 0 -0.4445 180)
			(size 0.1524 0.1524)
			(layers "F.Cu" "F.Mask" "F.Paste")
			(net "P12V")
			(options
				(clearance outline)
				(anchor circle)
			)
			(primitives
				(gr_poly
					(pts
						(arc
							(start 0.3048 -0.2032)
							(mid 0.275042 -0.275042)
							(end 0.2032 -0.3048)
						)
						(arc
							(start -0.2032 -0.3048)
							(mid -0.275042 -0.275042)
							(end -0.3048 -0.2032)
						)
						(arc
							(start -0.3048 0.2032)
							(mid -0.275042 0.275042)
							(end -0.2032 0.3048)
						)
						(arc
							(start 0.2032 0.3048)
							(mid 0.275042 0.275042)
							(end 0.3048 0.2032)
						)
					)
					(width 0)
					(fill yes)
				)
			)
		)
		(pad "2" smd custom
			(at 0 0.4445 180)
			(size 0.1524 0.1524)
			(layers "F.Cu" "F.Mask" "F.Paste")
			(net "SW_HDD7_N")
			(options
				(clearance outline)
				(anchor circle)
			)
			(primitives
				(gr_poly
					(pts
						(arc
							(start 0.3048 -0.2032)
							(mid 0.275042 -0.275042)
							(end 0.2032 -0.3048)
						)
						(arc
							(start -0.2032 -0.3048)
							(mid -0.275042 -0.275042)
							(end -0.3048 -0.2032)
						)
						(arc
							(start -0.3048 0.2032)
							(mid -0.275042 0.275042)
							(end -0.2032 0.3048)
						)
						(arc
							(start 0.2032 0.3048)
							(mid 0.275042 0.275042)
							(end 0.3048 0.2032)
						)
					)
					(width 0)
					(fill yes)
				)
			)
		)
	)
	(footprint ""
		(layer "F.Cu")
		(at 92.583 -13.462 -90)
		(property "Reference" "D29"
			(at 0 0 270)
			(layer "F.SilkS")
			(hide yes)
			(effects
				(font
					(size 1.27 1.27)
				)
			)
		)
		(property "Value" "RB551V30-1-GP"
			(at 0 -6.7818 270)
			(unlocked yes)
			(layer "F.Fab")
			(hide yes)
			(effects
				(font
					(size 1.016 1.016)
					(thickness 0.1524)
				)
			)
		)
		(property "Device Type" "SOD323AKH44"
			(at 0 -8.6868 270)
			(unlocked yes)
			(layer "F.Fab")
			(hide yes)
			(effects
				(font
					(size 1.016 1.016)
					(thickness 0.1524)
				)
			)
		)
		(duplicate_pad_numbers_are_jumpers no)
		(fp_line
			(start -0.889 2.159)
			(end -0.889 -1.9304)
			(stroke
				(width 0.1524)
				(type default)
			)
			(layer "F.SilkS")
		)
		(fp_line
			(start 0.889 2.159)
			(end -0.889 2.159)
			(stroke
				(width 0.1524)
				(type default)
			)
			(layer "F.SilkS")
		)
		(fp_line
			(start 0.762 2.0574)
			(end -0.762 2.0574)
			(stroke
				(width 0.508)
				(type default)
			)
			(layer "F.SilkS")
		)
		(fp_line
			(start -0.889 -1.9304)
			(end 0.889 -1.9304)
			(stroke
				(width 0.1524)
				(type default)
			)
			(layer "F.SilkS")
		)
		(fp_line
			(start 0.889 -1.9304)
			(end 0.889 2.159)
			(stroke
				(width 0.1524)
				(type default)
			)
			(layer "F.SilkS")
		)
		(fp_rect
			(start -1.016 2.3114)
			(end 1.016 -2.0066)
			(stroke
				(width 0)
				(type default)
			)
			(fill no)
			(layer "F.CrtYd")
		)
		(fp_poly
			(pts
				(xy -1.016 -2.0066) (xy 1.016 -2.0066) (xy 1.016 2.3114) (xy -1.016 2.3114)
			)
			(stroke
				(width 0)
				(type default)
			)
			(fill no)
			(layer "F.Fab")
		)
		(pad "A" smd rect
			(at 0 -1.143 270)
			(size 0.5588 1.016)
			(layers "F.Cu" "F.Mask" "F.Paste")
			(net "SW_HDD14_R")
		)
		(pad "K" smd rect
			(at 0 1.143 270)
			(size 0.5588 1.016)
			(layers "F.Cu" "F.Mask" "F.Paste")
			(net "SW_HDD14_N")
		)
	)
	(footprint ""
		(layer "F.Cu")
		(at 210.185 -68.3768)
		(property "Reference" "R370"
			(at 0 0 0)
			(layer "F.SilkS")
			(hide yes)
			(effects
				(font
					(size 1.27 1.27)
				)
			)
		)
		(property "Value" "10KR2F-2-GP"
			(at 0.064008 -3.993896 0)
			(unlocked yes)
			(layer "F.Fab")
			(hide yes)
			(effects
				(font
					(size 1.016 1.016)
					(thickness 0.1524)
				)
			)
		)
		(property "Device Type" "R402H16"
			(at 0.064008 -5.517896 0)
			(unlocked yes)
			(layer "F.Fab")
			(hide yes)
			(effects
				(font
					(size 1.016 1.016)
					(thickness 0.1524)
				)
			)
		)
		(duplicate_pad_numbers_are_jumpers no)
		(fp_line
			(start -0.508 -0.9398)
			(end -0.508 0.9398)
			(stroke
				(width 0.1524)
				(type default)
			)
			(layer "F.SilkS")
		)
		(fp_line
			(start 0.508 -0.9398)
			(end -0.508 -0.9398)
			(stroke
				(width 0.1524)
				(type default)
			)
			(layer "F.SilkS")
		)
		(fp_rect
			(start -0.508 0.9398)
			(end 0.508 -0.9398)
			(stroke
				(width 0)
				(type default)
			)
			(fill no)
			(layer "F.CrtYd")
		)
		(fp_rect
			(start -0.508 0.9398)
			(end 0.508 -0.9398)
			(stroke
				(width 0)
				(type default)
			)
			(fill no)
			(layer "F.Fab")
		)
		(pad "1" smd custom
			(at 0 -0.4445)
			(size 0.1397 0.1397)
			(layers "F.Cu" "F.Mask" "F.Paste")
			(net "P12V")
			(options
				(clearance outline)
				(anchor circle)
			)
			(primitives
				(gr_poly
					(pts
						(arc
							(start -0.1778 -0.2794)
							(mid -0.249642 -0.249642)
							(end -0.2794 -0.1778)
						)
						(arc
							(start -0.2794 0.1778)
							(mid -0.249642 0.249642)
							(end -0.1778 0.2794)
						)
						(arc
							(start 0.1778 0.2794)
							(mid 0.249642 0.249642)
							(end 0.2794 0.1778)
						)
						(arc
							(start 0.2794 -0.1778)
							(mid 0.249642 -0.249642)
							(end 0.1778 -0.2794)
						)
					)
					(width 0)
					(fill yes)
				)
			)
		)
		(pad "2" smd custom
			(at 0 0.4445)
			(size 0.1397 0.1397)
			(layers "F.Cu" "F.Mask" "F.Paste")
			(net "HDD4_LED_G")
			(options
				(clearance outline)
				(anchor circle)
			)
			(primitives
				(gr_poly
					(pts
						(arc
							(start -0.1778 -0.2794)
							(mid -0.249642 -0.249642)
							(end -0.2794 -0.1778)
						)
						(arc
							(start -0.2794 0.1778)
							(mid -0.249642 0.249642)
							(end -0.1778 0.2794)
						)
						(arc
							(start 0.1778 0.2794)
							(mid 0.249642 0.249642)
							(end 0.2794 0.1778)
						)
						(arc
							(start 0.2794 -0.1778)
							(mid 0.249642 -0.249642)
							(end 0.1778 -0.2794)
						)
					)
					(width 0)
					(fill yes)
				)
			)
		)
	)
	(footprint ""
		(layer "F.Cu")
		(at 14.5796 -155.1686)
		(property "Reference" "TP12"
			(at 0 0 0)
			(layer "F.SilkS")
			(hide yes)
			(effects
				(font
					(size 1.27 1.27)
				)
			)
		)
		(property "Value" "TPAD32-GP"
			(at 0 -3.166364 0)
			(unlocked yes)
			(layer "F.Fab")
			(hide yes)
			(effects
				(font
					(size 1.016 1.016)
					(thickness 0.1524)
				)
			)
		)
		(property "Device Type" "TPAD32"
			(at 0 -4.690618 0)
			(unlocked yes)
			(layer "F.Fab")
			(hide yes)
			(effects
				(font
					(size 1.016 1.016)
					(thickness 0.1524)
				)
			)
		)
		(duplicate_pad_numbers_are_jumpers no)
		(fp_poly
			(pts
				(arc
					(start 0.4064 0)
					(mid -0.4064 0)
					(end 0.4064 0)
				)
			)
			(stroke
				(width 0)
				(type default)
			)
			(fill no)
			(layer "F.CrtYd")
		)
		(fp_poly
			(pts
				(arc
					(start 0.7112 0)
					(mid -0.7112 0)
					(end 0.7112 0)
				)
			)
			(stroke
				(width 0)
				(type default)
			)
			(fill no)
			(layer "F.Fab")
		)
		(pad "1" smd circle
			(at 0 0)
			(size 0.8128 0.8128)
			(layers "F.Cu" "F.Mask" "F.Paste")
			(net "SAS2X28_B_HDD15_FLT")
		)
	)
	(footprint ""
		(layer "F.Cu")
		(at 32.99968 -4.499864)
		(property "Reference" "H5"
			(at 0 0 0)
			(layer "F.SilkS")
			(hide yes)
			(effects
				(font
					(size 1.27 1.27)
				)
			)
		)
		(property "Value" "HOLE315R157"
			(at -0.116332 -8.41375 0)
			(unlocked yes)
			(layer "F.Fab")
			(hide yes)
			(effects
				(font
					(size 1.016 1.016)
					(thickness 0.1524)
				)
			)
		)
		(property "Device Type" "HOLE315R157"
			(at -0.116332 -6.88975 0)
			(unlocked yes)
			(layer "F.Fab")
			(hide yes)
			(effects
				(font
					(size 1.016 1.016)
					(thickness 0.1524)
				)
			)
		)
		(duplicate_pad_numbers_are_jumpers no)
		(fp_poly
			(pts
				(arc
					(start 4.3053 0)
					(mid -4.3053 0)
					(end 4.3053 0)
				)
			)
			(stroke
				(width 0)
				(type default)
			)
			(fill no)
			(layer "F.CrtYd")
		)
		(fp_poly
			(pts
				(arc
					(start 4.3053 0)
					(mid -4.3053 0)
					(end 4.3053 0)
				)
			)
			(stroke
				(width 0)
				(type default)
			)
			(fill no)
			(layer "F.Fab")
		)
		(pad "1" thru_hole circle
			(at 0 0)
			(size 8.001 8.001)
			(drill 3.9878)
			(layers "*.Cu" "*.Mask")
			(remove_unused_layers no)
			(net "GND")
			(clearance -1.4986)
			(thermal_gap 0.3048)
			(padstack
				(mode front_inner_back)
				(layer "Inner"
					(shape circle)
					(size 4.3942 4.3942)
					(clearance 0.3048)
				)
				(layer "B.Cu"
					(shape circle)
					(size 8.001 8.001)
					(clearance -1.4986)
				)
			)
		)
	)
	(footprint ""
		(layer "F.Cu")
		(at 8.127746 -487.8197 180)
		(property "Reference" "PR36"
			(at 0 0 180)
			(layer "F.SilkS")
			(hide yes)
			(effects
				(font
					(size 1.27 1.27)
				)
			)
		)
		(property "Value" "3D01R2F-GP"
			(at 0.064008 -3.993896 180)
			(unlocked yes)
			(layer "F.Fab")
			(hide yes)
			(effects
				(font
					(size 1.016 1.016)
					(thickness 0.1524)
				)
			)
		)
		(property "Device Type" "R402H16"
			(at 0.064008 -5.517896 180)
			(unlocked yes)
			(layer "F.Fab")
			(hide yes)
			(effects
				(font
					(size 1.016 1.016)
					(thickness 0.1524)
				)
			)
		)
		(duplicate_pad_numbers_are_jumpers no)
		(fp_line
			(start 0.508 -0.9398)
			(end -0.508 -0.9398)
			(stroke
				(width 0.1524)
				(type default)
			)
			(layer "F.SilkS")
		)
		(fp_line
			(start -0.508 -0.9398)
			(end -0.508 0.9398)
			(stroke
				(width 0.1524)
				(type default)
			)
			(layer "F.SilkS")
		)
		(fp_rect
			(start -0.508 0.9398)
			(end 0.508 -0.9398)
			(stroke
				(width 0)
				(type default)
			)
			(fill no)
			(layer "F.CrtYd")
		)
		(fp_rect
			(start -0.508 0.9398)
			(end 0.508 -0.9398)
			(stroke
				(width 0)
				(type default)
			)
			(fill no)
			(layer "F.Fab")
		)
		(pad "1" smd custom
			(at 0 -0.4445 180)
			(size 0.1397 0.1397)
			(layers "F.Cu" "F.Mask" "F.Paste")
			(net "GND")
			(options
				(clearance outline)
				(anchor circle)
			)
			(primitives
				(gr_poly
					(pts
						(arc
							(start -0.1778 -0.2794)
							(mid -0.249642 -0.249642)
							(end -0.2794 -0.1778)
						)
						(arc
							(start -0.2794 0.1778)
							(mid -0.249642 0.249642)
							(end -0.1778 0.2794)
						)
						(arc
							(start 0.1778 0.2794)
							(mid 0.249642 0.249642)
							(end 0.2794 0.1778)
						)
						(arc
							(start 0.2794 -0.1778)
							(mid 0.249642 -0.249642)
							(end 0.1778 -0.2794)
						)
					)
					(width 0)
					(fill yes)
				)
			)
		)
		(pad "2" smd custom
			(at 0 0.4445 180)
			(size 0.1397 0.1397)
			(layers "F.Cu" "F.Mask" "F.Paste")
			(net "P5VC_SNB")
			(options
				(clearance outline)
				(anchor circle)
			)
			(primitives
				(gr_poly
					(pts
						(arc
							(start -0.1778 -0.2794)
							(mid -0.249642 -0.249642)
							(end -0.2794 -0.1778)
						)
						(arc
							(start -0.2794 0.1778)
							(mid -0.249642 0.249642)
							(end -0.1778 0.2794)
						)
						(arc
							(start 0.1778 0.2794)
							(mid 0.249642 0.249642)
							(end 0.2794 0.1778)
						)
						(arc
							(start 0.2794 -0.1778)
							(mid 0.249642 -0.249642)
							(end 0.1778 -0.2794)
						)
					)
					(width 0)
					(fill yes)
				)
			)
		)
	)
	(footprint ""
		(layer "F.Cu")
		(at 55.245 -276.098)
		(property "Reference" "R208"
			(at 0 0 0)
			(layer "F.SilkS")
			(hide yes)
			(effects
				(font
					(size 1.27 1.27)
				)
			)
		)
		(property "Value" "220R3F-1-GP"
			(at -0.0254 -2.5146 0)
			(unlocked yes)
			(layer "F.Fab")
			(hide yes)
			(effects
				(font
					(size 1.016 1.016)
					(thickness 0.1524)
				)
			)
		)
		(property "Device Type" "R603H22"
			(at -0.0254 -4.0386 0)
			(unlocked yes)
			(layer "F.Fab")
			(hide yes)
			(effects
				(font
					(size 1.016 1.016)
					(thickness 0.1524)
				)
			)
		)
		(duplicate_pad_numbers_are_jumpers no)
		(fp_line
			(start -0.4826 0)
			(end -0.2032 0)
			(stroke
				(width 0.2032)
				(type default)
			)
			(layer "F.SilkS")
		)
		(fp_line
			(start 0.2032 0)
			(end 0.4826 0)
			(stroke
				(width 0.2032)
				(type default)
			)
			(layer "F.SilkS")
		)
		(fp_rect
			(start -0.5842 1.3335)
			(end 0.5842 -1.3335)
			(stroke
				(width 0)
				(type default)
			)
			(fill no)
			(layer "F.CrtYd")
		)
		(fp_rect
			(start -0.5842 1.3335)
			(end 0.5842 -1.3335)
			(stroke
				(width 0)
				(type default)
			)
			(fill no)
			(layer "F.Fab")
		)
		(pad "1" smd custom
			(at 0 -0.762)
			(size 0.2159 0.2159)
			(layers "F.Cu" "F.Mask" "F.Paste")
			(net "HDD_PRSNT_NET7")
			(options
				(clearance outline)
				(anchor circle)
			)
			(primitives
				(gr_poly
					(pts
						(arc
							(start -0.3302 -0.4318)
							(mid -0.402042 -0.402042)
							(end -0.4318 -0.3302)
						)
						(arc
							(start -0.4318 0.3302)
							(mid -0.402042 0.402042)
							(end -0.3302 0.4318)
						)
						(arc
							(start 0.3302 0.4318)
							(mid 0.402042 0.402042)
							(end 0.4318 0.3302)
						)
						(arc
							(start 0.4318 -0.3302)
							(mid 0.402042 -0.402042)
							(end 0.3302 -0.4318)
						)
					)
					(width 0)
					(fill yes)
				)
			)
		)
		(pad "2" smd custom
			(at 0 0.762)
			(size 0.2159 0.2159)
			(layers "F.Cu" "F.Mask" "F.Paste")
			(net "HDD_PRSNT7")
			(options
				(clearance outline)
				(anchor circle)
			)
			(primitives
				(gr_poly
					(pts
						(arc
							(start -0.3302 -0.4318)
							(mid -0.402042 -0.402042)
							(end -0.4318 -0.3302)
						)
						(arc
							(start -0.4318 0.3302)
							(mid -0.402042 0.402042)
							(end -0.3302 0.4318)
						)
						(arc
							(start 0.3302 0.4318)
							(mid 0.402042 0.402042)
							(end 0.4318 0.3302)
						)
						(arc
							(start 0.4318 -0.3302)
							(mid 0.402042 -0.402042)
							(end 0.3302 -0.4318)
						)
					)
					(width 0)
					(fill yes)
				)
			)
		)
	)
	(footprint ""
		(layer "F.Cu")
		(at 193.758058 -392.886184 -90)
		(property "Reference" "Q4"
			(at 0 0 270)
			(layer "F.SilkS")
			(hide yes)
			(effects
				(font
					(size 1.27 1.27)
				)
			)
		)
		(property "Value" "2N7002DW-7F-GP"
			(at -2.3622 -8.2042 270)
			(unlocked yes)
			(layer "F.Fab")
			(hide yes)
			(effects
				(font
					(size 1.016 1.016)
					(thickness 0.1524)
				)
			)
		)
		(property "Device Type" "SOT-363H44"
			(at -2.3622 -10.1092 270)
			(unlocked yes)
			(layer "F.Fab")
			(hide yes)
			(effects
				(font
					(size 1.016 1.016)
					(thickness 0.1524)
				)
			)
		)
		(duplicate_pad_numbers_are_jumpers no)
		(fp_line
			(start -1.4478 1.7018)
			(end 1.4478 1.7018)
			(stroke
				(width 0.1524)
				(type default)
			)
			(layer "F.SilkS")
		)
		(fp_line
			(start 1.4478 1.7018)
			(end 1.4478 -1.7018)
			(stroke
				(width 0.1524)
				(type default)
			)
			(layer "F.SilkS")
		)
		(fp_line
			(start -1.27 1.524)
			(end -1.27 0.6604)
			(stroke
				(width 0.4826)
				(type default)
			)
			(layer "F.SilkS")
		)
		(fp_line
			(start -1.4478 -1.7018)
			(end -1.4478 1.7018)
			(stroke
				(width 0.1524)
				(type default)
			)
			(layer "F.SilkS")
		)
		(fp_line
			(start 1.4478 -1.7018)
			(end -1.4478 -1.7018)
			(stroke
				(width 0.1524)
				(type default)
			)
			(layer "F.SilkS")
		)
		(fp_poly
			(pts
				(xy -1.524 -1.778) (xy 1.524 -1.778) (xy 1.524 1.778) (xy -1.524 1.778)
			)
			(stroke
				(width 0)
				(type default)
			)
			(fill no)
			(layer "F.CrtYd")
		)
		(fp_poly
			(pts
				(xy -1.524 -1.778) (xy 1.524 -1.778) (xy 1.524 1.778) (xy -1.524 1.778)
			)
			(stroke
				(width 0)
				(type default)
			)
			(fill no)
			(layer "F.Fab")
		)
		(pad "1" smd rect
			(at -0.65024 0.9398 270)
			(size 0.4064 1.016)
			(layers "F.Cu" "F.Mask" "F.Paste")
			(net "GND")
		)
		(pad "2" smd rect
			(at 0 0.9398 270)
			(size 0.4064 1.016)
			(layers "F.Cu" "F.Mask" "F.Paste")
			(net "SW_PWR_R_HDD1")
		)
		(pad "3" smd rect
			(at 0.65024 0.9398 270)
			(size 0.4064 1.016)
			(layers "F.Cu" "F.Mask" "F.Paste")
			(net "SW_HDD1_P")
		)
		(pad "4" smd rect
			(at 0.65024 -0.9398 270)
			(size 0.4064 1.016)
			(layers "F.Cu" "F.Mask" "F.Paste")
			(net "GND")
		)
		(pad "5" smd rect
			(at 0 -0.9398 270)
			(size 0.4064 1.016)
			(layers "F.Cu" "F.Mask" "F.Paste")
			(net "SW_HDD1_G")
		)
		(pad "6" smd rect
			(at -0.65024 -0.9398 270)
			(size 0.4064 1.016)
			(layers "F.Cu" "F.Mask" "F.Paste")
			(net "SW_HDD1_R")
		)
	)
	(footprint ""
		(layer "F.Cu")
		(at 216.364058 -389.711184 -90)
		(property "Reference" "R124"
			(at 0 0 270)
			(layer "F.SilkS")
			(hide yes)
			(effects
				(font
					(size 1.27 1.27)
				)
			)
		)
		(property "Value" "2R2010J-1-GP"
			(at 0.254 -8.0772 270)
			(unlocked yes)
			(layer "F.Fab")
			(hide yes)
			(effects
				(font
					(size 1.016 1.016)
					(thickness 0.1524)
				)
			)
		)
		(property "Device Type" "R2010H28"
			(at 0.254 -9.6774 270)
			(unlocked yes)
			(layer "F.Fab")
			(hide yes)
			(effects
				(font
					(size 1.016 1.016)
					(thickness 0.1524)
				)
			)
		)
		(duplicate_pad_numbers_are_jumpers no)
		(fp_line
			(start -1.651 3.302)
			(end 1.651 3.302)
			(stroke
				(width 0.1524)
				(type default)
			)
			(layer "F.SilkS")
		)
		(fp_line
			(start 1.651 3.302)
			(end 1.651 -3.302)
			(stroke
				(width 0.1524)
				(type default)
			)
			(layer "F.SilkS")
		)
		(fp_line
			(start -1.651 -3.302)
			(end -1.651 3.302)
			(stroke
				(width 0.1524)
				(type default)
			)
			(layer "F.SilkS")
		)
		(fp_line
			(start 1.651 -3.302)
			(end -1.651 -3.302)
			(stroke
				(width 0.1524)
				(type default)
			)
			(layer "F.SilkS")
		)
		(fp_rect
			(start -1.7272 -3.3782)
			(end 1.7272 3.3782)
			(stroke
				(width 0)
				(type default)
			)
			(fill no)
			(layer "F.CrtYd")
		)
		(fp_poly
			(pts
				(xy 1.7272 3.3782) (xy 1.7272 -3.3782) (xy -1.7272 -3.3782) (xy -1.7272 3.3782)
			)
			(stroke
				(width 0)
				(type default)
			)
			(fill no)
			(layer "F.Fab")
		)
		(pad "1" smd rect
			(at 0 -2.3495 270)
			(size 2.794 1.143)
			(layers "F.Cu" "F.Mask" "F.Paste")
			(net "12V_PRE_1")
		)
		(pad "2" smd rect
			(at 0 2.3495 270)
			(size 2.794 1.143)
			(layers "F.Cu" "F.Mask" "F.Paste")
			(net "P12V_HDD1")
		)
	)
	(footprint ""
		(layer "F.Cu")
		(at 26.669746 -432.781202 180)
		(property "Reference" "C270"
			(at 0 0 180)
			(layer "F.SilkS")
			(hide yes)
			(effects
				(font
					(size 1.27 1.27)
				)
			)
		)
		(property "Value" "SCD01U50V2KX-1GP"
			(at 1.1811 -2.7051 180)
			(unlocked yes)
			(layer "F.Fab")
			(hide yes)
			(effects
				(font
					(size 1.016 1.016)
					(thickness 0.1524)
				)
			)
		)
		(property "Device Type" "C402H22"
			(at 1.1811 -4.2291 180)
			(unlocked yes)
			(layer "F.Fab")
			(hide yes)
			(effects
				(font
					(size 1.016 1.016)
					(thickness 0.1524)
				)
			)
		)
		(duplicate_pad_numbers_are_jumpers no)
		(fp_rect
			(start -0.4318 0.9525)
			(end 0.4318 -0.9525)
			(stroke
				(width 0)
				(type default)
			)
			(fill no)
			(layer "F.CrtYd")
		)
		(fp_rect
			(start -0.4318 0.9525)
			(end 0.4318 -0.9525)
			(stroke
				(width 0)
				(type default)
			)
			(fill no)
			(layer "F.Fab")
		)
		(pad "1" smd custom
			(at 0 -0.4445 180)
			(size 0.1524 0.1524)
			(layers "F.Cu" "F.Mask" "F.Paste")
			(net "HDD_PRSNT_NET10")
			(options
				(clearance outline)
				(anchor circle)
			)
			(primitives
				(gr_poly
					(pts
						(arc
							(start 0.3048 -0.2032)
							(mid 0.275042 -0.275042)
							(end 0.2032 -0.3048)
						)
						(arc
							(start -0.2032 -0.3048)
							(mid -0.275042 -0.275042)
							(end -0.3048 -0.2032)
						)
						(arc
							(start -0.3048 0.2032)
							(mid -0.275042 0.275042)
							(end -0.2032 0.3048)
						)
						(arc
							(start 0.2032 0.3048)
							(mid 0.275042 0.275042)
							(end 0.3048 0.2032)
						)
					)
					(width 0)
					(fill yes)
				)
			)
		)
		(pad "2" smd custom
			(at 0 0.4445 180)
			(size 0.1524 0.1524)
			(layers "F.Cu" "F.Mask" "F.Paste")
			(net "GND")
			(options
				(clearance outline)
				(anchor circle)
			)
			(primitives
				(gr_poly
					(pts
						(arc
							(start 0.3048 -0.2032)
							(mid 0.275042 -0.275042)
							(end 0.2032 -0.3048)
						)
						(arc
							(start -0.2032 -0.3048)
							(mid -0.275042 -0.275042)
							(end -0.3048 -0.2032)
						)
						(arc
							(start -0.3048 0.2032)
							(mid -0.275042 0.275042)
							(end -0.2032 0.3048)
						)
						(arc
							(start 0.2032 0.3048)
							(mid 0.275042 0.275042)
							(end 0.3048 0.2032)
						)
					)
					(width 0)
					(fill yes)
				)
			)
		)
	)
	(footprint ""
		(layer "F.Cu")
		(at 45.338746 -41.9227 90)
		(property "Reference" "R226"
			(at 0 0 90)
			(layer "F.SilkS")
			(hide yes)
			(effects
				(font
					(size 1.27 1.27)
				)
			)
		)
		(property "Value" "10KR2F-2-GP"
			(at 0.064008 -3.993896 90)
			(unlocked yes)
			(layer "F.Fab")
			(hide yes)
			(effects
				(font
					(size 1.016 1.016)
					(thickness 0.1524)
				)
			)
		)
		(property "Device Type" "R402H16"
			(at 0.064008 -5.517896 90)
			(unlocked yes)
			(layer "F.Fab")
			(hide yes)
			(effects
				(font
					(size 1.016 1.016)
					(thickness 0.1524)
				)
			)
		)
		(duplicate_pad_numbers_are_jumpers no)
		(fp_line
			(start 0.508 -0.9398)
			(end -0.508 -0.9398)
			(stroke
				(width 0.1524)
				(type default)
			)
			(layer "F.SilkS")
		)
		(fp_line
			(start -0.508 -0.9398)
			(end -0.508 0.9398)
			(stroke
				(width 0.1524)
				(type default)
			)
			(layer "F.SilkS")
		)
		(fp_rect
			(start -0.508 0.9398)
			(end 0.508 -0.9398)
			(stroke
				(width 0)
				(type default)
			)
			(fill no)
			(layer "F.CrtYd")
		)
		(fp_rect
			(start -0.508 0.9398)
			(end 0.508 -0.9398)
			(stroke
				(width 0)
				(type default)
			)
			(fill no)
			(layer "F.Fab")
		)
		(pad "1" smd custom
			(at 0 -0.4445 90)
			(size 0.1397 0.1397)
			(layers "F.Cu" "F.Mask" "F.Paste")
			(net "P5VB")
			(options
				(clearance outline)
				(anchor circle)
			)
			(primitives
				(gr_poly
					(pts
						(arc
							(start -0.1778 -0.2794)
							(mid -0.249642 -0.249642)
							(end -0.2794 -0.1778)
						)
						(arc
							(start -0.2794 0.1778)
							(mid -0.249642 0.249642)
							(end -0.1778 0.2794)
						)
						(arc
							(start 0.1778 0.2794)
							(mid 0.249642 0.249642)
							(end 0.2794 0.1778)
						)
						(arc
							(start 0.2794 -0.1778)
							(mid 0.249642 -0.249642)
							(end 0.1778 -0.2794)
						)
					)
					(width 0)
					(fill yes)
				)
			)
		)
		(pad "2" smd custom
			(at 0 0.4445 90)
			(size 0.1397 0.1397)
			(layers "F.Cu" "F.Mask" "F.Paste")
			(net "DRIVE_ACT_9")
			(options
				(clearance outline)
				(anchor circle)
			)
			(primitives
				(gr_poly
					(pts
						(arc
							(start -0.1778 -0.2794)
							(mid -0.249642 -0.249642)
							(end -0.2794 -0.1778)
						)
						(arc
							(start -0.2794 0.1778)
							(mid -0.249642 0.249642)
							(end -0.1778 0.2794)
						)
						(arc
							(start 0.1778 0.2794)
							(mid 0.249642 0.249642)
							(end 0.2794 0.1778)
						)
						(arc
							(start 0.2794 -0.1778)
							(mid 0.249642 -0.249642)
							(end 0.1778 -0.2794)
						)
					)
					(width 0)
					(fill yes)
				)
			)
		)
	)
	(footprint ""
		(layer "F.Cu")
		(at 176.669446 -462.695036 90)
		(property "Reference" "R379"
			(at 0 0 90)
			(layer "F.SilkS")
			(hide yes)
			(effects
				(font
					(size 1.27 1.27)
				)
			)
		)
		(property "Value" "0R2J-2-GP"
			(at 0.064008 -3.993896 90)
			(unlocked yes)
			(layer "F.Fab")
			(hide yes)
			(effects
				(font
					(size 1.016 1.016)
					(thickness 0.1524)
				)
			)
		)
		(property "Device Type" "R402H16"
			(at 0.064008 -5.517896 90)
			(unlocked yes)
			(layer "F.Fab")
			(hide yes)
			(effects
				(font
					(size 1.016 1.016)
					(thickness 0.1524)
				)
			)
		)
		(duplicate_pad_numbers_are_jumpers no)
		(fp_line
			(start 0.508 -0.9398)
			(end -0.508 -0.9398)
			(stroke
				(width 0.1524)
				(type default)
			)
			(layer "F.SilkS")
		)
		(fp_line
			(start -0.508 -0.9398)
			(end -0.508 0.9398)
			(stroke
				(width 0.1524)
				(type default)
			)
			(layer "F.SilkS")
		)
		(fp_rect
			(start -0.508 0.9398)
			(end 0.508 -0.9398)
			(stroke
				(width 0)
				(type default)
			)
			(fill no)
			(layer "F.CrtYd")
		)
		(fp_rect
			(start -0.508 0.9398)
			(end 0.508 -0.9398)
			(stroke
				(width 0)
				(type default)
			)
			(fill no)
			(layer "F.Fab")
		)
		(pad "1" smd custom
			(at 0 -0.4445 90)
			(size 0.1397 0.1397)
			(layers "F.Cu" "F.Mask" "F.Paste")
			(net "VOL_SEN_SCL")
			(options
				(clearance outline)
				(anchor circle)
			)
			(primitives
				(gr_poly
					(pts
						(arc
							(start -0.1778 -0.2794)
							(mid -0.249642 -0.249642)
							(end -0.2794 -0.1778)
						)
						(arc
							(start -0.2794 0.1778)
							(mid -0.249642 0.249642)
							(end -0.1778 0.2794)
						)
						(arc
							(start 0.1778 0.2794)
							(mid 0.249642 0.249642)
							(end 0.2794 0.1778)
						)
						(arc
							(start 0.2794 -0.1778)
							(mid 0.249642 -0.249642)
							(end 0.1778 -0.2794)
						)
					)
					(width 0)
					(fill yes)
				)
			)
		)
		(pad "2" smd custom
			(at 0 0.4445 90)
			(size 0.1397 0.1397)
			(layers "F.Cu" "F.Mask" "F.Paste")
			(net "I2C_B_SCL")
			(options
				(clearance outline)
				(anchor circle)
			)
			(primitives
				(gr_poly
					(pts
						(arc
							(start -0.1778 -0.2794)
							(mid -0.249642 -0.249642)
							(end -0.2794 -0.1778)
						)
						(arc
							(start -0.2794 0.1778)
							(mid -0.249642 0.249642)
							(end -0.1778 0.2794)
						)
						(arc
							(start 0.1778 0.2794)
							(mid 0.249642 0.249642)
							(end 0.2794 0.1778)
						)
						(arc
							(start 0.2794 -0.1778)
							(mid 0.249642 -0.249642)
							(end 0.1778 -0.2794)
						)
					)
					(width 0)
					(fill yes)
				)
			)
		)
	)
	(footprint ""
		(layer "F.Cu")
		(at 14.495272 -500.446548 180)
		(property "Reference" "PC37"
			(at 0 0 180)
			(layer "F.SilkS")
			(hide yes)
			(effects
				(font
					(size 1.27 1.27)
				)
			)
		)
		(property "Value" "SC22U25V5MX-GP"
			(at -0.0762 -6.1214 180)
			(unlocked yes)
			(layer "F.Fab")
			(hide yes)
			(effects
				(font
					(size 1.016 1.016)
					(thickness 0.1524)
				)
			)
		)
		(property "Device Type" "C805H58"
			(at -0.0762 -8.1534 180)
			(unlocked yes)
			(layer "F.Fab")
			(hide yes)
			(effects
				(font
					(size 1.016 1.016)
					(thickness 0.1524)
				)
			)
		)
		(duplicate_pad_numbers_are_jumpers no)
		(fp_line
			(start 0.635 0)
			(end -0.635 0)
			(stroke
				(width 0.508)
				(type default)
			)
			(layer "F.SilkS")
		)
		(fp_rect
			(start -0.9652 1.778)
			(end 0.9652 -1.778)
			(stroke
				(width 0)
				(type default)
			)
			(fill no)
			(layer "F.CrtYd")
		)
		(fp_poly
			(pts
				(xy -0.9652 -1.778) (xy 0.9652 -1.778) (xy 0.9652 1.778) (xy -0.9652 1.778)
			)
			(stroke
				(width 0)
				(type default)
			)
			(fill no)
			(layer "F.Fab")
		)
		(pad "1" smd rect
			(at 0 -0.9652 180)
			(size 1.397 1.143)
			(layers "F.Cu" "F.Mask" "F.Paste")
			(net "P5VC_12VIN")
		)
		(pad "2" smd rect
			(at 0 0.9652 180)
			(size 1.397 1.143)
			(layers "F.Cu" "F.Mask" "F.Paste")
			(net "GND")
		)
	)
	(footprint ""
		(layer "F.Cu")
		(at 44.830746 -212.118702)
		(property "Reference" "R280"
			(at 0 0 0)
			(layer "F.SilkS")
			(hide yes)
			(effects
				(font
					(size 1.27 1.27)
				)
			)
		)
		(property "Value" "0R2J-2-GP"
			(at 0.064008 -3.993896 0)
			(unlocked yes)
			(layer "F.Fab")
			(hide yes)
			(effects
				(font
					(size 1.016 1.016)
					(thickness 0.1524)
				)
			)
		)
		(property "Device Type" "R402H16"
			(at 0.064008 -5.517896 0)
			(unlocked yes)
			(layer "F.Fab")
			(hide yes)
			(effects
				(font
					(size 1.016 1.016)
					(thickness 0.1524)
				)
			)
		)
		(duplicate_pad_numbers_are_jumpers no)
		(fp_line
			(start -0.508 -0.9398)
			(end -0.508 0.9398)
			(stroke
				(width 0.1524)
				(type default)
			)
			(layer "F.SilkS")
		)
		(fp_line
			(start 0.508 -0.9398)
			(end -0.508 -0.9398)
			(stroke
				(width 0.1524)
				(type default)
			)
			(layer "F.SilkS")
		)
		(fp_rect
			(start -0.508 0.9398)
			(end 0.508 -0.9398)
			(stroke
				(width 0)
				(type default)
			)
			(fill no)
			(layer "F.CrtYd")
		)
		(fp_rect
			(start -0.508 0.9398)
			(end 0.508 -0.9398)
			(stroke
				(width 0)
				(type default)
			)
			(fill no)
			(layer "F.Fab")
		)
		(pad "1" smd custom
			(at 0 -0.4445)
			(size 0.1397 0.1397)
			(layers "F.Cu" "F.Mask" "F.Paste")
			(net "SW_PWR_HDD12")
			(options
				(clearance outline)
				(anchor circle)
			)
			(primitives
				(gr_poly
					(pts
						(arc
							(start -0.1778 -0.2794)
							(mid -0.249642 -0.249642)
							(end -0.2794 -0.1778)
						)
						(arc
							(start -0.2794 0.1778)
							(mid -0.249642 0.249642)
							(end -0.1778 0.2794)
						)
						(arc
							(start 0.1778 0.2794)
							(mid 0.249642 0.249642)
							(end 0.2794 0.1778)
						)
						(arc
							(start 0.2794 -0.1778)
							(mid 0.249642 -0.249642)
							(end 0.1778 -0.2794)
						)
					)
					(width 0)
					(fill yes)
				)
			)
		)
		(pad "2" smd custom
			(at 0 0.4445)
			(size 0.1397 0.1397)
			(layers "F.Cu" "F.Mask" "F.Paste")
			(net "SW_PWR_R_HDD12")
			(options
				(clearance outline)
				(anchor circle)
			)
			(primitives
				(gr_poly
					(pts
						(arc
							(start -0.1778 -0.2794)
							(mid -0.249642 -0.249642)
							(end -0.2794 -0.1778)
						)
						(arc
							(start -0.2794 0.1778)
							(mid -0.249642 0.249642)
							(end -0.1778 0.2794)
						)
						(arc
							(start 0.1778 0.2794)
							(mid 0.249642 0.249642)
							(end 0.2794 0.1778)
						)
						(arc
							(start 0.2794 -0.1778)
							(mid 0.249642 -0.249642)
							(end 0.1778 -0.2794)
						)
					)
					(width 0)
					(fill yes)
				)
			)
		)
	)
	(footprint ""
		(layer "F.Cu")
		(at 33.019746 -57.0357 -90)
		(property "Reference" "C246"
			(at 0 0 270)
			(layer "F.SilkS")
			(hide yes)
			(effects
				(font
					(size 1.27 1.27)
				)
			)
		)
		(property "Value" "SCD01U50V2KX-1GP"
			(at 1.1811 -2.7051 270)
			(unlocked yes)
			(layer "F.Fab")
			(hide yes)
			(effects
				(font
					(size 1.016 1.016)
					(thickness 0.1524)
				)
			)
		)
		(property "Device Type" "C402H22"
			(at 1.1811 -4.2291 270)
			(unlocked yes)
			(layer "F.Fab")
			(hide yes)
			(effects
				(font
					(size 1.016 1.016)
					(thickness 0.1524)
				)
			)
		)
		(duplicate_pad_numbers_are_jumpers no)
		(fp_rect
			(start -0.4318 0.9525)
			(end 0.4318 -0.9525)
			(stroke
				(width 0)
				(type default)
			)
			(fill no)
			(layer "F.CrtYd")
		)
		(fp_rect
			(start -0.4318 0.9525)
			(end 0.4318 -0.9525)
			(stroke
				(width 0)
				(type default)
			)
			(fill no)
			(layer "F.Fab")
		)
		(pad "1" smd custom
			(at 0 -0.4445 270)
			(size 0.1524 0.1524)
			(layers "F.Cu" "F.Mask" "F.Paste")
			(net "SAS2X28_DRIVE_RX_N_A9")
			(options
				(clearance outline)
				(anchor circle)
			)
			(primitives
				(gr_poly
					(pts
						(arc
							(start 0.3048 -0.2032)
							(mid 0.275042 -0.275042)
							(end 0.2032 -0.3048)
						)
						(arc
							(start -0.2032 -0.3048)
							(mid -0.275042 -0.275042)
							(end -0.3048 -0.2032)
						)
						(arc
							(start -0.3048 0.2032)
							(mid -0.275042 0.275042)
							(end -0.2032 0.3048)
						)
						(arc
							(start 0.2032 0.3048)
							(mid 0.275042 0.275042)
							(end 0.3048 0.2032)
						)
					)
					(width 0)
					(fill yes)
				)
			)
		)
		(pad "2" smd custom
			(at 0 0.4445 270)
			(size 0.1524 0.1524)
			(layers "F.Cu" "F.Mask" "F.Paste")
			(net "SAS2X28_A_HDD9_RX_-")
			(options
				(clearance outline)
				(anchor circle)
			)
			(primitives
				(gr_poly
					(pts
						(arc
							(start 0.3048 -0.2032)
							(mid 0.275042 -0.275042)
							(end 0.2032 -0.3048)
						)
						(arc
							(start -0.2032 -0.3048)
							(mid -0.275042 -0.275042)
							(end -0.3048 -0.2032)
						)
						(arc
							(start -0.3048 0.2032)
							(mid -0.275042 0.275042)
							(end -0.2032 0.3048)
						)
						(arc
							(start 0.2032 0.3048)
							(mid 0.275042 0.275042)
							(end 0.3048 0.2032)
						)
					)
					(width 0)
					(fill yes)
				)
			)
		)
	)
	(footprint ""
		(layer "F.Cu")
		(at 230.364284 -145.004028 90)
		(property "Reference" "R142"
			(at 0 0 90)
			(layer "F.SilkS")
			(hide yes)
			(effects
				(font
					(size 1.27 1.27)
				)
			)
		)
		(property "Value" "10KR2F-2-GP"
			(at 0.064008 -3.993896 90)
			(unlocked yes)
			(layer "F.Fab")
			(hide yes)
			(effects
				(font
					(size 1.016 1.016)
					(thickness 0.1524)
				)
			)
		)
		(property "Device Type" "R402H16"
			(at 0.064008 -5.517896 90)
			(unlocked yes)
			(layer "F.Fab")
			(hide yes)
			(effects
				(font
					(size 1.016 1.016)
					(thickness 0.1524)
				)
			)
		)
		(duplicate_pad_numbers_are_jumpers no)
		(fp_line
			(start 0.508 -0.9398)
			(end -0.508 -0.9398)
			(stroke
				(width 0.1524)
				(type default)
			)
			(layer "F.SilkS")
		)
		(fp_line
			(start -0.508 -0.9398)
			(end -0.508 0.9398)
			(stroke
				(width 0.1524)
				(type default)
			)
			(layer "F.SilkS")
		)
		(fp_rect
			(start -0.508 0.9398)
			(end 0.508 -0.9398)
			(stroke
				(width 0)
				(type default)
			)
			(fill no)
			(layer "F.CrtYd")
		)
		(fp_rect
			(start -0.508 0.9398)
			(end 0.508 -0.9398)
			(stroke
				(width 0)
				(type default)
			)
			(fill no)
			(layer "F.Fab")
		)
		(pad "1" smd custom
			(at 0 -0.4445 90)
			(size 0.1397 0.1397)
			(layers "F.Cu" "F.Mask" "F.Paste")
			(net "P5VA")
			(options
				(clearance outline)
				(anchor circle)
			)
			(primitives
				(gr_poly
					(pts
						(arc
							(start -0.1778 -0.2794)
							(mid -0.249642 -0.249642)
							(end -0.2794 -0.1778)
						)
						(arc
							(start -0.2794 0.1778)
							(mid -0.249642 0.249642)
							(end -0.1778 0.2794)
						)
						(arc
							(start 0.1778 0.2794)
							(mid 0.249642 0.249642)
							(end 0.2794 0.1778)
						)
						(arc
							(start 0.2794 -0.1778)
							(mid 0.249642 -0.249642)
							(end 0.1778 -0.2794)
						)
					)
					(width 0)
					(fill yes)
				)
			)
		)
		(pad "2" smd custom
			(at 0 0.4445 90)
			(size 0.1397 0.1397)
			(layers "F.Cu" "F.Mask" "F.Paste")
			(net "DRIVE_ACT_3")
			(options
				(clearance outline)
				(anchor circle)
			)
			(primitives
				(gr_poly
					(pts
						(arc
							(start -0.1778 -0.2794)
							(mid -0.249642 -0.249642)
							(end -0.2794 -0.1778)
						)
						(arc
							(start -0.2794 0.1778)
							(mid -0.249642 0.249642)
							(end -0.1778 0.2794)
						)
						(arc
							(start 0.1778 0.2794)
							(mid 0.249642 0.249642)
							(end 0.2794 0.1778)
						)
						(arc
							(start 0.2794 -0.1778)
							(mid 0.249642 -0.249642)
							(end 0.1778 -0.2794)
						)
					)
					(width 0)
					(fill yes)
				)
			)
		)
	)
	(footprint ""
		(layer "F.Cu")
		(at 59.943746 -15.3797 90)
		(property "Reference" "PC14"
			(at 0 0 90)
			(layer "F.SilkS")
			(hide yes)
			(effects
				(font
					(size 1.27 1.27)
				)
			)
		)
		(property "Value" "SC22U25V5MX-GP"
			(at -0.0762 -6.1214 90)
			(unlocked yes)
			(layer "F.Fab")
			(hide yes)
			(effects
				(font
					(size 1.016 1.016)
					(thickness 0.1524)
				)
			)
		)
		(property "Device Type" "C805H58"
			(at -0.0762 -8.1534 90)
			(unlocked yes)
			(layer "F.Fab")
			(hide yes)
			(effects
				(font
					(size 1.016 1.016)
					(thickness 0.1524)
				)
			)
		)
		(duplicate_pad_numbers_are_jumpers no)
		(fp_line
			(start 0.635 0)
			(end -0.635 0)
			(stroke
				(width 0.508)
				(type default)
			)
			(layer "F.SilkS")
		)
		(fp_rect
			(start -0.9652 1.778)
			(end 0.9652 -1.778)
			(stroke
				(width 0)
				(type default)
			)
			(fill no)
			(layer "F.CrtYd")
		)
		(fp_poly
			(pts
				(xy -0.9652 -1.778) (xy 0.9652 -1.778) (xy 0.9652 1.778) (xy -0.9652 1.778)
			)
			(stroke
				(width 0)
				(type default)
			)
			(fill no)
			(layer "F.Fab")
		)
		(pad "1" smd rect
			(at 0 -0.9652 90)
			(size 1.397 1.143)
			(layers "F.Cu" "F.Mask" "F.Paste")
			(net "P5VB_12VIN")
		)
		(pad "2" smd rect
			(at 0 0.9652 90)
			(size 1.397 1.143)
			(layers "F.Cu" "F.Mask" "F.Paste")
			(net "GND")
		)
	)
	(footprint ""
		(layer "F.Cu")
		(at 162.572446 -458.631036)
		(property "Reference" "R388"
			(at 0 0 0)
			(layer "F.SilkS")
			(hide yes)
			(effects
				(font
					(size 1.27 1.27)
				)
			)
		)
		(property "Value" "10KR2F-2-GP"
			(at 0.064008 -3.993896 0)
			(unlocked yes)
			(layer "F.Fab")
			(hide yes)
			(effects
				(font
					(size 1.016 1.016)
					(thickness 0.1524)
				)
			)
		)
		(property "Device Type" "R402H16"
			(at 0.064008 -5.517896 0)
			(unlocked yes)
			(layer "F.Fab")
			(hide yes)
			(effects
				(font
					(size 1.016 1.016)
					(thickness 0.1524)
				)
			)
		)
		(duplicate_pad_numbers_are_jumpers no)
		(fp_line
			(start -0.508 -0.9398)
			(end -0.508 0.9398)
			(stroke
				(width 0.1524)
				(type default)
			)
			(layer "F.SilkS")
		)
		(fp_line
			(start 0.508 -0.9398)
			(end -0.508 -0.9398)
			(stroke
				(width 0.1524)
				(type default)
			)
			(layer "F.SilkS")
		)
		(fp_rect
			(start -0.508 0.9398)
			(end 0.508 -0.9398)
			(stroke
				(width 0)
				(type default)
			)
			(fill no)
			(layer "F.CrtYd")
		)
		(fp_rect
			(start -0.508 0.9398)
			(end 0.508 -0.9398)
			(stroke
				(width 0)
				(type default)
			)
			(fill no)
			(layer "F.Fab")
		)
		(pad "1" smd custom
			(at 0 -0.4445)
			(size 0.1397 0.1397)
			(layers "F.Cu" "F.Mask" "F.Paste")
			(net "P5VA")
			(options
				(clearance outline)
				(anchor circle)
			)
			(primitives
				(gr_poly
					(pts
						(arc
							(start -0.1778 -0.2794)
							(mid -0.249642 -0.249642)
							(end -0.2794 -0.1778)
						)
						(arc
							(start -0.2794 0.1778)
							(mid -0.249642 0.249642)
							(end -0.1778 0.2794)
						)
						(arc
							(start 0.1778 0.2794)
							(mid 0.249642 0.249642)
							(end 0.2794 0.1778)
						)
						(arc
							(start 0.2794 -0.1778)
							(mid 0.249642 -0.249642)
							(end 0.1778 -0.2794)
						)
					)
					(width 0)
					(fill yes)
				)
			)
		)
		(pad "2" smd custom
			(at 0 0.4445)
			(size 0.1397 0.1397)
			(layers "F.Cu" "F.Mask" "F.Paste")
			(net "P5VA_DIV")
			(options
				(clearance outline)
				(anchor circle)
			)
			(primitives
				(gr_poly
					(pts
						(arc
							(start -0.1778 -0.2794)
							(mid -0.249642 -0.249642)
							(end -0.2794 -0.1778)
						)
						(arc
							(start -0.2794 0.1778)
							(mid -0.249642 0.249642)
							(end -0.1778 0.2794)
						)
						(arc
							(start 0.1778 0.2794)
							(mid 0.249642 0.249642)
							(end 0.2794 0.1778)
						)
						(arc
							(start 0.2794 -0.1778)
							(mid 0.249642 -0.249642)
							(end 0.1778 -0.2794)
						)
					)
					(width 0)
					(fill yes)
				)
			)
		)
	)
	(footprint ""
		(layer "F.Cu")
		(at 51.028346 -347.3196 -90)
		(property "Reference" "R496"
			(at 0 0 270)
			(layer "F.SilkS")
			(hide yes)
			(effects
				(font
					(size 1.27 1.27)
				)
			)
		)
		(property "Value" "1KR2F-3-GP"
			(at 0.064008 -3.993896 270)
			(unlocked yes)
			(layer "F.Fab")
			(hide yes)
			(effects
				(font
					(size 1.016 1.016)
					(thickness 0.1524)
				)
			)
		)
		(property "Device Type" "R402H16"
			(at 0.064008 -5.517896 270)
			(unlocked yes)
			(layer "F.Fab")
			(hide yes)
			(effects
				(font
					(size 1.016 1.016)
					(thickness 0.1524)
				)
			)
		)
		(duplicate_pad_numbers_are_jumpers no)
		(fp_line
			(start -0.508 -0.9398)
			(end -0.508 0.9398)
			(stroke
				(width 0.1524)
				(type default)
			)
			(layer "F.SilkS")
		)
		(fp_line
			(start 0.508 -0.9398)
			(end -0.508 -0.9398)
			(stroke
				(width 0.1524)
				(type default)
			)
			(layer "F.SilkS")
		)
		(fp_rect
			(start -0.508 0.9398)
			(end 0.508 -0.9398)
			(stroke
				(width 0)
				(type default)
			)
			(fill no)
			(layer "F.CrtYd")
		)
		(fp_rect
			(start -0.508 0.9398)
			(end 0.508 -0.9398)
			(stroke
				(width 0)
				(type default)
			)
			(fill no)
			(layer "F.Fab")
		)
		(pad "1" smd custom
			(at 0 -0.4445 270)
			(size 0.1397 0.1397)
			(layers "F.Cu" "F.Mask" "F.Paste")
			(net "FLT_HDD6_B")
			(options
				(clearance outline)
				(anchor circle)
			)
			(primitives
				(gr_poly
					(pts
						(arc
							(start -0.1778 -0.2794)
							(mid -0.249642 -0.249642)
							(end -0.2794 -0.1778)
						)
						(arc
							(start -0.2794 0.1778)
							(mid -0.249642 0.249642)
							(end -0.1778 0.2794)
						)
						(arc
							(start 0.1778 0.2794)
							(mid 0.249642 0.249642)
							(end 0.2794 0.1778)
						)
						(arc
							(start 0.2794 -0.1778)
							(mid 0.249642 -0.249642)
							(end 0.1778 -0.2794)
						)
					)
					(width 0)
					(fill yes)
				)
			)
		)
		(pad "2" smd custom
			(at 0 0.4445 270)
			(size 0.1397 0.1397)
			(layers "F.Cu" "F.Mask" "F.Paste")
			(net "FLT_HDD6_DRIVE")
			(options
				(clearance outline)
				(anchor circle)
			)
			(primitives
				(gr_poly
					(pts
						(arc
							(start -0.1778 -0.2794)
							(mid -0.249642 -0.249642)
							(end -0.2794 -0.1778)
						)
						(arc
							(start -0.2794 0.1778)
							(mid -0.249642 0.249642)
							(end -0.1778 0.2794)
						)
						(arc
							(start 0.1778 0.2794)
							(mid 0.249642 0.249642)
							(end 0.2794 0.1778)
						)
						(arc
							(start 0.2794 -0.1778)
							(mid 0.249642 -0.249642)
							(end 0.1778 -0.2794)
						)
					)
					(width 0)
					(fill yes)
				)
			)
		)
	)
	(footprint ""
		(layer "F.Cu")
		(at 32.9946 -298.958 180)
		(property "Reference" "C223"
			(at 0 0 180)
			(layer "F.SilkS")
			(hide yes)
			(effects
				(font
					(size 1.27 1.27)
				)
			)
		)
		(property "Value" "SC10U25V6KX-1GP"
			(at -0.0762 -5.1308 180)
			(unlocked yes)
			(layer "F.Fab")
			(hide yes)
			(effects
				(font
					(size 1.016 1.016)
					(thickness 0.1524)
				)
			)
		)
		(property "Device Type" "C1206H71"
			(at -0.127 -6.6548 180)
			(unlocked yes)
			(layer "F.Fab")
			(hide yes)
			(effects
				(font
					(size 1.016 1.016)
					(thickness 0.1524)
				)
			)
		)
		(duplicate_pad_numbers_are_jumpers no)
		(fp_line
			(start 1.016 2.2352)
			(end -1.016 2.2352)
			(stroke
				(width 0.1524)
				(type default)
			)
			(layer "F.SilkS")
		)
		(fp_line
			(start 1.016 0.8382)
			(end 1.016 2.2352)
			(stroke
				(width 0.1524)
				(type default)
			)
			(layer "F.SilkS")
		)
		(fp_line
			(start 1.016 -2.2352)
			(end 1.016 -0.8382)
			(stroke
				(width 0.1524)
				(type default)
			)
			(layer "F.SilkS")
		)
		(fp_line
			(start -1.016 2.2352)
			(end -1.016 0.8382)
			(stroke
				(width 0.1524)
				(type default)
			)
			(layer "F.SilkS")
		)
		(fp_line
			(start -1.016 -0.8382)
			(end -1.016 -2.2352)
			(stroke
				(width 0.1524)
				(type default)
			)
			(layer "F.SilkS")
		)
		(fp_line
			(start -1.016 -2.2352)
			(end 1.016 -2.2352)
			(stroke
				(width 0.1524)
				(type default)
			)
			(layer "F.SilkS")
		)
		(fp_rect
			(start -1.0922 2.3114)
			(end 1.0922 -2.3114)
			(stroke
				(width 0)
				(type default)
			)
			(fill no)
			(layer "F.CrtYd")
		)
		(fp_poly
			(pts
				(xy 1.0922 -2.3114) (xy 1.0922 2.3114) (xy -1.0922 2.3114) (xy -1.0922 -2.3114)
			)
			(stroke
				(width 0)
				(type default)
			)
			(fill no)
			(layer "F.Fab")
		)
		(pad "1" smd rect
			(at 0 -1.397 180)
			(size 1.651 1.27)
			(layers "F.Cu" "F.Mask" "F.Paste")
			(net "P12V_HDD7")
		)
		(pad "2" smd rect
			(at 0 1.397 180)
			(size 1.651 1.27)
			(layers "F.Cu" "F.Mask" "F.Paste")
			(net "GND")
		)
	)
	(footprint ""
		(layer "F.Cu")
		(at 85.781134 -493.625886 -90)
		(property "Reference" "R445"
			(at 0 0 270)
			(layer "F.SilkS")
			(hide yes)
			(effects
				(font
					(size 1.27 1.27)
				)
			)
		)
		(property "Value" "4K7R2J-2-GP"
			(at 0.064008 -3.993896 270)
			(unlocked yes)
			(layer "F.Fab")
			(hide yes)
			(effects
				(font
					(size 1.016 1.016)
					(thickness 0.1524)
				)
			)
		)
		(property "Device Type" "R402H16"
			(at 0.064008 -5.517896 270)
			(unlocked yes)
			(layer "F.Fab")
			(hide yes)
			(effects
				(font
					(size 1.016 1.016)
					(thickness 0.1524)
				)
			)
		)
		(duplicate_pad_numbers_are_jumpers no)
		(fp_line
			(start -0.508 -0.9398)
			(end -0.508 0.9398)
			(stroke
				(width 0.1524)
				(type default)
			)
			(layer "F.SilkS")
		)
		(fp_line
			(start 0.508 -0.9398)
			(end -0.508 -0.9398)
			(stroke
				(width 0.1524)
				(type default)
			)
			(layer "F.SilkS")
		)
		(fp_rect
			(start -0.508 0.9398)
			(end 0.508 -0.9398)
			(stroke
				(width 0)
				(type default)
			)
			(fill no)
			(layer "F.CrtYd")
		)
		(fp_rect
			(start -0.508 0.9398)
			(end 0.508 -0.9398)
			(stroke
				(width 0)
				(type default)
			)
			(fill no)
			(layer "F.Fab")
		)
		(pad "1" smd custom
			(at 0 -0.4445 270)
			(size 0.1397 0.1397)
			(layers "F.Cu" "F.Mask" "F.Paste")
			(net "P3V3")
			(options
				(clearance outline)
				(anchor circle)
			)
			(primitives
				(gr_poly
					(pts
						(arc
							(start -0.1778 -0.2794)
							(mid -0.249642 -0.249642)
							(end -0.2794 -0.1778)
						)
						(arc
							(start -0.2794 0.1778)
							(mid -0.249642 0.249642)
							(end -0.1778 0.2794)
						)
						(arc
							(start 0.1778 0.2794)
							(mid 0.249642 0.249642)
							(end 0.2794 0.1778)
						)
						(arc
							(start 0.2794 -0.1778)
							(mid 0.249642 -0.249642)
							(end 0.1778 -0.2794)
						)
					)
					(width 0)
					(fill yes)
				)
			)
		)
		(pad "2" smd custom
			(at 0 0.4445 270)
			(size 0.1397 0.1397)
			(layers "F.Cu" "F.Mask" "F.Paste")
			(net "SAS_EXP_B_PWR5")
			(options
				(clearance outline)
				(anchor circle)
			)
			(primitives
				(gr_poly
					(pts
						(arc
							(start -0.1778 -0.2794)
							(mid -0.249642 -0.249642)
							(end -0.2794 -0.1778)
						)
						(arc
							(start -0.2794 0.1778)
							(mid -0.249642 0.249642)
							(end -0.1778 0.2794)
						)
						(arc
							(start 0.1778 0.2794)
							(mid 0.249642 0.249642)
							(end 0.2794 0.1778)
						)
						(arc
							(start 0.2794 -0.1778)
							(mid 0.249642 -0.249642)
							(end 0.1778 -0.2794)
						)
					)
					(width 0)
					(fill yes)
				)
			)
		)
	)
	(footprint ""
		(layer "F.Cu")
		(at 21.742146 -254.1143 90)
		(property "Reference" "R371"
			(at 0 0 90)
			(layer "F.SilkS")
			(hide yes)
			(effects
				(font
					(size 1.27 1.27)
				)
			)
		)
		(property "Value" "4K7R2J-2-GP"
			(at 0.064008 -3.993896 90)
			(unlocked yes)
			(layer "F.Fab")
			(hide yes)
			(effects
				(font
					(size 1.016 1.016)
					(thickness 0.1524)
				)
			)
		)
		(property "Device Type" "R402H16"
			(at 0.064008 -5.517896 90)
			(unlocked yes)
			(layer "F.Fab")
			(hide yes)
			(effects
				(font
					(size 1.016 1.016)
					(thickness 0.1524)
				)
			)
		)
		(duplicate_pad_numbers_are_jumpers no)
		(fp_line
			(start 0.508 -0.9398)
			(end -0.508 -0.9398)
			(stroke
				(width 0.1524)
				(type default)
			)
			(layer "F.SilkS")
		)
		(fp_line
			(start -0.508 -0.9398)
			(end -0.508 0.9398)
			(stroke
				(width 0.1524)
				(type default)
			)
			(layer "F.SilkS")
		)
		(fp_rect
			(start -0.508 0.9398)
			(end 0.508 -0.9398)
			(stroke
				(width 0)
				(type default)
			)
			(fill no)
			(layer "F.CrtYd")
		)
		(fp_rect
			(start -0.508 0.9398)
			(end 0.508 -0.9398)
			(stroke
				(width 0)
				(type default)
			)
			(fill no)
			(layer "F.Fab")
		)
		(pad "1" smd custom
			(at 0 -0.4445 90)
			(size 0.1397 0.1397)
			(layers "F.Cu" "F.Mask" "F.Paste")
			(net "P3V3")
			(options
				(clearance outline)
				(anchor circle)
			)
			(primitives
				(gr_poly
					(pts
						(arc
							(start -0.1778 -0.2794)
							(mid -0.249642 -0.249642)
							(end -0.2794 -0.1778)
						)
						(arc
							(start -0.2794 0.1778)
							(mid -0.249642 0.249642)
							(end -0.1778 0.2794)
						)
						(arc
							(start 0.1778 0.2794)
							(mid 0.249642 0.249642)
							(end 0.2794 0.1778)
						)
						(arc
							(start 0.2794 -0.1778)
							(mid 0.249642 -0.249642)
							(end 0.1778 -0.2794)
						)
					)
					(width 0)
					(fill yes)
				)
			)
		)
		(pad "2" smd custom
			(at 0 0.4445 90)
			(size 0.1397 0.1397)
			(layers "F.Cu" "F.Mask" "F.Paste")
			(net "I2C_D_SCL")
			(options
				(clearance outline)
				(anchor circle)
			)
			(primitives
				(gr_poly
					(pts
						(arc
							(start -0.1778 -0.2794)
							(mid -0.249642 -0.249642)
							(end -0.2794 -0.1778)
						)
						(arc
							(start -0.2794 0.1778)
							(mid -0.249642 0.249642)
							(end -0.1778 0.2794)
						)
						(arc
							(start 0.1778 0.2794)
							(mid 0.249642 0.249642)
							(end 0.2794 0.1778)
						)
						(arc
							(start 0.2794 -0.1778)
							(mid 0.249642 -0.249642)
							(end 0.1778 -0.2794)
						)
					)
					(width 0)
					(fill yes)
				)
			)
		)
	)
	(footprint ""
		(layer "F.Cu")
		(at 27.2923 -341.5284 -90)
		(property "Reference" "C38"
			(at 0 0 270)
			(layer "F.SilkS")
			(hide yes)
			(effects
				(font
					(size 1.27 1.27)
				)
			)
		)
		(property "Value" "SCD01U50V2KX-1GP"
			(at 1.1811 -2.7051 270)
			(unlocked yes)
			(layer "F.Fab")
			(hide yes)
			(effects
				(font
					(size 1.016 1.016)
					(thickness 0.1524)
				)
			)
		)
		(property "Device Type" "C402H22"
			(at 1.1811 -4.2291 270)
			(unlocked yes)
			(layer "F.Fab")
			(hide yes)
			(effects
				(font
					(size 1.016 1.016)
					(thickness 0.1524)
				)
			)
		)
		(duplicate_pad_numbers_are_jumpers no)
		(fp_rect
			(start -0.4318 0.9525)
			(end 0.4318 -0.9525)
			(stroke
				(width 0)
				(type default)
			)
			(fill no)
			(layer "F.CrtYd")
		)
		(fp_rect
			(start -0.4318 0.9525)
			(end 0.4318 -0.9525)
			(stroke
				(width 0)
				(type default)
			)
			(fill no)
			(layer "F.Fab")
		)
		(pad "1" smd custom
			(at 0 -0.4445 270)
			(size 0.1524 0.1524)
			(layers "F.Cu" "F.Mask" "F.Paste")
			(net "SEB_AB_TX+")
			(options
				(clearance outline)
				(anchor circle)
			)
			(primitives
				(gr_poly
					(pts
						(arc
							(start 0.3048 -0.2032)
							(mid 0.275042 -0.275042)
							(end 0.2032 -0.3048)
						)
						(arc
							(start -0.2032 -0.3048)
							(mid -0.275042 -0.275042)
							(end -0.3048 -0.2032)
						)
						(arc
							(start -0.3048 0.2032)
							(mid -0.275042 0.275042)
							(end -0.2032 0.3048)
						)
						(arc
							(start 0.2032 0.3048)
							(mid 0.275042 0.275042)
							(end 0.3048 0.2032)
						)
					)
					(width 0)
					(fill yes)
				)
			)
		)
		(pad "2" smd custom
			(at 0 0.4445 270)
			(size 0.1524 0.1524)
			(layers "F.Cu" "F.Mask" "F.Paste")
			(net "SEB_AB_RX+")
			(options
				(clearance outline)
				(anchor circle)
			)
			(primitives
				(gr_poly
					(pts
						(arc
							(start 0.3048 -0.2032)
							(mid 0.275042 -0.275042)
							(end 0.2032 -0.3048)
						)
						(arc
							(start -0.2032 -0.3048)
							(mid -0.275042 -0.275042)
							(end -0.3048 -0.2032)
						)
						(arc
							(start -0.3048 0.2032)
							(mid -0.275042 0.275042)
							(end -0.2032 0.3048)
						)
						(arc
							(start 0.2032 0.3048)
							(mid 0.275042 0.275042)
							(end 0.3048 0.2032)
						)
					)
					(width 0)
					(fill yes)
				)
			)
		)
	)
	(footprint ""
		(layer "F.Cu")
		(at 8.636 -269.24)
		(property "Reference" "R502"
			(at 0 0 0)
			(layer "F.SilkS")
			(hide yes)
			(effects
				(font
					(size 1.27 1.27)
				)
			)
		)
		(property "Value" "1KR2F-3-GP"
			(at 0.064008 -3.993896 0)
			(unlocked yes)
			(layer "F.Fab")
			(hide yes)
			(effects
				(font
					(size 1.016 1.016)
					(thickness 0.1524)
				)
			)
		)
		(property "Device Type" "R402H16"
			(at 0.064008 -5.517896 0)
			(unlocked yes)
			(layer "F.Fab")
			(hide yes)
			(effects
				(font
					(size 1.016 1.016)
					(thickness 0.1524)
				)
			)
		)
		(duplicate_pad_numbers_are_jumpers no)
		(fp_line
			(start -0.508 -0.9398)
			(end -0.508 0.9398)
			(stroke
				(width 0.1524)
				(type default)
			)
			(layer "F.SilkS")
		)
		(fp_line
			(start 0.508 -0.9398)
			(end -0.508 -0.9398)
			(stroke
				(width 0.1524)
				(type default)
			)
			(layer "F.SilkS")
		)
		(fp_rect
			(start -0.508 0.9398)
			(end 0.508 -0.9398)
			(stroke
				(width 0)
				(type default)
			)
			(fill no)
			(layer "F.CrtYd")
		)
		(fp_rect
			(start -0.508 0.9398)
			(end 0.508 -0.9398)
			(stroke
				(width 0)
				(type default)
			)
			(fill no)
			(layer "F.Fab")
		)
		(pad "1" smd custom
			(at 0 -0.4445)
			(size 0.1397 0.1397)
			(layers "F.Cu" "F.Mask" "F.Paste")
			(net "FLT_HDD12_B")
			(options
				(clearance outline)
				(anchor circle)
			)
			(primitives
				(gr_poly
					(pts
						(arc
							(start -0.1778 -0.2794)
							(mid -0.249642 -0.249642)
							(end -0.2794 -0.1778)
						)
						(arc
							(start -0.2794 0.1778)
							(mid -0.249642 0.249642)
							(end -0.1778 0.2794)
						)
						(arc
							(start 0.1778 0.2794)
							(mid 0.249642 0.249642)
							(end 0.2794 0.1778)
						)
						(arc
							(start 0.2794 -0.1778)
							(mid 0.249642 -0.249642)
							(end 0.1778 -0.2794)
						)
					)
					(width 0)
					(fill yes)
				)
			)
		)
		(pad "2" smd custom
			(at 0 0.4445)
			(size 0.1397 0.1397)
			(layers "F.Cu" "F.Mask" "F.Paste")
			(net "FLT_HDD12_DRIVE")
			(options
				(clearance outline)
				(anchor circle)
			)
			(primitives
				(gr_poly
					(pts
						(arc
							(start -0.1778 -0.2794)
							(mid -0.249642 -0.249642)
							(end -0.2794 -0.1778)
						)
						(arc
							(start -0.2794 0.1778)
							(mid -0.249642 0.249642)
							(end -0.1778 0.2794)
						)
						(arc
							(start 0.1778 0.2794)
							(mid 0.249642 0.249642)
							(end 0.2794 0.1778)
						)
						(arc
							(start 0.2794 -0.1778)
							(mid 0.249642 -0.249642)
							(end 0.1778 -0.2794)
						)
					)
					(width 0)
					(fill yes)
				)
			)
		)
	)
	(footprint ""
		(layer "F.Cu")
		(at 34.926016 -441.280042 180)
		(property "Reference" "C269"
			(at 0 0 180)
			(layer "F.SilkS")
			(hide yes)
			(effects
				(font
					(size 1.27 1.27)
				)
			)
		)
		(property "Value" "SCD1U10V2KX-5GP"
			(at 1.1811 -2.7051 180)
			(unlocked yes)
			(layer "F.Fab")
			(hide yes)
			(effects
				(font
					(size 1.016 1.016)
					(thickness 0.1524)
				)
			)
		)
		(property "Device Type" "C402H22"
			(at 1.1811 -4.2291 180)
			(unlocked yes)
			(layer "F.Fab")
			(hide yes)
			(effects
				(font
					(size 1.016 1.016)
					(thickness 0.1524)
				)
			)
		)
		(duplicate_pad_numbers_are_jumpers no)
		(fp_rect
			(start -0.4318 0.9525)
			(end 0.4318 -0.9525)
			(stroke
				(width 0)
				(type default)
			)
			(fill no)
			(layer "F.CrtYd")
		)
		(fp_rect
			(start -0.4318 0.9525)
			(end 0.4318 -0.9525)
			(stroke
				(width 0)
				(type default)
			)
			(fill no)
			(layer "F.Fab")
		)
		(pad "1" smd custom
			(at 0 -0.4445 180)
			(size 0.1524 0.1524)
			(layers "F.Cu" "F.Mask" "F.Paste")
			(net "P3V3")
			(options
				(clearance outline)
				(anchor circle)
			)
			(primitives
				(gr_poly
					(pts
						(arc
							(start 0.3048 -0.2032)
							(mid 0.275042 -0.275042)
							(end 0.2032 -0.3048)
						)
						(arc
							(start -0.2032 -0.3048)
							(mid -0.275042 -0.275042)
							(end -0.3048 -0.2032)
						)
						(arc
							(start -0.3048 0.2032)
							(mid -0.275042 0.275042)
							(end -0.2032 0.3048)
						)
						(arc
							(start 0.2032 0.3048)
							(mid 0.275042 0.275042)
							(end 0.3048 0.2032)
						)
					)
					(width 0)
					(fill yes)
				)
			)
		)
		(pad "2" smd custom
			(at 0 0.4445 180)
			(size 0.1524 0.1524)
			(layers "F.Cu" "F.Mask" "F.Paste")
			(net "GND")
			(options
				(clearance outline)
				(anchor circle)
			)
			(primitives
				(gr_poly
					(pts
						(arc
							(start 0.3048 -0.2032)
							(mid 0.275042 -0.275042)
							(end 0.2032 -0.3048)
						)
						(arc
							(start -0.2032 -0.3048)
							(mid -0.275042 -0.275042)
							(end -0.3048 -0.2032)
						)
						(arc
							(start -0.3048 0.2032)
							(mid -0.275042 0.275042)
							(end -0.2032 0.3048)
						)
						(arc
							(start 0.2032 0.3048)
							(mid 0.275042 0.275042)
							(end 0.3048 0.2032)
						)
					)
					(width 0)
					(fill yes)
				)
			)
		)
	)
	(footprint ""
		(layer "F.Cu")
		(at 44.449746 -18.5547 180)
		(property "Reference" "PR50"
			(at 0 0 180)
			(layer "F.SilkS")
			(hide yes)
			(effects
				(font
					(size 1.27 1.27)
				)
			)
		)
		(property "Value" "10KR2F-2-GP"
			(at 0.064008 -3.993896 180)
			(unlocked yes)
			(layer "F.Fab")
			(hide yes)
			(effects
				(font
					(size 1.016 1.016)
					(thickness 0.1524)
				)
			)
		)
		(property "Device Type" "R402H16"
			(at 0.064008 -5.517896 180)
			(unlocked yes)
			(layer "F.Fab")
			(hide yes)
			(effects
				(font
					(size 1.016 1.016)
					(thickness 0.1524)
				)
			)
		)
		(duplicate_pad_numbers_are_jumpers no)
		(fp_line
			(start 0.508 -0.9398)
			(end -0.508 -0.9398)
			(stroke
				(width 0.1524)
				(type default)
			)
			(layer "F.SilkS")
		)
		(fp_line
			(start -0.508 -0.9398)
			(end -0.508 0.9398)
			(stroke
				(width 0.1524)
				(type default)
			)
			(layer "F.SilkS")
		)
		(fp_rect
			(start -0.508 0.9398)
			(end 0.508 -0.9398)
			(stroke
				(width 0)
				(type default)
			)
			(fill no)
			(layer "F.CrtYd")
		)
		(fp_rect
			(start -0.508 0.9398)
			(end 0.508 -0.9398)
			(stroke
				(width 0)
				(type default)
			)
			(fill no)
			(layer "F.Fab")
		)
		(pad "1" smd custom
			(at 0 -0.4445 180)
			(size 0.1397 0.1397)
			(layers "F.Cu" "F.Mask" "F.Paste")
			(net "P5VB_LL")
			(options
				(clearance outline)
				(anchor circle)
			)
			(primitives
				(gr_poly
					(pts
						(arc
							(start -0.1778 -0.2794)
							(mid -0.249642 -0.249642)
							(end -0.2794 -0.1778)
						)
						(arc
							(start -0.2794 0.1778)
							(mid -0.249642 0.249642)
							(end -0.1778 0.2794)
						)
						(arc
							(start 0.1778 0.2794)
							(mid 0.249642 0.249642)
							(end 0.2794 0.1778)
						)
						(arc
							(start 0.2794 -0.1778)
							(mid 0.249642 -0.249642)
							(end 0.1778 -0.2794)
						)
					)
					(width 0)
					(fill yes)
				)
			)
		)
		(pad "2" smd custom
			(at 0 0.4445 180)
			(size 0.1397 0.1397)
			(layers "F.Cu" "F.Mask" "F.Paste")
			(net "P5VB_LL_NET")
			(options
				(clearance outline)
				(anchor circle)
			)
			(primitives
				(gr_poly
					(pts
						(arc
							(start -0.1778 -0.2794)
							(mid -0.249642 -0.249642)
							(end -0.2794 -0.1778)
						)
						(arc
							(start -0.2794 0.1778)
							(mid -0.249642 0.249642)
							(end -0.1778 0.2794)
						)
						(arc
							(start 0.1778 0.2794)
							(mid 0.249642 0.249642)
							(end 0.2794 0.1778)
						)
						(arc
							(start 0.2794 -0.1778)
							(mid 0.249642 -0.249642)
							(end 0.1778 -0.2794)
						)
					)
					(width 0)
					(fill yes)
				)
			)
		)
	)
	(footprint ""
		(layer "F.Cu")
		(at 41.909746 -434.368702)
		(property "Reference" "Q21"
			(at 0 0 0)
			(layer "F.SilkS")
			(hide yes)
			(effects
				(font
					(size 1.27 1.27)
				)
			)
		)
		(property "Value" "AO4406AL-GP"
			(at -3.707384 -1.5367 0)
			(unlocked yes)
			(layer "F.Fab")
			(hide yes)
			(effects
				(font
					(size 1.016 1.016)
					(thickness 0.1524)
				)
			)
		)
		(property "Device Type" "SOIC8H69"
			(at -3.707384 -3.0607 0)
			(unlocked yes)
			(layer "F.Fab")
			(hide yes)
			(effects
				(font
					(size 1.016 1.016)
					(thickness 0.1524)
				)
			)
		)
		(duplicate_pad_numbers_are_jumpers no)
		(fp_line
			(start -2.7432 -1.4224)
			(end -2.7432 1.4224)
			(stroke
				(width 0.1524)
				(type default)
			)
			(layer "F.SilkS")
		)
		(fp_line
			(start -2.7432 1.4224)
			(end -2.6416 1.4224)
			(stroke
				(width 0.1524)
				(type default)
			)
			(layer "F.SilkS")
		)
		(fp_line
			(start -2.7432 1.4224)
			(end 2.1336 1.4224)
			(stroke
				(width 0.1524)
				(type default)
			)
			(layer "F.SilkS")
		)
		(fp_line
			(start -2.7178 -0.508)
			(end -2.1844 -0.0508)
			(stroke
				(width 0.1524)
				(type default)
			)
			(layer "F.SilkS")
		)
		(fp_line
			(start -2.6289 3.4417)
			(end -2.6289 1.4732)
			(stroke
				(width 0.381)
				(type default)
			)
			(layer "F.SilkS")
		)
		(fp_line
			(start -2.1844 -0.0508)
			(end -2.7178 0.508)
			(stroke
				(width 0.1524)
				(type default)
			)
			(layer "F.SilkS")
		)
		(fp_line
			(start 2.1336 -1.4224)
			(end -2.7432 -1.4224)
			(stroke
				(width 0.1524)
				(type default)
			)
			(layer "F.SilkS")
		)
		(fp_line
			(start 2.1336 1.4224)
			(end 2.1336 -1.4224)
			(stroke
				(width 0.1524)
				(type default)
			)
			(layer "F.SilkS")
		)
		(fp_poly
			(pts
				(xy -2.2098 -1.4224) (xy -2.2098 1.4224) (xy 2.2098 1.4224) (xy 2.2098 -1.4224)
			)
			(stroke
				(width 0)
				(type default)
			)
			(fill yes)
			(layer "F.SilkS")
		)
		(fp_rect
			(start -2.450084 2.999994)
			(end 2.450084 -2.999994)
			(stroke
				(width 0)
				(type default)
			)
			(fill no)
			(layer "F.CrtYd")
		)
		(fp_poly
			(pts
				(xy -2.8194 3.6322) (xy -2.8194 -3.6322) (xy 2.8194 -3.6322) (xy 2.8194 1.18364) (xy 2.450084 1.18364)
				(xy 2.450084 -2.999994) (xy -2.450084 -2.999994) (xy -2.450084 2.999994) (xy 2.450084 2.999994)
				(xy 2.450084 1.18618) (xy 2.8194 1.18618) (xy 2.8194 3.6322)
			)
			(stroke
				(width 0)
				(type default)
			)
			(fill no)
			(layer "F.CrtYd")
		)
		(fp_rect
			(start -2.8194 3.6322)
			(end 2.8194 -3.6322)
			(stroke
				(width 0)
				(type default)
			)
			(fill no)
			(layer "F.Fab")
		)
		(pad "1" smd rect
			(at -1.905 2.54)
			(size 0.635 1.651)
			(layers "F.Cu" "F.Mask" "F.Paste")
			(net "P5V_HDD10")
		)
		(pad "2" smd rect
			(at -0.635 2.54)
			(size 0.635 1.651)
			(layers "F.Cu" "F.Mask" "F.Paste")
			(net "P5V_HDD10")
		)
		(pad "3" smd rect
			(at 0.635 2.54)
			(size 0.635 1.651)
			(layers "F.Cu" "F.Mask" "F.Paste")
			(net "P5V_HDD10")
		)
		(pad "4" smd rect
			(at 1.905 2.54)
			(size 0.635 1.651)
			(layers "F.Cu" "F.Mask" "F.Paste")
			(net "SW_HDD10_P")
		)
		(pad "5" smd rect
			(at 1.905 -2.54)
			(size 0.635 1.651)
			(layers "F.Cu" "F.Mask" "F.Paste")
			(net "P5VC")
		)
		(pad "6" smd rect
			(at 0.635 -2.54)
			(size 0.635 1.651)
			(layers "F.Cu" "F.Mask" "F.Paste")
			(net "P5VC")
		)
		(pad "7" smd rect
			(at -0.635 -2.54)
			(size 0.635 1.651)
			(layers "F.Cu" "F.Mask" "F.Paste")
			(net "P5VC")
		)
		(pad "8" smd rect
			(at -1.905 -2.54)
			(size 0.635 1.651)
			(layers "F.Cu" "F.Mask" "F.Paste")
			(net "P5VC")
		)
	)
	(footprint ""
		(layer "F.Cu")
		(at 180.987446 -459.824836)
		(property "Reference" "R387"
			(at 0 0 0)
			(layer "F.SilkS")
			(hide yes)
			(effects
				(font
					(size 1.27 1.27)
				)
			)
		)
		(property "Value" "10KR2F-2-GP"
			(at 0.064008 -3.993896 0)
			(unlocked yes)
			(layer "F.Fab")
			(hide yes)
			(effects
				(font
					(size 1.016 1.016)
					(thickness 0.1524)
				)
			)
		)
		(property "Device Type" "R402H16"
			(at 0.064008 -5.517896 0)
			(unlocked yes)
			(layer "F.Fab")
			(hide yes)
			(effects
				(font
					(size 1.016 1.016)
					(thickness 0.1524)
				)
			)
		)
		(duplicate_pad_numbers_are_jumpers no)
		(fp_line
			(start -0.508 -0.9398)
			(end -0.508 0.9398)
			(stroke
				(width 0.1524)
				(type default)
			)
			(layer "F.SilkS")
		)
		(fp_line
			(start 0.508 -0.9398)
			(end -0.508 -0.9398)
			(stroke
				(width 0.1524)
				(type default)
			)
			(layer "F.SilkS")
		)
		(fp_rect
			(start -0.508 0.9398)
			(end 0.508 -0.9398)
			(stroke
				(width 0)
				(type default)
			)
			(fill no)
			(layer "F.CrtYd")
		)
		(fp_rect
			(start -0.508 0.9398)
			(end 0.508 -0.9398)
			(stroke
				(width 0)
				(type default)
			)
			(fill no)
			(layer "F.Fab")
		)
		(pad "1" smd custom
			(at 0 -0.4445)
			(size 0.1397 0.1397)
			(layers "F.Cu" "F.Mask" "F.Paste")
			(net "P12V")
			(options
				(clearance outline)
				(anchor circle)
			)
			(primitives
				(gr_poly
					(pts
						(arc
							(start -0.1778 -0.2794)
							(mid -0.249642 -0.249642)
							(end -0.2794 -0.1778)
						)
						(arc
							(start -0.2794 0.1778)
							(mid -0.249642 0.249642)
							(end -0.1778 0.2794)
						)
						(arc
							(start 0.1778 0.2794)
							(mid 0.249642 0.249642)
							(end 0.2794 0.1778)
						)
						(arc
							(start 0.2794 -0.1778)
							(mid 0.249642 -0.249642)
							(end 0.1778 -0.2794)
						)
					)
					(width 0)
					(fill yes)
				)
			)
		)
		(pad "2" smd custom
			(at 0 0.4445)
			(size 0.1397 0.1397)
			(layers "F.Cu" "F.Mask" "F.Paste")
			(net "P12V_DIV")
			(options
				(clearance outline)
				(anchor circle)
			)
			(primitives
				(gr_poly
					(pts
						(arc
							(start -0.1778 -0.2794)
							(mid -0.249642 -0.249642)
							(end -0.2794 -0.1778)
						)
						(arc
							(start -0.2794 0.1778)
							(mid -0.249642 0.249642)
							(end -0.1778 0.2794)
						)
						(arc
							(start 0.1778 0.2794)
							(mid 0.249642 0.249642)
							(end 0.2794 0.1778)
						)
						(arc
							(start 0.2794 -0.1778)
							(mid 0.249642 -0.249642)
							(end 0.1778 -0.2794)
						)
					)
					(width 0)
					(fill yes)
				)
			)
		)
	)
	(footprint ""
		(layer "F.Cu")
		(at 219.8878 -393.5984 180)
		(property "Reference" "C130"
			(at 0 0 180)
			(layer "F.SilkS")
			(hide yes)
			(effects
				(font
					(size 1.27 1.27)
				)
			)
		)
		(property "Value" "SC1U25V3KX-1-GP"
			(at 0 -2.8194 180)
			(unlocked yes)
			(layer "F.Fab")
			(hide yes)
			(effects
				(font
					(size 1.016 1.016)
					(thickness 0.1524)
				)
			)
		)
		(property "Device Type" "C603H36"
			(at 0 -4.3434 180)
			(unlocked yes)
			(layer "F.Fab")
			(hide yes)
			(effects
				(font
					(size 1.016 1.016)
					(thickness 0.1524)
				)
			)
		)
		(duplicate_pad_numbers_are_jumpers no)
		(fp_line
			(start 0.508 0)
			(end -0.508 0)
			(stroke
				(width 0.2032)
				(type default)
			)
			(layer "F.SilkS")
		)
		(fp_rect
			(start -0.5842 1.3335)
			(end 0.5842 -1.3335)
			(stroke
				(width 0)
				(type default)
			)
			(fill no)
			(layer "F.CrtYd")
		)
		(fp_rect
			(start -0.5842 1.3335)
			(end 0.5842 -1.3335)
			(stroke
				(width 0)
				(type default)
			)
			(fill no)
			(layer "F.Fab")
		)
		(pad "1" smd custom
			(at 0 -0.762 180)
			(size 0.2159 0.2159)
			(layers "F.Cu" "F.Mask" "F.Paste")
			(net "P12V_HDD1")
			(options
				(clearance outline)
				(anchor circle)
			)
			(primitives
				(gr_poly
					(pts
						(arc
							(start -0.3302 -0.4318)
							(mid -0.402042 -0.402042)
							(end -0.4318 -0.3302)
						)
						(arc
							(start -0.4318 0.3302)
							(mid -0.402042 0.402042)
							(end -0.3302 0.4318)
						)
						(arc
							(start 0.3302 0.4318)
							(mid 0.402042 0.402042)
							(end 0.4318 0.3302)
						)
						(arc
							(start 0.4318 -0.3302)
							(mid 0.402042 -0.402042)
							(end 0.3302 -0.4318)
						)
					)
					(width 0)
					(fill yes)
				)
			)
		)
		(pad "2" smd custom
			(at 0 0.762 180)
			(size 0.2159 0.2159)
			(layers "F.Cu" "F.Mask" "F.Paste")
			(net "GND")
			(options
				(clearance outline)
				(anchor circle)
			)
			(primitives
				(gr_poly
					(pts
						(arc
							(start -0.3302 -0.4318)
							(mid -0.402042 -0.402042)
							(end -0.4318 -0.3302)
						)
						(arc
							(start -0.4318 0.3302)
							(mid -0.402042 0.402042)
							(end -0.3302 0.4318)
						)
						(arc
							(start 0.3302 0.4318)
							(mid 0.402042 0.402042)
							(end 0.4318 0.3302)
						)
						(arc
							(start 0.4318 -0.3302)
							(mid 0.402042 -0.402042)
							(end 0.3302 -0.4318)
						)
					)
					(width 0)
					(fill yes)
				)
			)
		)
	)
	(footprint ""
		(layer "F.Cu")
		(at 43.306746 -205.895702 180)
		(property "Reference" "R470"
			(at 0 0 180)
			(layer "F.SilkS")
			(hide yes)
			(effects
				(font
					(size 1.27 1.27)
				)
			)
		)
		(property "Value" "4K7R2J-2-GP"
			(at 0.064008 -3.993896 180)
			(unlocked yes)
			(layer "F.Fab")
			(hide yes)
			(effects
				(font
					(size 1.016 1.016)
					(thickness 0.1524)
				)
			)
		)
		(property "Device Type" "R402H16"
			(at 0.064008 -5.517896 180)
			(unlocked yes)
			(layer "F.Fab")
			(hide yes)
			(effects
				(font
					(size 1.016 1.016)
					(thickness 0.1524)
				)
			)
		)
		(duplicate_pad_numbers_are_jumpers no)
		(fp_line
			(start 0.508 -0.9398)
			(end -0.508 -0.9398)
			(stroke
				(width 0.1524)
				(type default)
			)
			(layer "F.SilkS")
		)
		(fp_line
			(start -0.508 -0.9398)
			(end -0.508 0.9398)
			(stroke
				(width 0.1524)
				(type default)
			)
			(layer "F.SilkS")
		)
		(fp_rect
			(start -0.508 0.9398)
			(end 0.508 -0.9398)
			(stroke
				(width 0)
				(type default)
			)
			(fill no)
			(layer "F.CrtYd")
		)
		(fp_rect
			(start -0.508 0.9398)
			(end 0.508 -0.9398)
			(stroke
				(width 0)
				(type default)
			)
			(fill no)
			(layer "F.Fab")
		)
		(pad "1" smd custom
			(at 0 -0.4445 180)
			(size 0.1397 0.1397)
			(layers "F.Cu" "F.Mask" "F.Paste")
			(net "P3V3")
			(options
				(clearance outline)
				(anchor circle)
			)
			(primitives
				(gr_poly
					(pts
						(arc
							(start -0.1778 -0.2794)
							(mid -0.249642 -0.249642)
							(end -0.2794 -0.1778)
						)
						(arc
							(start -0.2794 0.1778)
							(mid -0.249642 0.249642)
							(end -0.1778 0.2794)
						)
						(arc
							(start 0.1778 0.2794)
							(mid 0.249642 0.249642)
							(end 0.2794 0.1778)
						)
						(arc
							(start 0.2794 -0.1778)
							(mid 0.249642 -0.249642)
							(end 0.1778 -0.2794)
						)
					)
					(width 0)
					(fill yes)
				)
			)
		)
		(pad "2" smd custom
			(at 0 0.4445 180)
			(size 0.1397 0.1397)
			(layers "F.Cu" "F.Mask" "F.Paste")
			(net "SAS_EXP_A_PWR12")
			(options
				(clearance outline)
				(anchor circle)
			)
			(primitives
				(gr_poly
					(pts
						(arc
							(start -0.1778 -0.2794)
							(mid -0.249642 -0.249642)
							(end -0.2794 -0.1778)
						)
						(arc
							(start -0.2794 0.1778)
							(mid -0.249642 0.249642)
							(end -0.1778 0.2794)
						)
						(arc
							(start 0.1778 0.2794)
							(mid 0.249642 0.249642)
							(end 0.2794 0.1778)
						)
						(arc
							(start 0.2794 -0.1778)
							(mid 0.249642 -0.249642)
							(end 0.1778 -0.2794)
						)
					)
					(width 0)
					(fill yes)
				)
			)
		)
	)
	(footprint ""
		(layer "F.Cu")
		(at 39.750746 -40.9067 90)
		(property "Reference" "R229"
			(at 0 0 90)
			(layer "F.SilkS")
			(hide yes)
			(effects
				(font
					(size 1.27 1.27)
				)
			)
		)
		(property "Value" "330R2F-GP"
			(at 0.064008 -3.993896 90)
			(unlocked yes)
			(layer "F.Fab")
			(hide yes)
			(effects
				(font
					(size 1.016 1.016)
					(thickness 0.1524)
				)
			)
		)
		(property "Device Type" "R402H16"
			(at 0.064008 -5.517896 90)
			(unlocked yes)
			(layer "F.Fab")
			(hide yes)
			(effects
				(font
					(size 1.016 1.016)
					(thickness 0.1524)
				)
			)
		)
		(duplicate_pad_numbers_are_jumpers no)
		(fp_line
			(start 0.508 -0.9398)
			(end -0.508 -0.9398)
			(stroke
				(width 0.1524)
				(type default)
			)
			(layer "F.SilkS")
		)
		(fp_line
			(start -0.508 -0.9398)
			(end -0.508 0.9398)
			(stroke
				(width 0.1524)
				(type default)
			)
			(layer "F.SilkS")
		)
		(fp_rect
			(start -0.508 0.9398)
			(end 0.508 -0.9398)
			(stroke
				(width 0)
				(type default)
			)
			(fill no)
			(layer "F.CrtYd")
		)
		(fp_rect
			(start -0.508 0.9398)
			(end 0.508 -0.9398)
			(stroke
				(width 0)
				(type default)
			)
			(fill no)
			(layer "F.Fab")
		)
		(pad "1" smd custom
			(at 0 -0.4445 90)
			(size 0.1397 0.1397)
			(layers "F.Cu" "F.Mask" "F.Paste")
			(net "P3V3_HDD9_LED")
			(options
				(clearance outline)
				(anchor circle)
			)
			(primitives
				(gr_poly
					(pts
						(arc
							(start -0.1778 -0.2794)
							(mid -0.249642 -0.249642)
							(end -0.2794 -0.1778)
						)
						(arc
							(start -0.2794 0.1778)
							(mid -0.249642 0.249642)
							(end -0.1778 0.2794)
						)
						(arc
							(start 0.1778 0.2794)
							(mid 0.249642 0.249642)
							(end 0.2794 0.1778)
						)
						(arc
							(start 0.2794 -0.1778)
							(mid 0.249642 -0.249642)
							(end 0.1778 -0.2794)
						)
					)
					(width 0)
					(fill yes)
				)
			)
		)
		(pad "2" smd custom
			(at 0 0.4445 90)
			(size 0.1397 0.1397)
			(layers "F.Cu" "F.Mask" "F.Paste")
			(net "FLT_HDD9")
			(options
				(clearance outline)
				(anchor circle)
			)
			(primitives
				(gr_poly
					(pts
						(arc
							(start -0.1778 -0.2794)
							(mid -0.249642 -0.249642)
							(end -0.2794 -0.1778)
						)
						(arc
							(start -0.2794 0.1778)
							(mid -0.249642 0.249642)
							(end -0.1778 0.2794)
						)
						(arc
							(start 0.1778 0.2794)
							(mid 0.249642 0.249642)
							(end 0.2794 0.1778)
						)
						(arc
							(start 0.2794 -0.1778)
							(mid 0.249642 -0.249642)
							(end 0.1778 -0.2794)
						)
					)
					(width 0)
					(fill yes)
				)
			)
		)
	)
	(footprint ""
		(layer "F.Cu")
		(at 190.627 -190.373)
		(property "Reference" "R149"
			(at 0 0 0)
			(layer "F.SilkS")
			(hide yes)
			(effects
				(font
					(size 1.27 1.27)
				)
			)
		)
		(property "Value" "200KR2F-L-GP"
			(at 0.064008 -3.993896 0)
			(unlocked yes)
			(layer "F.Fab")
			(hide yes)
			(effects
				(font
					(size 1.016 1.016)
					(thickness 0.1524)
				)
			)
		)
		(property "Device Type" "R402H16"
			(at 0.064008 -5.517896 0)
			(unlocked yes)
			(layer "F.Fab")
			(hide yes)
			(effects
				(font
					(size 1.016 1.016)
					(thickness 0.1524)
				)
			)
		)
		(duplicate_pad_numbers_are_jumpers no)
		(fp_line
			(start -0.508 -0.9398)
			(end -0.508 0.9398)
			(stroke
				(width 0.1524)
				(type default)
			)
			(layer "F.SilkS")
		)
		(fp_line
			(start 0.508 -0.9398)
			(end -0.508 -0.9398)
			(stroke
				(width 0.1524)
				(type default)
			)
			(layer "F.SilkS")
		)
		(fp_rect
			(start -0.508 0.9398)
			(end 0.508 -0.9398)
			(stroke
				(width 0)
				(type default)
			)
			(fill no)
			(layer "F.CrtYd")
		)
		(fp_rect
			(start -0.508 0.9398)
			(end 0.508 -0.9398)
			(stroke
				(width 0)
				(type default)
			)
			(fill no)
			(layer "F.Fab")
		)
		(pad "1" smd custom
			(at 0 -0.4445)
			(size 0.1397 0.1397)
			(layers "F.Cu" "F.Mask" "F.Paste")
			(net "P12V")
			(options
				(clearance outline)
				(anchor circle)
			)
			(primitives
				(gr_poly
					(pts
						(arc
							(start -0.1778 -0.2794)
							(mid -0.249642 -0.249642)
							(end -0.2794 -0.1778)
						)
						(arc
							(start -0.2794 0.1778)
							(mid -0.249642 0.249642)
							(end -0.1778 0.2794)
						)
						(arc
							(start 0.1778 0.2794)
							(mid 0.249642 0.249642)
							(end 0.2794 0.1778)
						)
						(arc
							(start 0.2794 -0.1778)
							(mid 0.249642 -0.249642)
							(end 0.1778 -0.2794)
						)
					)
					(width 0)
					(fill yes)
				)
			)
		)
		(pad "2" smd custom
			(at 0 0.4445)
			(size 0.1397 0.1397)
			(layers "F.Cu" "F.Mask" "F.Paste")
			(net "SW_HDD3_P")
			(options
				(clearance outline)
				(anchor circle)
			)
			(primitives
				(gr_poly
					(pts
						(arc
							(start -0.1778 -0.2794)
							(mid -0.249642 -0.249642)
							(end -0.2794 -0.1778)
						)
						(arc
							(start -0.2794 0.1778)
							(mid -0.249642 0.249642)
							(end -0.1778 0.2794)
						)
						(arc
							(start 0.1778 0.2794)
							(mid 0.249642 0.249642)
							(end 0.2794 0.1778)
						)
						(arc
							(start 0.2794 -0.1778)
							(mid 0.249642 -0.249642)
							(end 0.1778 -0.2794)
						)
					)
					(width 0)
					(fill yes)
				)
			)
		)
	)
	(footprint ""
		(layer "F.Cu")
		(at 213.741 -393.9032 180)
		(property "Reference" "C127"
			(at 0 0 180)
			(layer "F.SilkS")
			(hide yes)
			(effects
				(font
					(size 1.27 1.27)
				)
			)
		)
		(property "Value" "SC10U25V6KX-1GP"
			(at -0.0762 -5.1308 180)
			(unlocked yes)
			(layer "F.Fab")
			(hide yes)
			(effects
				(font
					(size 1.016 1.016)
					(thickness 0.1524)
				)
			)
		)
		(property "Device Type" "C1206H71"
			(at -0.127 -6.6548 180)
			(unlocked yes)
			(layer "F.Fab")
			(hide yes)
			(effects
				(font
					(size 1.016 1.016)
					(thickness 0.1524)
				)
			)
		)
		(duplicate_pad_numbers_are_jumpers no)
		(fp_line
			(start 1.016 2.2352)
			(end -1.016 2.2352)
			(stroke
				(width 0.1524)
				(type default)
			)
			(layer "F.SilkS")
		)
		(fp_line
			(start 1.016 0.8382)
			(end 1.016 2.2352)
			(stroke
				(width 0.1524)
				(type default)
			)
			(layer "F.SilkS")
		)
		(fp_line
			(start 1.016 -2.2352)
			(end 1.016 -0.8382)
			(stroke
				(width 0.1524)
				(type default)
			)
			(layer "F.SilkS")
		)
		(fp_line
			(start -1.016 2.2352)
			(end -1.016 0.8382)
			(stroke
				(width 0.1524)
				(type default)
			)
			(layer "F.SilkS")
		)
		(fp_line
			(start -1.016 -0.8382)
			(end -1.016 -2.2352)
			(stroke
				(width 0.1524)
				(type default)
			)
			(layer "F.SilkS")
		)
		(fp_line
			(start -1.016 -2.2352)
			(end 1.016 -2.2352)
			(stroke
				(width 0.1524)
				(type default)
			)
			(layer "F.SilkS")
		)
		(fp_rect
			(start -1.0922 2.3114)
			(end 1.0922 -2.3114)
			(stroke
				(width 0)
				(type default)
			)
			(fill no)
			(layer "F.CrtYd")
		)
		(fp_poly
			(pts
				(xy 1.0922 -2.3114) (xy 1.0922 2.3114) (xy -1.0922 2.3114) (xy -1.0922 -2.3114)
			)
			(stroke
				(width 0)
				(type default)
			)
			(fill no)
			(layer "F.Fab")
		)
		(pad "1" smd rect
			(at 0 -1.397 180)
			(size 1.651 1.27)
			(layers "F.Cu" "F.Mask" "F.Paste")
			(net "P12V_HDD1")
		)
		(pad "2" smd rect
			(at 0 1.397 180)
			(size 1.651 1.27)
			(layers "F.Cu" "F.Mask" "F.Paste")
			(net "GND")
		)
	)
	(footprint ""
		(layer "F.Cu")
		(at 78.867 -402.463)
		(property "Reference" "R569"
			(at 0 0 0)
			(layer "F.SilkS")
			(hide yes)
			(effects
				(font
					(size 1.27 1.27)
				)
			)
		)
		(property "Value" "300KR2F-GP"
			(at 0.064008 -3.993896 0)
			(unlocked yes)
			(layer "F.Fab")
			(hide yes)
			(effects
				(font
					(size 1.016 1.016)
					(thickness 0.1524)
				)
			)
		)
		(property "Device Type" "R402H16"
			(at 0.064008 -5.517896 0)
			(unlocked yes)
			(layer "F.Fab")
			(hide yes)
			(effects
				(font
					(size 1.016 1.016)
					(thickness 0.1524)
				)
			)
		)
		(duplicate_pad_numbers_are_jumpers no)
		(fp_line
			(start -0.508 -0.9398)
			(end -0.508 0.9398)
			(stroke
				(width 0.1524)
				(type default)
			)
			(layer "F.SilkS")
		)
		(fp_line
			(start 0.508 -0.9398)
			(end -0.508 -0.9398)
			(stroke
				(width 0.1524)
				(type default)
			)
			(layer "F.SilkS")
		)
		(fp_rect
			(start -0.508 0.9398)
			(end 0.508 -0.9398)
			(stroke
				(width 0)
				(type default)
			)
			(fill no)
			(layer "F.CrtYd")
		)
		(fp_rect
			(start -0.508 0.9398)
			(end 0.508 -0.9398)
			(stroke
				(width 0)
				(type default)
			)
			(fill no)
			(layer "F.Fab")
		)
		(pad "1" smd custom
			(at 0 -0.4445)
			(size 0.1397 0.1397)
			(layers "F.Cu" "F.Mask" "F.Paste")
			(net "SW_HDD6_N")
			(options
				(clearance outline)
				(anchor circle)
			)
			(primitives
				(gr_poly
					(pts
						(arc
							(start -0.1778 -0.2794)
							(mid -0.249642 -0.249642)
							(end -0.2794 -0.1778)
						)
						(arc
							(start -0.2794 0.1778)
							(mid -0.249642 0.249642)
							(end -0.1778 0.2794)
						)
						(arc
							(start 0.1778 0.2794)
							(mid 0.249642 0.249642)
							(end 0.2794 0.1778)
						)
						(arc
							(start 0.2794 -0.1778)
							(mid 0.249642 -0.249642)
							(end 0.1778 -0.2794)
						)
					)
					(width 0)
					(fill yes)
				)
			)
		)
		(pad "2" smd custom
			(at 0 0.4445)
			(size 0.1397 0.1397)
			(layers "F.Cu" "F.Mask" "F.Paste")
			(net "P12V")
			(options
				(clearance outline)
				(anchor circle)
			)
			(primitives
				(gr_poly
					(pts
						(arc
							(start -0.1778 -0.2794)
							(mid -0.249642 -0.249642)
							(end -0.2794 -0.1778)
						)
						(arc
							(start -0.2794 0.1778)
							(mid -0.249642 0.249642)
							(end -0.1778 0.2794)
						)
						(arc
							(start 0.1778 0.2794)
							(mid 0.249642 0.249642)
							(end 0.2794 0.1778)
						)
						(arc
							(start 0.2794 -0.1778)
							(mid 0.249642 -0.249642)
							(end 0.1778 -0.2794)
						)
					)
					(width 0)
					(fill yes)
				)
			)
		)
	)
	(footprint ""
		(layer "F.Cu")
		(at 51.562 -416.433)
		(property "Reference" "R573"
			(at 0 0 0)
			(layer "F.SilkS")
			(hide yes)
			(effects
				(font
					(size 1.27 1.27)
				)
			)
		)
		(property "Value" "300KR2F-GP"
			(at 0.064008 -3.993896 0)
			(unlocked yes)
			(layer "F.Fab")
			(hide yes)
			(effects
				(font
					(size 1.016 1.016)
					(thickness 0.1524)
				)
			)
		)
		(property "Device Type" "R402H16"
			(at 0.064008 -5.517896 0)
			(unlocked yes)
			(layer "F.Fab")
			(hide yes)
			(effects
				(font
					(size 1.016 1.016)
					(thickness 0.1524)
				)
			)
		)
		(duplicate_pad_numbers_are_jumpers no)
		(fp_line
			(start -0.508 -0.9398)
			(end -0.508 0.9398)
			(stroke
				(width 0.1524)
				(type default)
			)
			(layer "F.SilkS")
		)
		(fp_line
			(start 0.508 -0.9398)
			(end -0.508 -0.9398)
			(stroke
				(width 0.1524)
				(type default)
			)
			(layer "F.SilkS")
		)
		(fp_rect
			(start -0.508 0.9398)
			(end 0.508 -0.9398)
			(stroke
				(width 0)
				(type default)
			)
			(fill no)
			(layer "F.CrtYd")
		)
		(fp_rect
			(start -0.508 0.9398)
			(end 0.508 -0.9398)
			(stroke
				(width 0)
				(type default)
			)
			(fill no)
			(layer "F.Fab")
		)
		(pad "1" smd custom
			(at 0 -0.4445)
			(size 0.1397 0.1397)
			(layers "F.Cu" "F.Mask" "F.Paste")
			(net "SW_HDD10_N")
			(options
				(clearance outline)
				(anchor circle)
			)
			(primitives
				(gr_poly
					(pts
						(arc
							(start -0.1778 -0.2794)
							(mid -0.249642 -0.249642)
							(end -0.2794 -0.1778)
						)
						(arc
							(start -0.2794 0.1778)
							(mid -0.249642 0.249642)
							(end -0.1778 0.2794)
						)
						(arc
							(start 0.1778 0.2794)
							(mid 0.249642 0.249642)
							(end 0.2794 0.1778)
						)
						(arc
							(start 0.2794 -0.1778)
							(mid 0.249642 -0.249642)
							(end 0.1778 -0.2794)
						)
					)
					(width 0)
					(fill yes)
				)
			)
		)
		(pad "2" smd custom
			(at 0 0.4445)
			(size 0.1397 0.1397)
			(layers "F.Cu" "F.Mask" "F.Paste")
			(net "P12V")
			(options
				(clearance outline)
				(anchor circle)
			)
			(primitives
				(gr_poly
					(pts
						(arc
							(start -0.1778 -0.2794)
							(mid -0.249642 -0.249642)
							(end -0.2794 -0.1778)
						)
						(arc
							(start -0.2794 0.1778)
							(mid -0.249642 0.249642)
							(end -0.1778 0.2794)
						)
						(arc
							(start 0.1778 0.2794)
							(mid 0.249642 0.249642)
							(end 0.2794 0.1778)
						)
						(arc
							(start 0.2794 -0.1778)
							(mid 0.249642 -0.249642)
							(end 0.1778 -0.2794)
						)
					)
					(width 0)
					(fill yes)
				)
			)
		)
	)
	(footprint ""
		(layer "F.Cu")
		(at 199.850756 -498.402102 -90)
		(property "Reference" "U2"
			(at 0 0 270)
			(layer "F.SilkS")
			(hide yes)
			(effects
				(font
					(size 1.27 1.27)
				)
			)
		)
		(property "Value" "P2003EVG-GP"
			(at 0 -11.1252 270)
			(unlocked yes)
			(layer "F.Fab")
			(hide yes)
			(effects
				(font
					(size 1.016 1.016)
					(thickness 0.1524)
				)
			)
		)
		(property "Device Type" "SOIC8H79"
			(at 0 -12.6492 270)
			(unlocked yes)
			(layer "F.Fab")
			(hide yes)
			(effects
				(font
					(size 1.016 1.016)
					(thickness 0.1524)
				)
			)
		)
		(duplicate_pad_numbers_are_jumpers no)
		(fp_line
			(start -2.6162 3.429)
			(end -2.6162 1.4732)
			(stroke
				(width 0.4064)
				(type default)
			)
			(layer "F.SilkS")
		)
		(fp_line
			(start -2.7432 1.4224)
			(end 2.1336 1.4224)
			(stroke
				(width 0.1524)
				(type default)
			)
			(layer "F.SilkS")
		)
		(fp_line
			(start 2.1336 1.4224)
			(end 2.1336 -1.4224)
			(stroke
				(width 0.1524)
				(type default)
			)
			(layer "F.SilkS")
		)
		(fp_line
			(start -2.2352 0)
			(end -2.7432 0.508)
			(stroke
				(width 0.1524)
				(type default)
			)
			(layer "F.SilkS")
		)
		(fp_line
			(start -2.7432 -0.508)
			(end -2.2352 0)
			(stroke
				(width 0.1524)
				(type default)
			)
			(layer "F.SilkS")
		)
		(fp_line
			(start -2.7432 -1.4224)
			(end -2.7432 1.4224)
			(stroke
				(width 0.1524)
				(type default)
			)
			(layer "F.SilkS")
		)
		(fp_line
			(start 2.1336 -1.4224)
			(end -2.7432 -1.4224)
			(stroke
				(width 0.1524)
				(type default)
			)
			(layer "F.SilkS")
		)
		(fp_poly
			(pts
				(xy 2.2098 -1.4224) (xy 2.2098 1.4224) (xy -2.2225 1.4224) (xy -2.2225 -1.4224)
			)
			(stroke
				(width 0)
				(type default)
			)
			(fill yes)
			(layer "F.SilkS")
		)
		(fp_rect
			(start -2.4511 2.9972)
			(end 2.4511 -2.9972)
			(stroke
				(width 0)
				(type default)
			)
			(fill no)
			(layer "F.CrtYd")
		)
		(fp_poly
			(pts
				(xy -2.8194 3.6322) (xy -2.8194 -3.6322) (xy 2.8194 -3.6322) (xy 2.8194 -2.2987) (xy 2.4511 -2.2987)
				(xy 2.4511 -2.9972) (xy -2.4511 -2.9972) (xy -2.4511 2.9972) (xy 2.4511 2.9972) (xy 2.4511 -2.286)
				(xy 2.8194 -2.286) (xy 2.8194 3.6322)
			)
			(stroke
				(width 0)
				(type default)
			)
			(fill no)
			(layer "F.CrtYd")
		)
		(fp_rect
			(start -2.8194 3.6322)
			(end 2.8194 -3.6322)
			(stroke
				(width 0)
				(type default)
			)
			(fill no)
			(layer "F.Fab")
		)
		(pad "1" smd rect
			(at -1.905 2.54 270)
			(size 0.635 1.651)
			(layers "F.Cu" "F.Mask" "F.Paste")
			(net "P12V")
		)
		(pad "2" smd rect
			(at -0.635 2.54 270)
			(size 0.635 1.651)
			(layers "F.Cu" "F.Mask" "F.Paste")
			(net "P12V")
		)
		(pad "3" smd rect
			(at 0.635 2.54 270)
			(size 0.635 1.651)
			(layers "F.Cu" "F.Mask" "F.Paste")
			(net "P12V")
		)
		(pad "4" smd rect
			(at 1.905 2.54 270)
			(size 0.635 1.651)
			(layers "F.Cu" "F.Mask" "F.Paste")
			(net "SW_HDD0_N")
		)
		(pad "5" smd rect
			(at 1.905 -2.54 270)
			(size 0.635 1.651)
			(layers "F.Cu" "F.Mask" "F.Paste")
			(net "P12V_HDD0")
		)
		(pad "6" smd rect
			(at 0.635 -2.54 270)
			(size 0.635 1.651)
			(layers "F.Cu" "F.Mask" "F.Paste")
			(net "P12V_HDD0")
		)
		(pad "7" smd rect
			(at -0.635 -2.54 270)
			(size 0.635 1.651)
			(layers "F.Cu" "F.Mask" "F.Paste")
			(net "P12V_HDD0")
		)
		(pad "8" smd rect
			(at -1.905 -2.54 270)
			(size 0.635 1.651)
			(layers "F.Cu" "F.Mask" "F.Paste")
			(net "P12V_HDD0")
		)
	)
	(footprint ""
		(layer "F.Cu")
		(at 33.043368 -468.948516 -90)
		(property "Reference" "C182"
			(at 0 0 270)
			(layer "F.SilkS")
			(hide yes)
			(effects
				(font
					(size 1.27 1.27)
				)
			)
		)
		(property "Value" "SCD01U50V2KX-1GP"
			(at 1.1811 -2.7051 270)
			(unlocked yes)
			(layer "F.Fab")
			(hide yes)
			(effects
				(font
					(size 1.016 1.016)
					(thickness 0.1524)
				)
			)
		)
		(property "Device Type" "C402H22"
			(at 1.1811 -4.2291 270)
			(unlocked yes)
			(layer "F.Fab")
			(hide yes)
			(effects
				(font
					(size 1.016 1.016)
					(thickness 0.1524)
				)
			)
		)
		(duplicate_pad_numbers_are_jumpers no)
		(fp_rect
			(start -0.4318 0.9525)
			(end 0.4318 -0.9525)
			(stroke
				(width 0)
				(type default)
			)
			(fill no)
			(layer "F.CrtYd")
		)
		(fp_rect
			(start -0.4318 0.9525)
			(end 0.4318 -0.9525)
			(stroke
				(width 0)
				(type default)
			)
			(fill no)
			(layer "F.Fab")
		)
		(pad "1" smd custom
			(at 0 -0.4445 270)
			(size 0.1524 0.1524)
			(layers "F.Cu" "F.Mask" "F.Paste")
			(net "SAS2X28_DRIVE_RX_N_A5")
			(options
				(clearance outline)
				(anchor circle)
			)
			(primitives
				(gr_poly
					(pts
						(arc
							(start 0.3048 -0.2032)
							(mid 0.275042 -0.275042)
							(end 0.2032 -0.3048)
						)
						(arc
							(start -0.2032 -0.3048)
							(mid -0.275042 -0.275042)
							(end -0.3048 -0.2032)
						)
						(arc
							(start -0.3048 0.2032)
							(mid -0.275042 0.275042)
							(end -0.2032 0.3048)
						)
						(arc
							(start 0.2032 0.3048)
							(mid 0.275042 0.275042)
							(end 0.3048 0.2032)
						)
					)
					(width 0)
					(fill yes)
				)
			)
		)
		(pad "2" smd custom
			(at 0 0.4445 270)
			(size 0.1524 0.1524)
			(layers "F.Cu" "F.Mask" "F.Paste")
			(net "SAS2X28_A_HDD5_RX_-")
			(options
				(clearance outline)
				(anchor circle)
			)
			(primitives
				(gr_poly
					(pts
						(arc
							(start 0.3048 -0.2032)
							(mid 0.275042 -0.275042)
							(end 0.2032 -0.3048)
						)
						(arc
							(start -0.2032 -0.3048)
							(mid -0.275042 -0.275042)
							(end -0.3048 -0.2032)
						)
						(arc
							(start -0.3048 0.2032)
							(mid -0.275042 0.275042)
							(end -0.2032 0.3048)
						)
						(arc
							(start 0.2032 0.3048)
							(mid 0.275042 0.275042)
							(end 0.3048 0.2032)
						)
					)
					(width 0)
					(fill yes)
				)
			)
		)
	)
	(footprint ""
		(layer "F.Cu")
		(at 40.055546 -133.3119 -90)
		(property "Reference" "R323"
			(at 0 0 270)
			(layer "F.SilkS")
			(hide yes)
			(effects
				(font
					(size 1.27 1.27)
				)
			)
		)
		(property "Value" "4K7R2J-2-GP"
			(at 0.064008 -3.993896 270)
			(unlocked yes)
			(layer "F.Fab")
			(hide yes)
			(effects
				(font
					(size 1.016 1.016)
					(thickness 0.1524)
				)
			)
		)
		(property "Device Type" "R402H16"
			(at 0.064008 -5.517896 270)
			(unlocked yes)
			(layer "F.Fab")
			(hide yes)
			(effects
				(font
					(size 1.016 1.016)
					(thickness 0.1524)
				)
			)
		)
		(duplicate_pad_numbers_are_jumpers no)
		(fp_line
			(start -0.508 -0.9398)
			(end -0.508 0.9398)
			(stroke
				(width 0.1524)
				(type default)
			)
			(layer "F.SilkS")
		)
		(fp_line
			(start 0.508 -0.9398)
			(end -0.508 -0.9398)
			(stroke
				(width 0.1524)
				(type default)
			)
			(layer "F.SilkS")
		)
		(fp_rect
			(start -0.508 0.9398)
			(end 0.508 -0.9398)
			(stroke
				(width 0)
				(type default)
			)
			(fill no)
			(layer "F.CrtYd")
		)
		(fp_rect
			(start -0.508 0.9398)
			(end 0.508 -0.9398)
			(stroke
				(width 0)
				(type default)
			)
			(fill no)
			(layer "F.Fab")
		)
		(pad "1" smd custom
			(at 0 -0.4445 270)
			(size 0.1397 0.1397)
			(layers "F.Cu" "F.Mask" "F.Paste")
			(net "I2C_B_TMP2_A2")
			(options
				(clearance outline)
				(anchor circle)
			)
			(primitives
				(gr_poly
					(pts
						(arc
							(start -0.1778 -0.2794)
							(mid -0.249642 -0.249642)
							(end -0.2794 -0.1778)
						)
						(arc
							(start -0.2794 0.1778)
							(mid -0.249642 0.249642)
							(end -0.1778 0.2794)
						)
						(arc
							(start 0.1778 0.2794)
							(mid 0.249642 0.249642)
							(end 0.2794 0.1778)
						)
						(arc
							(start 0.2794 -0.1778)
							(mid 0.249642 -0.249642)
							(end 0.1778 -0.2794)
						)
					)
					(width 0)
					(fill yes)
				)
			)
		)
		(pad "2" smd custom
			(at 0 0.4445 270)
			(size 0.1397 0.1397)
			(layers "F.Cu" "F.Mask" "F.Paste")
			(net "GND")
			(options
				(clearance outline)
				(anchor circle)
			)
			(primitives
				(gr_poly
					(pts
						(arc
							(start -0.1778 -0.2794)
							(mid -0.249642 -0.249642)
							(end -0.2794 -0.1778)
						)
						(arc
							(start -0.2794 0.1778)
							(mid -0.249642 0.249642)
							(end -0.1778 0.2794)
						)
						(arc
							(start 0.1778 0.2794)
							(mid 0.249642 0.249642)
							(end 0.2794 0.1778)
						)
						(arc
							(start 0.2794 -0.1778)
							(mid 0.249642 -0.249642)
							(end 0.1778 -0.2794)
						)
					)
					(width 0)
					(fill yes)
				)
			)
		)
	)
	(footprint ""
		(layer "F.Cu")
		(at 27.304746 -437.035702 90)
		(property "Reference" "R461"
			(at 0 0 90)
			(layer "F.SilkS")
			(hide yes)
			(effects
				(font
					(size 1.27 1.27)
				)
			)
		)
		(property "Value" "4K7R2J-2-GP"
			(at 0.064008 -3.993896 90)
			(unlocked yes)
			(layer "F.Fab")
			(hide yes)
			(effects
				(font
					(size 1.016 1.016)
					(thickness 0.1524)
				)
			)
		)
		(property "Device Type" "R402H16"
			(at 0.064008 -5.517896 90)
			(unlocked yes)
			(layer "F.Fab")
			(hide yes)
			(effects
				(font
					(size 1.016 1.016)
					(thickness 0.1524)
				)
			)
		)
		(duplicate_pad_numbers_are_jumpers no)
		(fp_line
			(start 0.508 -0.9398)
			(end -0.508 -0.9398)
			(stroke
				(width 0.1524)
				(type default)
			)
			(layer "F.SilkS")
		)
		(fp_line
			(start -0.508 -0.9398)
			(end -0.508 0.9398)
			(stroke
				(width 0.1524)
				(type default)
			)
			(layer "F.SilkS")
		)
		(fp_rect
			(start -0.508 0.9398)
			(end 0.508 -0.9398)
			(stroke
				(width 0)
				(type default)
			)
			(fill no)
			(layer "F.CrtYd")
		)
		(fp_rect
			(start -0.508 0.9398)
			(end 0.508 -0.9398)
			(stroke
				(width 0)
				(type default)
			)
			(fill no)
			(layer "F.Fab")
		)
		(pad "1" smd custom
			(at 0 -0.4445 90)
			(size 0.1397 0.1397)
			(layers "F.Cu" "F.Mask" "F.Paste")
			(net "P3V3")
			(options
				(clearance outline)
				(anchor circle)
			)
			(primitives
				(gr_poly
					(pts
						(arc
							(start -0.1778 -0.2794)
							(mid -0.249642 -0.249642)
							(end -0.2794 -0.1778)
						)
						(arc
							(start -0.2794 0.1778)
							(mid -0.249642 0.249642)
							(end -0.1778 0.2794)
						)
						(arc
							(start 0.1778 0.2794)
							(mid 0.249642 0.249642)
							(end 0.2794 0.1778)
						)
						(arc
							(start 0.2794 -0.1778)
							(mid 0.249642 -0.249642)
							(end 0.1778 -0.2794)
						)
					)
					(width 0)
					(fill yes)
				)
			)
		)
		(pad "2" smd custom
			(at 0 0.4445 90)
			(size 0.1397 0.1397)
			(layers "F.Cu" "F.Mask" "F.Paste")
			(net "SAS2X28_B_HDD10_FLT")
			(options
				(clearance outline)
				(anchor circle)
			)
			(primitives
				(gr_poly
					(pts
						(arc
							(start -0.1778 -0.2794)
							(mid -0.249642 -0.249642)
							(end -0.2794 -0.1778)
						)
						(arc
							(start -0.2794 0.1778)
							(mid -0.249642 0.249642)
							(end -0.1778 0.2794)
						)
						(arc
							(start 0.1778 0.2794)
							(mid 0.249642 0.249642)
							(end 0.2794 0.1778)
						)
						(arc
							(start 0.2794 -0.1778)
							(mid 0.249642 -0.249642)
							(end 0.1778 -0.2794)
						)
					)
					(width 0)
					(fill yes)
				)
			)
		)
	)
	(footprint ""
		(layer "F.Cu")
		(at 214.778082 -278.559768 -90)
		(property "Reference" "R134"
			(at 0 0 270)
			(layer "F.SilkS")
			(hide yes)
			(effects
				(font
					(size 1.27 1.27)
				)
			)
		)
		(property "Value" "2R2010J-1-GP"
			(at 0.254 -8.0772 270)
			(unlocked yes)
			(layer "F.Fab")
			(hide yes)
			(effects
				(font
					(size 1.016 1.016)
					(thickness 0.1524)
				)
			)
		)
		(property "Device Type" "R2010H28"
			(at 0.254 -9.6774 270)
			(unlocked yes)
			(layer "F.Fab")
			(hide yes)
			(effects
				(font
					(size 1.016 1.016)
					(thickness 0.1524)
				)
			)
		)
		(duplicate_pad_numbers_are_jumpers no)
		(fp_line
			(start -1.651 3.302)
			(end 1.651 3.302)
			(stroke
				(width 0.1524)
				(type default)
			)
			(layer "F.SilkS")
		)
		(fp_line
			(start 1.651 3.302)
			(end 1.651 -3.302)
			(stroke
				(width 0.1524)
				(type default)
			)
			(layer "F.SilkS")
		)
		(fp_line
			(start -1.651 -3.302)
			(end -1.651 3.302)
			(stroke
				(width 0.1524)
				(type default)
			)
			(layer "F.SilkS")
		)
		(fp_line
			(start 1.651 -3.302)
			(end -1.651 -3.302)
			(stroke
				(width 0.1524)
				(type default)
			)
			(layer "F.SilkS")
		)
		(fp_rect
			(start -1.7272 -3.3782)
			(end 1.7272 3.3782)
			(stroke
				(width 0)
				(type default)
			)
			(fill no)
			(layer "F.CrtYd")
		)
		(fp_poly
			(pts
				(xy 1.7272 3.3782) (xy 1.7272 -3.3782) (xy -1.7272 -3.3782) (xy -1.7272 3.3782)
			)
			(stroke
				(width 0)
				(type default)
			)
			(fill no)
			(layer "F.Fab")
		)
		(pad "1" smd rect
			(at 0 -2.3495 270)
			(size 2.794 1.143)
			(layers "F.Cu" "F.Mask" "F.Paste")
			(net "5V_PRE_2")
		)
		(pad "2" smd rect
			(at 0 2.3495 270)
			(size 2.794 1.143)
			(layers "F.Cu" "F.Mask" "F.Paste")
			(net "P5V_HDD2")
		)
	)
	(footprint ""
		(layer "F.Cu")
		(at 46.735746 -111.1377 -90)
		(property "Reference" "U41"
			(at 0 0 270)
			(layer "F.SilkS")
			(hide yes)
			(effects
				(font
					(size 1.27 1.27)
				)
			)
		)
		(property "Value" "P2003EVG-GP"
			(at 0 -11.1252 270)
			(unlocked yes)
			(layer "F.Fab")
			(hide yes)
			(effects
				(font
					(size 1.016 1.016)
					(thickness 0.1524)
				)
			)
		)
		(property "Device Type" "SOIC8H79"
			(at 0 -12.6492 270)
			(unlocked yes)
			(layer "F.Fab")
			(hide yes)
			(effects
				(font
					(size 1.016 1.016)
					(thickness 0.1524)
				)
			)
		)
		(duplicate_pad_numbers_are_jumpers no)
		(fp_line
			(start -2.6162 3.429)
			(end -2.6162 1.4732)
			(stroke
				(width 0.4064)
				(type default)
			)
			(layer "F.SilkS")
		)
		(fp_line
			(start -2.7432 1.4224)
			(end 2.1336 1.4224)
			(stroke
				(width 0.1524)
				(type default)
			)
			(layer "F.SilkS")
		)
		(fp_line
			(start 2.1336 1.4224)
			(end 2.1336 -1.4224)
			(stroke
				(width 0.1524)
				(type default)
			)
			(layer "F.SilkS")
		)
		(fp_line
			(start -2.2352 0)
			(end -2.7432 0.508)
			(stroke
				(width 0.1524)
				(type default)
			)
			(layer "F.SilkS")
		)
		(fp_line
			(start -2.7432 -0.508)
			(end -2.2352 0)
			(stroke
				(width 0.1524)
				(type default)
			)
			(layer "F.SilkS")
		)
		(fp_line
			(start -2.7432 -1.4224)
			(end -2.7432 1.4224)
			(stroke
				(width 0.1524)
				(type default)
			)
			(layer "F.SilkS")
		)
		(fp_line
			(start 2.1336 -1.4224)
			(end -2.7432 -1.4224)
			(stroke
				(width 0.1524)
				(type default)
			)
			(layer "F.SilkS")
		)
		(fp_poly
			(pts
				(xy 2.2098 -1.4224) (xy 2.2098 1.4224) (xy -2.2225 1.4224) (xy -2.2225 -1.4224)
			)
			(stroke
				(width 0)
				(type default)
			)
			(fill yes)
			(layer "F.SilkS")
		)
		(fp_rect
			(start -2.4511 2.9972)
			(end 2.4511 -2.9972)
			(stroke
				(width 0)
				(type default)
			)
			(fill no)
			(layer "F.CrtYd")
		)
		(fp_poly
			(pts
				(xy -2.8194 3.6322) (xy -2.8194 -3.6322) (xy 2.8194 -3.6322) (xy 2.8194 -2.2987) (xy 2.4511 -2.2987)
				(xy 2.4511 -2.9972) (xy -2.4511 -2.9972) (xy -2.4511 2.9972) (xy 2.4511 2.9972) (xy 2.4511 -2.286)
				(xy 2.8194 -2.286) (xy 2.8194 3.6322)
			)
			(stroke
				(width 0)
				(type default)
			)
			(fill no)
			(layer "F.CrtYd")
		)
		(fp_rect
			(start -2.8194 3.6322)
			(end 2.8194 -3.6322)
			(stroke
				(width 0)
				(type default)
			)
			(fill no)
			(layer "F.Fab")
		)
		(pad "1" smd rect
			(at -1.905 2.54 270)
			(size 0.635 1.651)
			(layers "F.Cu" "F.Mask" "F.Paste")
			(net "P12V")
		)
		(pad "2" smd rect
			(at -0.635 2.54 270)
			(size 0.635 1.651)
			(layers "F.Cu" "F.Mask" "F.Paste")
			(net "P12V")
		)
		(pad "3" smd rect
			(at 0.635 2.54 270)
			(size 0.635 1.651)
			(layers "F.Cu" "F.Mask" "F.Paste")
			(net "P12V")
		)
		(pad "4" smd rect
			(at 1.905 2.54 270)
			(size 0.635 1.651)
			(layers "F.Cu" "F.Mask" "F.Paste")
			(net "SW_HDD13_N")
		)
		(pad "5" smd rect
			(at 1.905 -2.54 270)
			(size 0.635 1.651)
			(layers "F.Cu" "F.Mask" "F.Paste")
			(net "P12V_HDD13")
		)
		(pad "6" smd rect
			(at 0.635 -2.54 270)
			(size 0.635 1.651)
			(layers "F.Cu" "F.Mask" "F.Paste")
			(net "P12V_HDD13")
		)
		(pad "7" smd rect
			(at -0.635 -2.54 270)
			(size 0.635 1.651)
			(layers "F.Cu" "F.Mask" "F.Paste")
			(net "P12V_HDD13")
		)
		(pad "8" smd rect
			(at -1.905 -2.54 270)
			(size 0.635 1.651)
			(layers "F.Cu" "F.Mask" "F.Paste")
			(net "P12V_HDD13")
		)
	)
	(footprint ""
		(layer "F.Cu")
		(at 32.9184 -337.947)
		(property "Reference" "Q69"
			(at 0 0 0)
			(layer "F.SilkS")
			(hide yes)
			(effects
				(font
					(size 1.27 1.27)
				)
			)
		)
		(property "Value" "2N7002-11-GP"
			(at 0.127 -8.9662 0)
			(unlocked yes)
			(layer "F.Fab")
			(hide yes)
			(effects
				(font
					(size 1.016 1.016)
					(thickness 0.1524)
				)
			)
		)
		(property "Device Type" "SOT23DGS2D4H44"
			(at 0.127 -10.4902 0)
			(unlocked yes)
			(layer "F.Fab")
			(hide yes)
			(effects
				(font
					(size 1.016 1.016)
					(thickness 0.1524)
				)
			)
		)
		(duplicate_pad_numbers_are_jumpers no)
		(fp_line
			(start -1.651 -1.778)
			(end -1.651 1.778)
			(stroke
				(width 0.1524)
				(type default)
			)
			(layer "F.SilkS")
		)
		(fp_line
			(start -1.651 1.778)
			(end 1.651 1.778)
			(stroke
				(width 0.1524)
				(type default)
			)
			(layer "F.SilkS")
		)
		(fp_line
			(start 1.651 -1.778)
			(end -1.651 -1.778)
			(stroke
				(width 0.1524)
				(type default)
			)
			(layer "F.SilkS")
		)
		(fp_line
			(start 1.651 1.778)
			(end 1.651 -1.778)
			(stroke
				(width 0.1524)
				(type default)
			)
			(layer "F.SilkS")
		)
		(fp_poly
			(pts
				(xy -1.778 1.8796) (xy -1.778 -1.8796) (xy 1.778 -1.8796) (xy 1.778 1.8796)
			)
			(stroke
				(width 0)
				(type default)
			)
			(fill no)
			(layer "F.CrtYd")
		)
		(fp_poly
			(pts
				(xy -1.778 1.8796) (xy -1.778 -1.8796) (xy 1.778 -1.8796) (xy 1.778 1.8796)
			)
			(stroke
				(width 0)
				(type default)
			)
			(fill no)
			(layer "F.Fab")
		)
		(pad "D" smd custom
			(at 0 -0.9525)
			(size 0.1905 0.1905)
			(layers "F.Cu" "F.Mask" "F.Paste")
			(net "HDD11_LED_G")
			(options
				(clearance outline)
				(anchor circle)
			)
			(primitives
				(gr_poly
					(pts
						(arc
							(start -0.1778 0.5715)
							(mid -0.321484 0.511984)
							(end -0.381 0.3683)
						)
						(arc
							(start -0.381 -0.3683)
							(mid -0.321484 -0.511984)
							(end -0.1778 -0.5715)
						)
						(arc
							(start 0.1778 -0.5715)
							(mid 0.321484 -0.511984)
							(end 0.381 -0.3683)
						)
						(arc
							(start 0.381 0.3683)
							(mid 0.321484 0.511984)
							(end 0.1778 0.5715)
						)
					)
					(width 0)
					(fill yes)
				)
			)
		)
		(pad "G" smd custom
			(at -0.98425 0.9525)
			(size 0.1905 0.1905)
			(layers "F.Cu" "F.Mask" "F.Paste")
			(net "HDD11_LED_B")
			(options
				(clearance outline)
				(anchor circle)
			)
			(primitives
				(gr_poly
					(pts
						(arc
							(start -0.1778 0.5715)
							(mid -0.321484 0.511984)
							(end -0.381 0.3683)
						)
						(arc
							(start -0.381 -0.3683)
							(mid -0.321484 -0.511984)
							(end -0.1778 -0.5715)
						)
						(arc
							(start 0.1778 -0.5715)
							(mid 0.321484 -0.511984)
							(end 0.381 -0.3683)
						)
						(arc
							(start 0.381 0.3683)
							(mid 0.321484 0.511984)
							(end 0.1778 0.5715)
						)
					)
					(width 0)
					(fill yes)
				)
			)
		)
		(pad "S" smd custom
			(at 0.98425 0.9525)
			(size 0.1905 0.1905)
			(layers "F.Cu" "F.Mask" "F.Paste")
			(net "GND")
			(options
				(clearance outline)
				(anchor circle)
			)
			(primitives
				(gr_poly
					(pts
						(arc
							(start -0.1778 0.5715)
							(mid -0.321484 0.511984)
							(end -0.381 0.3683)
						)
						(arc
							(start -0.381 -0.3683)
							(mid -0.321484 -0.511984)
							(end -0.1778 -0.5715)
						)
						(arc
							(start 0.1778 -0.5715)
							(mid 0.321484 -0.511984)
							(end 0.381 -0.3683)
						)
						(arc
							(start 0.381 0.3683)
							(mid 0.321484 0.511984)
							(end 0.1778 0.5715)
						)
					)
					(width 0)
					(fill yes)
				)
			)
		)
	)
	(footprint ""
		(layer "F.Cu")
		(at 242.061746 -25.7937 90)
		(property "Reference" "PC6"
			(at 0 0 90)
			(layer "F.SilkS")
			(hide yes)
			(effects
				(font
					(size 1.27 1.27)
				)
			)
		)
		(property "Value" "SC4D7U25V5KX-GP"
			(at -0.0762 -6.1214 90)
			(unlocked yes)
			(layer "F.Fab")
			(hide yes)
			(effects
				(font
					(size 1.016 1.016)
					(thickness 0.1524)
				)
			)
		)
		(property "Device Type" "C805H54"
			(at -0.0762 -8.1534 90)
			(unlocked yes)
			(layer "F.Fab")
			(hide yes)
			(effects
				(font
					(size 1.016 1.016)
					(thickness 0.1524)
				)
			)
		)
		(duplicate_pad_numbers_are_jumpers no)
		(fp_line
			(start 0.635 0)
			(end -0.635 0)
			(stroke
				(width 0.508)
				(type default)
			)
			(layer "F.SilkS")
		)
		(fp_rect
			(start -0.9652 1.778)
			(end 0.9652 -1.778)
			(stroke
				(width 0)
				(type default)
			)
			(fill no)
			(layer "F.CrtYd")
		)
		(fp_poly
			(pts
				(xy -0.9652 -1.778) (xy 0.9652 -1.778) (xy 0.9652 1.778) (xy -0.9652 1.778)
			)
			(stroke
				(width 0)
				(type default)
			)
			(fill no)
			(layer "F.Fab")
		)
		(pad "1" smd rect
			(at 0 -0.9652 90)
			(size 1.397 1.143)
			(layers "F.Cu" "F.Mask" "F.Paste")
			(net "P5VA_VDD")
		)
		(pad "2" smd rect
			(at 0 0.9652 90)
			(size 1.397 1.143)
			(layers "F.Cu" "F.Mask" "F.Paste")
			(net "GND")
		)
	)
	(footprint ""
		(layer "F.Cu")
		(at 59.007756 -481.485702)
		(property "Reference" "C190"
			(at 0 0 0)
			(layer "F.SilkS")
			(hide yes)
			(effects
				(font
					(size 1.27 1.27)
				)
			)
		)
		(property "Value" "SCD01U50V2KX-1GP"
			(at 1.1811 -2.7051 0)
			(unlocked yes)
			(layer "F.Fab")
			(hide yes)
			(effects
				(font
					(size 1.016 1.016)
					(thickness 0.1524)
				)
			)
		)
		(property "Device Type" "C402H22"
			(at 1.1811 -4.2291 0)
			(unlocked yes)
			(layer "F.Fab")
			(hide yes)
			(effects
				(font
					(size 1.016 1.016)
					(thickness 0.1524)
				)
			)
		)
		(duplicate_pad_numbers_are_jumpers no)
		(fp_rect
			(start -0.4318 0.9525)
			(end 0.4318 -0.9525)
			(stroke
				(width 0)
				(type default)
			)
			(fill no)
			(layer "F.CrtYd")
		)
		(fp_rect
			(start -0.4318 0.9525)
			(end 0.4318 -0.9525)
			(stroke
				(width 0)
				(type default)
			)
			(fill no)
			(layer "F.Fab")
		)
		(pad "1" smd custom
			(at 0 -0.4445)
			(size 0.1524 0.1524)
			(layers "F.Cu" "F.Mask" "F.Paste")
			(net "HDD_PRSNT_NET5")
			(options
				(clearance outline)
				(anchor circle)
			)
			(primitives
				(gr_poly
					(pts
						(arc
							(start 0.3048 -0.2032)
							(mid 0.275042 -0.275042)
							(end 0.2032 -0.3048)
						)
						(arc
							(start -0.2032 -0.3048)
							(mid -0.275042 -0.275042)
							(end -0.3048 -0.2032)
						)
						(arc
							(start -0.3048 0.2032)
							(mid -0.275042 0.275042)
							(end -0.2032 0.3048)
						)
						(arc
							(start 0.2032 0.3048)
							(mid 0.275042 0.275042)
							(end 0.3048 0.2032)
						)
					)
					(width 0)
					(fill yes)
				)
			)
		)
		(pad "2" smd custom
			(at 0 0.4445)
			(size 0.1524 0.1524)
			(layers "F.Cu" "F.Mask" "F.Paste")
			(net "GND")
			(options
				(clearance outline)
				(anchor circle)
			)
			(primitives
				(gr_poly
					(pts
						(arc
							(start 0.3048 -0.2032)
							(mid 0.275042 -0.275042)
							(end 0.2032 -0.3048)
						)
						(arc
							(start -0.2032 -0.3048)
							(mid -0.275042 -0.275042)
							(end -0.3048 -0.2032)
						)
						(arc
							(start -0.3048 0.2032)
							(mid -0.275042 0.275042)
							(end -0.2032 0.3048)
						)
						(arc
							(start 0.2032 0.3048)
							(mid 0.275042 0.275042)
							(end 0.3048 0.2032)
						)
					)
					(width 0)
					(fill yes)
				)
			)
		)
	)
	(footprint ""
		(layer "F.Cu")
		(at 30.860746 -344.4367 90)
		(property "Reference" "R254"
			(at 0 0 90)
			(layer "F.SilkS")
			(hide yes)
			(effects
				(font
					(size 1.27 1.27)
				)
			)
		)
		(property "Value" "10KR2F-2-GP"
			(at 0.064008 -3.993896 90)
			(unlocked yes)
			(layer "F.Fab")
			(hide yes)
			(effects
				(font
					(size 1.016 1.016)
					(thickness 0.1524)
				)
			)
		)
		(property "Device Type" "R402H16"
			(at 0.064008 -5.517896 90)
			(unlocked yes)
			(layer "F.Fab")
			(hide yes)
			(effects
				(font
					(size 1.016 1.016)
					(thickness 0.1524)
				)
			)
		)
		(duplicate_pad_numbers_are_jumpers no)
		(fp_line
			(start 0.508 -0.9398)
			(end -0.508 -0.9398)
			(stroke
				(width 0.1524)
				(type default)
			)
			(layer "F.SilkS")
		)
		(fp_line
			(start -0.508 -0.9398)
			(end -0.508 0.9398)
			(stroke
				(width 0.1524)
				(type default)
			)
			(layer "F.SilkS")
		)
		(fp_rect
			(start -0.508 0.9398)
			(end 0.508 -0.9398)
			(stroke
				(width 0)
				(type default)
			)
			(fill no)
			(layer "F.CrtYd")
		)
		(fp_rect
			(start -0.508 0.9398)
			(end 0.508 -0.9398)
			(stroke
				(width 0)
				(type default)
			)
			(fill no)
			(layer "F.Fab")
		)
		(pad "1" smd custom
			(at 0 -0.4445 90)
			(size 0.1397 0.1397)
			(layers "F.Cu" "F.Mask" "F.Paste")
			(net "P5VC")
			(options
				(clearance outline)
				(anchor circle)
			)
			(primitives
				(gr_poly
					(pts
						(arc
							(start -0.1778 -0.2794)
							(mid -0.249642 -0.249642)
							(end -0.2794 -0.1778)
						)
						(arc
							(start -0.2794 0.1778)
							(mid -0.249642 0.249642)
							(end -0.1778 0.2794)
						)
						(arc
							(start 0.1778 0.2794)
							(mid 0.249642 0.249642)
							(end 0.2794 0.1778)
						)
						(arc
							(start 0.2794 -0.1778)
							(mid 0.249642 -0.249642)
							(end 0.1778 -0.2794)
						)
					)
					(width 0)
					(fill yes)
				)
			)
		)
		(pad "2" smd custom
			(at 0 0.4445 90)
			(size 0.1397 0.1397)
			(layers "F.Cu" "F.Mask" "F.Paste")
			(net "DRIVE_ACT_11")
			(options
				(clearance outline)
				(anchor circle)
			)
			(primitives
				(gr_poly
					(pts
						(arc
							(start -0.1778 -0.2794)
							(mid -0.249642 -0.249642)
							(end -0.2794 -0.1778)
						)
						(arc
							(start -0.2794 0.1778)
							(mid -0.249642 0.249642)
							(end -0.1778 0.2794)
						)
						(arc
							(start 0.1778 0.2794)
							(mid 0.249642 0.249642)
							(end 0.2794 0.1778)
						)
						(arc
							(start 0.2794 -0.1778)
							(mid 0.249642 -0.249642)
							(end 0.1778 -0.2794)
						)
					)
					(width 0)
					(fill yes)
				)
			)
		)
	)
	(footprint ""
		(layer "F.Cu")
		(at 89.788746 -24.5237)
		(property "Reference" "Q29"
			(at 0 0 0)
			(layer "F.SilkS")
			(hide yes)
			(effects
				(font
					(size 1.27 1.27)
				)
			)
		)
		(property "Value" "AO4406AL-GP"
			(at -3.707384 -1.5367 0)
			(unlocked yes)
			(layer "F.Fab")
			(hide yes)
			(effects
				(font
					(size 1.016 1.016)
					(thickness 0.1524)
				)
			)
		)
		(property "Device Type" "SOIC8H69"
			(at -3.707384 -3.0607 0)
			(unlocked yes)
			(layer "F.Fab")
			(hide yes)
			(effects
				(font
					(size 1.016 1.016)
					(thickness 0.1524)
				)
			)
		)
		(duplicate_pad_numbers_are_jumpers no)
		(fp_line
			(start -2.7432 -1.4224)
			(end -2.7432 1.4224)
			(stroke
				(width 0.1524)
				(type default)
			)
			(layer "F.SilkS")
		)
		(fp_line
			(start -2.7432 1.4224)
			(end -2.6416 1.4224)
			(stroke
				(width 0.1524)
				(type default)
			)
			(layer "F.SilkS")
		)
		(fp_line
			(start -2.7432 1.4224)
			(end 2.1336 1.4224)
			(stroke
				(width 0.1524)
				(type default)
			)
			(layer "F.SilkS")
		)
		(fp_line
			(start -2.7178 -0.508)
			(end -2.1844 -0.0508)
			(stroke
				(width 0.1524)
				(type default)
			)
			(layer "F.SilkS")
		)
		(fp_line
			(start -2.6289 3.4417)
			(end -2.6289 1.4732)
			(stroke
				(width 0.381)
				(type default)
			)
			(layer "F.SilkS")
		)
		(fp_line
			(start -2.1844 -0.0508)
			(end -2.7178 0.508)
			(stroke
				(width 0.1524)
				(type default)
			)
			(layer "F.SilkS")
		)
		(fp_line
			(start 2.1336 -1.4224)
			(end -2.7432 -1.4224)
			(stroke
				(width 0.1524)
				(type default)
			)
			(layer "F.SilkS")
		)
		(fp_line
			(start 2.1336 1.4224)
			(end 2.1336 -1.4224)
			(stroke
				(width 0.1524)
				(type default)
			)
			(layer "F.SilkS")
		)
		(fp_poly
			(pts
				(xy -2.2098 -1.4224) (xy -2.2098 1.4224) (xy 2.2098 1.4224) (xy 2.2098 -1.4224)
			)
			(stroke
				(width 0)
				(type default)
			)
			(fill yes)
			(layer "F.SilkS")
		)
		(fp_rect
			(start -2.450084 2.999994)
			(end 2.450084 -2.999994)
			(stroke
				(width 0)
				(type default)
			)
			(fill no)
			(layer "F.CrtYd")
		)
		(fp_poly
			(pts
				(xy -2.8194 3.6322) (xy -2.8194 -3.6322) (xy 2.8194 -3.6322) (xy 2.8194 1.18364) (xy 2.450084 1.18364)
				(xy 2.450084 -2.999994) (xy -2.450084 -2.999994) (xy -2.450084 2.999994) (xy 2.450084 2.999994)
				(xy 2.450084 1.18618) (xy 2.8194 1.18618) (xy 2.8194 3.6322)
			)
			(stroke
				(width 0)
				(type default)
			)
			(fill no)
			(layer "F.CrtYd")
		)
		(fp_rect
			(start -2.8194 3.6322)
			(end 2.8194 -3.6322)
			(stroke
				(width 0)
				(type default)
			)
			(fill no)
			(layer "F.Fab")
		)
		(pad "1" smd rect
			(at -1.905 2.54)
			(size 0.635 1.651)
			(layers "F.Cu" "F.Mask" "F.Paste")
			(net "P5V_HDD14")
		)
		(pad "2" smd rect
			(at -0.635 2.54)
			(size 0.635 1.651)
			(layers "F.Cu" "F.Mask" "F.Paste")
			(net "P5V_HDD14")
		)
		(pad "3" smd rect
			(at 0.635 2.54)
			(size 0.635 1.651)
			(layers "F.Cu" "F.Mask" "F.Paste")
			(net "P5V_HDD14")
		)
		(pad "4" smd rect
			(at 1.905 2.54)
			(size 0.635 1.651)
			(layers "F.Cu" "F.Mask" "F.Paste")
			(net "SW_HDD14_P")
		)
		(pad "5" smd rect
			(at 1.905 -2.54)
			(size 0.635 1.651)
			(layers "F.Cu" "F.Mask" "F.Paste")
			(net "P5VC")
		)
		(pad "6" smd rect
			(at 0.635 -2.54)
			(size 0.635 1.651)
			(layers "F.Cu" "F.Mask" "F.Paste")
			(net "P5VC")
		)
		(pad "7" smd rect
			(at -0.635 -2.54)
			(size 0.635 1.651)
			(layers "F.Cu" "F.Mask" "F.Paste")
			(net "P5VC")
		)
		(pad "8" smd rect
			(at -1.905 -2.54)
			(size 0.635 1.651)
			(layers "F.Cu" "F.Mask" "F.Paste")
			(net "P5VC")
		)
	)
	(footprint ""
		(layer "F.Cu")
		(at 193.166746 -290.5887 -90)
		(property "Reference" "Q6"
			(at 0 0 270)
			(layer "F.SilkS")
			(hide yes)
			(effects
				(font
					(size 1.27 1.27)
				)
			)
		)
		(property "Value" "2N7002DW-7F-GP"
			(at -2.3622 -8.2042 270)
			(unlocked yes)
			(layer "F.Fab")
			(hide yes)
			(effects
				(font
					(size 1.016 1.016)
					(thickness 0.1524)
				)
			)
		)
		(property "Device Type" "SOT-363H44"
			(at -2.3622 -10.1092 270)
			(unlocked yes)
			(layer "F.Fab")
			(hide yes)
			(effects
				(font
					(size 1.016 1.016)
					(thickness 0.1524)
				)
			)
		)
		(duplicate_pad_numbers_are_jumpers no)
		(fp_line
			(start -1.4478 1.7018)
			(end 1.4478 1.7018)
			(stroke
				(width 0.1524)
				(type default)
			)
			(layer "F.SilkS")
		)
		(fp_line
			(start 1.4478 1.7018)
			(end 1.4478 -1.7018)
			(stroke
				(width 0.1524)
				(type default)
			)
			(layer "F.SilkS")
		)
		(fp_line
			(start -1.27 1.524)
			(end -1.27 0.6604)
			(stroke
				(width 0.4826)
				(type default)
			)
			(layer "F.SilkS")
		)
		(fp_line
			(start -1.4478 -1.7018)
			(end -1.4478 1.7018)
			(stroke
				(width 0.1524)
				(type default)
			)
			(layer "F.SilkS")
		)
		(fp_line
			(start 1.4478 -1.7018)
			(end -1.4478 -1.7018)
			(stroke
				(width 0.1524)
				(type default)
			)
			(layer "F.SilkS")
		)
		(fp_poly
			(pts
				(xy -1.524 -1.778) (xy 1.524 -1.778) (xy 1.524 1.778) (xy -1.524 1.778)
			)
			(stroke
				(width 0)
				(type default)
			)
			(fill no)
			(layer "F.CrtYd")
		)
		(fp_poly
			(pts
				(xy -1.524 -1.778) (xy 1.524 -1.778) (xy 1.524 1.778) (xy -1.524 1.778)
			)
			(stroke
				(width 0)
				(type default)
			)
			(fill no)
			(layer "F.Fab")
		)
		(pad "1" smd rect
			(at -0.65024 0.9398 270)
			(size 0.4064 1.016)
			(layers "F.Cu" "F.Mask" "F.Paste")
			(net "GND")
		)
		(pad "2" smd rect
			(at 0 0.9398 270)
			(size 0.4064 1.016)
			(layers "F.Cu" "F.Mask" "F.Paste")
			(net "SW_PWR_R_HDD2")
		)
		(pad "3" smd rect
			(at 0.65024 0.9398 270)
			(size 0.4064 1.016)
			(layers "F.Cu" "F.Mask" "F.Paste")
			(net "SW_HDD2_P")
		)
		(pad "4" smd rect
			(at 0.65024 -0.9398 270)
			(size 0.4064 1.016)
			(layers "F.Cu" "F.Mask" "F.Paste")
			(net "GND")
		)
		(pad "5" smd rect
			(at 0 -0.9398 270)
			(size 0.4064 1.016)
			(layers "F.Cu" "F.Mask" "F.Paste")
			(net "SW_HDD2_G")
		)
		(pad "6" smd rect
			(at -0.65024 -0.9398 270)
			(size 0.4064 1.016)
			(layers "F.Cu" "F.Mask" "F.Paste")
			(net "SW_HDD2_R")
		)
	)
	(footprint ""
		(layer "F.Cu")
		(at 191.256412 -82.276696 -90)
		(property "Reference" "R164"
			(at 0 0 270)
			(layer "F.SilkS")
			(hide yes)
			(effects
				(font
					(size 1.27 1.27)
				)
			)
		)
		(property "Value" "1KR2F-3-GP"
			(at 0.064008 -3.993896 270)
			(unlocked yes)
			(layer "F.Fab")
			(hide yes)
			(effects
				(font
					(size 1.016 1.016)
					(thickness 0.1524)
				)
			)
		)
		(property "Device Type" "R402H16"
			(at 0.064008 -5.517896 270)
			(unlocked yes)
			(layer "F.Fab")
			(hide yes)
			(effects
				(font
					(size 1.016 1.016)
					(thickness 0.1524)
				)
			)
		)
		(duplicate_pad_numbers_are_jumpers no)
		(fp_line
			(start -0.508 -0.9398)
			(end -0.508 0.9398)
			(stroke
				(width 0.1524)
				(type default)
			)
			(layer "F.SilkS")
		)
		(fp_line
			(start 0.508 -0.9398)
			(end -0.508 -0.9398)
			(stroke
				(width 0.1524)
				(type default)
			)
			(layer "F.SilkS")
		)
		(fp_rect
			(start -0.508 0.9398)
			(end 0.508 -0.9398)
			(stroke
				(width 0)
				(type default)
			)
			(fill no)
			(layer "F.CrtYd")
		)
		(fp_rect
			(start -0.508 0.9398)
			(end 0.508 -0.9398)
			(stroke
				(width 0)
				(type default)
			)
			(fill no)
			(layer "F.Fab")
		)
		(pad "1" smd custom
			(at 0 -0.4445 270)
			(size 0.1397 0.1397)
			(layers "F.Cu" "F.Mask" "F.Paste")
			(net "P3V3")
			(options
				(clearance outline)
				(anchor circle)
			)
			(primitives
				(gr_poly
					(pts
						(arc
							(start -0.1778 -0.2794)
							(mid -0.249642 -0.249642)
							(end -0.2794 -0.1778)
						)
						(arc
							(start -0.2794 0.1778)
							(mid -0.249642 0.249642)
							(end -0.1778 0.2794)
						)
						(arc
							(start 0.1778 0.2794)
							(mid 0.249642 0.249642)
							(end 0.2794 0.1778)
						)
						(arc
							(start 0.2794 -0.1778)
							(mid 0.249642 -0.249642)
							(end 0.1778 -0.2794)
						)
					)
					(width 0)
					(fill yes)
				)
			)
		)
		(pad "2" smd custom
			(at 0 0.4445 270)
			(size 0.1397 0.1397)
			(layers "F.Cu" "F.Mask" "F.Paste")
			(net "SW_PWR_HDD4")
			(options
				(clearance outline)
				(anchor circle)
			)
			(primitives
				(gr_poly
					(pts
						(arc
							(start -0.1778 -0.2794)
							(mid -0.249642 -0.249642)
							(end -0.2794 -0.1778)
						)
						(arc
							(start -0.2794 0.1778)
							(mid -0.249642 0.249642)
							(end -0.1778 0.2794)
						)
						(arc
							(start 0.1778 0.2794)
							(mid 0.249642 0.249642)
							(end 0.2794 0.1778)
						)
						(arc
							(start 0.2794 -0.1778)
							(mid 0.249642 -0.249642)
							(end 0.1778 -0.2794)
						)
					)
					(width 0)
					(fill yes)
				)
			)
		)
	)
	(footprint ""
		(layer "F.Cu")
		(at 33.914334 -30.499558 180)
		(property "Reference" "PTC4"
			(at 0 0 180)
			(layer "F.SilkS")
			(hide yes)
			(effects
				(font
					(size 1.27 1.27)
				)
			)
		)
		(property "Value" "ST330U10VDM-2GP"
			(at 0 -9.6012 180)
			(unlocked yes)
			(layer "F.Fab")
			(hide yes)
			(effects
				(font
					(size 1.016 1.016)
					(thickness 0.1524)
				)
			)
		)
		(property "Device Type" "CT7343H150"
			(at 0 -11.1252 180)
			(unlocked yes)
			(layer "F.Fab")
			(hide yes)
			(effects
				(font
					(size 1.016 1.016)
					(thickness 0.1524)
				)
			)
		)
		(duplicate_pad_numbers_are_jumpers no)
		(fp_line
			(start 2.286 4.8768)
			(end -2.286 4.8768)
			(stroke
				(width 0.1524)
				(type default)
			)
			(layer "F.SilkS")
		)
		(fp_line
			(start 2.286 2.032)
			(end 2.286 4.8768)
			(stroke
				(width 0.1524)
				(type default)
			)
			(layer "F.SilkS")
		)
		(fp_line
			(start 2.286 -2.032)
			(end 2.286 -4.8768)
			(stroke
				(width 0.1524)
				(type default)
			)
			(layer "F.SilkS")
		)
		(fp_line
			(start 2.286 -4.8768)
			(end -2.286 -4.8768)
			(stroke
				(width 0.1524)
				(type default)
			)
			(layer "F.SilkS")
		)
		(fp_line
			(start 2.1082 -4.699)
			(end -2.1082 -4.699)
			(stroke
				(width 0.508)
				(type default)
			)
			(layer "F.SilkS")
		)
		(fp_line
			(start -2.286 4.8768)
			(end -2.286 2.032)
			(stroke
				(width 0.1524)
				(type default)
			)
			(layer "F.SilkS")
		)
		(fp_line
			(start -2.286 -4.8768)
			(end -2.286 -2.032)
			(stroke
				(width 0.1524)
				(type default)
			)
			(layer "F.SilkS")
		)
		(fp_rect
			(start -2.1463 3.6449)
			(end 2.1463 -3.6449)
			(stroke
				(width 0)
				(type default)
			)
			(fill no)
			(layer "F.CrtYd")
		)
		(fp_poly
			(pts
				(xy -2.54 4.953) (xy -2.54 4.2926) (xy -3.81 4.2926) (xy -3.81 -4.2926) (xy -2.54 -4.2926) (xy -2.54 -4.953)
				(xy 2.54 -4.953) (xy 2.54 -4.2926) (xy 3.81 -4.2926) (xy 3.81 -1.6256) (xy 2.1463 -1.6256) (xy 2.1463 -3.6449)
				(xy -2.1463 -3.6449) (xy -2.1463 3.6449) (xy 2.1463 3.6449) (xy 2.1463 -1.6129) (xy 3.81 -1.6129)
				(xy 3.81 4.2926) (xy 2.54 4.2926) (xy 2.54 4.953)
			)
			(stroke
				(width 0)
				(type default)
			)
			(fill no)
			(layer "F.CrtYd")
		)
		(fp_rect
			(start 2.54 4.2926)
			(end 3.81 -4.2926)
			(stroke
				(width 0)
				(type default)
			)
			(fill no)
			(layer "F.Fab")
		)
		(fp_rect
			(start -2.54 4.953)
			(end 2.54 -4.953)
			(stroke
				(width 0)
				(type default)
			)
			(fill no)
			(layer "F.Fab")
		)
		(fp_rect
			(start -3.81 4.2926)
			(end -2.54 -4.2926)
			(stroke
				(width 0)
				(type default)
			)
			(fill no)
			(layer "F.Fab")
		)
		(pad "1" smd rect
			(at 0 -3.1496 180)
			(size 2.413 2.286)
			(layers "F.Cu" "F.Mask" "F.Paste")
			(net "P5VB")
		)
		(pad "2" smd rect
			(at 0 3.1496 180)
			(size 2.413 2.286)
			(layers "F.Cu" "F.Mask" "F.Paste")
			(net "GND")
		)
		(zone
			(layer "F.Cu")
			(hatch none 0.5)
			(connect_pads
				(clearance 0)
			)
			(min_thickness 0.25)
			(keepout
				(tracks allowed)
				(vias not_allowed)
				(pads allowed)
				(copperpour not_allowed)
				(footprints allowed)
			)
			(placement
				(enabled no)
				(sheetname "")
			)
			(fill
				(thermal_gap 0.5)
				(thermal_bridge_width 0.5)
				(island_removal_mode 0)
			)
			(polygon
				(pts
					(xy 32.403034 -28.810458) (xy 32.403034 -25.902158) (xy 35.425634 -25.902158) (xy 35.425634 -28.797758)
					(xy 35.425634 -29.127958) (xy 32.403034 -29.127958)
				)
			)
		)
		(zone
			(layer "F.Cu")
			(hatch none 0.5)
			(connect_pads
				(clearance 0)
			)
			(min_thickness 0.25)
			(keepout
				(tracks allowed)
				(vias not_allowed)
				(pads allowed)
				(copperpour not_allowed)
				(footprints allowed)
			)
			(placement
				(enabled no)
				(sheetname "")
			)
			(fill
				(thermal_gap 0.5)
				(thermal_bridge_width 0.5)
				(island_removal_mode 0)
			)
			(polygon
				(pts
					(xy 35.425634 -35.096958) (xy 32.403034 -35.096958) (xy 32.403034 -32.201358) (xy 32.403034 -31.871158)
					(xy 35.425634 -31.871158) (xy 35.425634 -32.201358)
				)
			)
		)
	)
	(footprint ""
		(layer "F.Cu")
		(at 81.5594 -24.1046 90)
		(property "Reference" "Q74"
			(at 0 0 90)
			(layer "F.SilkS")
			(hide yes)
			(effects
				(font
					(size 1.27 1.27)
				)
			)
		)
		(property "Value" "2N7002DW-7F-GP"
			(at -2.3622 -8.2042 90)
			(unlocked yes)
			(layer "F.Fab")
			(hide yes)
			(effects
				(font
					(size 1.016 1.016)
					(thickness 0.1524)
				)
			)
		)
		(property "Device Type" "SOT-363H44"
			(at -2.3622 -10.1092 90)
			(unlocked yes)
			(layer "F.Fab")
			(hide yes)
			(effects
				(font
					(size 1.016 1.016)
					(thickness 0.1524)
				)
			)
		)
		(duplicate_pad_numbers_are_jumpers no)
		(fp_line
			(start 1.4478 -1.7018)
			(end -1.4478 -1.7018)
			(stroke
				(width 0.1524)
				(type default)
			)
			(layer "F.SilkS")
		)
		(fp_line
			(start -1.4478 -1.7018)
			(end -1.4478 1.7018)
			(stroke
				(width 0.1524)
				(type default)
			)
			(layer "F.SilkS")
		)
		(fp_line
			(start -1.27 1.524)
			(end -1.27 0.6604)
			(stroke
				(width 0.4826)
				(type default)
			)
			(layer "F.SilkS")
		)
		(fp_line
			(start 1.4478 1.7018)
			(end 1.4478 -1.7018)
			(stroke
				(width 0.1524)
				(type default)
			)
			(layer "F.SilkS")
		)
		(fp_line
			(start -1.4478 1.7018)
			(end 1.4478 1.7018)
			(stroke
				(width 0.1524)
				(type default)
			)
			(layer "F.SilkS")
		)
		(fp_poly
			(pts
				(xy -1.524 -1.778) (xy 1.524 -1.778) (xy 1.524 1.778) (xy -1.524 1.778)
			)
			(stroke
				(width 0)
				(type default)
			)
			(fill no)
			(layer "F.CrtYd")
		)
		(fp_poly
			(pts
				(xy -1.524 -1.778) (xy 1.524 -1.778) (xy 1.524 1.778) (xy -1.524 1.778)
			)
			(stroke
				(width 0)
				(type default)
			)
			(fill no)
			(layer "F.Fab")
		)
		(pad "1" smd rect
			(at -0.65024 0.9398 90)
			(size 0.4064 1.016)
			(layers "F.Cu" "F.Mask" "F.Paste")
			(net "P3V3_HDD14_LED")
		)
		(pad "2" smd rect
			(at 0 0.9398 90)
			(size 0.4064 1.016)
			(layers "F.Cu" "F.Mask" "F.Paste")
			(net "HDD14_LED_G")
		)
		(pad "3" smd rect
			(at 0.65024 0.9398 90)
			(size 0.4064 1.016)
			(layers "F.Cu" "F.Mask" "F.Paste")
			(net "P5VC")
		)
		(pad "4" smd rect
			(at 0.65024 -0.9398 90)
			(size 0.4064 1.016)
			(layers "F.Cu" "F.Mask" "F.Paste")
			(net "P5VC_HDD14_LED")
		)
		(pad "5" smd rect
			(at 0 -0.9398 90)
			(size 0.4064 1.016)
			(layers "F.Cu" "F.Mask" "F.Paste")
			(net "HDD14_LED_G")
		)
		(pad "6" smd rect
			(at -0.65024 -0.9398 90)
			(size 0.4064 1.016)
			(layers "F.Cu" "F.Mask" "F.Paste")
			(net "P3V3")
		)
	)
	(footprint ""
		(layer "F.Cu")
		(at 207.4926 -170.2054 -90)
		(property "Reference" "Q52"
			(at 0 0 270)
			(layer "F.SilkS")
			(hide yes)
			(effects
				(font
					(size 1.27 1.27)
				)
			)
		)
		(property "Value" "2N7002DW-7F-GP"
			(at -2.3622 -8.2042 270)
			(unlocked yes)
			(layer "F.Fab")
			(hide yes)
			(effects
				(font
					(size 1.016 1.016)
					(thickness 0.1524)
				)
			)
		)
		(property "Device Type" "SOT-363H44"
			(at -2.3622 -10.1092 270)
			(unlocked yes)
			(layer "F.Fab")
			(hide yes)
			(effects
				(font
					(size 1.016 1.016)
					(thickness 0.1524)
				)
			)
		)
		(duplicate_pad_numbers_are_jumpers no)
		(fp_line
			(start -1.4478 1.7018)
			(end 1.4478 1.7018)
			(stroke
				(width 0.1524)
				(type default)
			)
			(layer "F.SilkS")
		)
		(fp_line
			(start 1.4478 1.7018)
			(end 1.4478 -1.7018)
			(stroke
				(width 0.1524)
				(type default)
			)
			(layer "F.SilkS")
		)
		(fp_line
			(start -1.27 1.524)
			(end -1.27 0.6604)
			(stroke
				(width 0.4826)
				(type default)
			)
			(layer "F.SilkS")
		)
		(fp_line
			(start -1.4478 -1.7018)
			(end -1.4478 1.7018)
			(stroke
				(width 0.1524)
				(type default)
			)
			(layer "F.SilkS")
		)
		(fp_line
			(start 1.4478 -1.7018)
			(end -1.4478 -1.7018)
			(stroke
				(width 0.1524)
				(type default)
			)
			(layer "F.SilkS")
		)
		(fp_poly
			(pts
				(xy -1.524 -1.778) (xy 1.524 -1.778) (xy 1.524 1.778) (xy -1.524 1.778)
			)
			(stroke
				(width 0)
				(type default)
			)
			(fill no)
			(layer "F.CrtYd")
		)
		(fp_poly
			(pts
				(xy -1.524 -1.778) (xy 1.524 -1.778) (xy 1.524 1.778) (xy -1.524 1.778)
			)
			(stroke
				(width 0)
				(type default)
			)
			(fill no)
			(layer "F.Fab")
		)
		(pad "1" smd rect
			(at -0.65024 0.9398 270)
			(size 0.4064 1.016)
			(layers "F.Cu" "F.Mask" "F.Paste")
			(net "P3V3_HDD3_LED")
		)
		(pad "2" smd rect
			(at 0 0.9398 270)
			(size 0.4064 1.016)
			(layers "F.Cu" "F.Mask" "F.Paste")
			(net "HDD3_LED_G")
		)
		(pad "3" smd rect
			(at 0.65024 0.9398 270)
			(size 0.4064 1.016)
			(layers "F.Cu" "F.Mask" "F.Paste")
			(net "P5VA")
		)
		(pad "4" smd rect
			(at 0.65024 -0.9398 270)
			(size 0.4064 1.016)
			(layers "F.Cu" "F.Mask" "F.Paste")
			(net "P5VA_HDD3_LED")
		)
		(pad "5" smd rect
			(at 0 -0.9398 270)
			(size 0.4064 1.016)
			(layers "F.Cu" "F.Mask" "F.Paste")
			(net "HDD3_LED_G")
		)
		(pad "6" smd rect
			(at -0.65024 -0.9398 270)
			(size 0.4064 1.016)
			(layers "F.Cu" "F.Mask" "F.Paste")
			(net "P3V3")
		)
	)
	(footprint ""
		(layer "F.Cu")
		(at 18.541746 -476.7707)
		(property "Reference" "PC38"
			(at 0 0 0)
			(layer "F.SilkS")
			(hide yes)
			(effects
				(font
					(size 1.27 1.27)
				)
			)
		)
		(property "Value" "SC10U16V6KX-2GP"
			(at -0.0762 -5.1308 0)
			(unlocked yes)
			(layer "F.Fab")
			(hide yes)
			(effects
				(font
					(size 1.016 1.016)
					(thickness 0.1524)
				)
			)
		)
		(property "Device Type" "C1206H71"
			(at -0.127 -6.6548 0)
			(unlocked yes)
			(layer "F.Fab")
			(hide yes)
			(effects
				(font
					(size 1.016 1.016)
					(thickness 0.1524)
				)
			)
		)
		(duplicate_pad_numbers_are_jumpers no)
		(fp_line
			(start -1.016 -2.2352)
			(end 1.016 -2.2352)
			(stroke
				(width 0.1524)
				(type default)
			)
			(layer "F.SilkS")
		)
		(fp_line
			(start -1.016 -0.8382)
			(end -1.016 -2.2352)
			(stroke
				(width 0.1524)
				(type default)
			)
			(layer "F.SilkS")
		)
		(fp_line
			(start -1.016 2.2352)
			(end -1.016 0.8382)
			(stroke
				(width 0.1524)
				(type default)
			)
			(layer "F.SilkS")
		)
		(fp_line
			(start 1.016 -2.2352)
			(end 1.016 -0.8382)
			(stroke
				(width 0.1524)
				(type default)
			)
			(layer "F.SilkS")
		)
		(fp_line
			(start 1.016 0.8382)
			(end 1.016 2.2352)
			(stroke
				(width 0.1524)
				(type default)
			)
			(layer "F.SilkS")
		)
		(fp_line
			(start 1.016 2.2352)
			(end -1.016 2.2352)
			(stroke
				(width 0.1524)
				(type default)
			)
			(layer "F.SilkS")
		)
		(fp_rect
			(start -1.0922 2.3114)
			(end 1.0922 -2.3114)
			(stroke
				(width 0)
				(type default)
			)
			(fill no)
			(layer "F.CrtYd")
		)
		(fp_poly
			(pts
				(xy 1.0922 -2.3114) (xy 1.0922 2.3114) (xy -1.0922 2.3114) (xy -1.0922 -2.3114)
			)
			(stroke
				(width 0)
				(type default)
			)
			(fill no)
			(layer "F.Fab")
		)
		(pad "1" smd rect
			(at 0 -1.397)
			(size 1.651 1.27)
			(layers "F.Cu" "F.Mask" "F.Paste")
			(net "P5VC")
		)
		(pad "2" smd rect
			(at 0 1.397)
			(size 1.651 1.27)
			(layers "F.Cu" "F.Mask" "F.Paste")
			(net "GND")
		)
	)
	(footprint ""
		(layer "F.Cu")
		(at 217.854784 -166.340028 -90)
		(property "Reference" "C152"
			(at 0 0 270)
			(layer "F.SilkS")
			(hide yes)
			(effects
				(font
					(size 1.27 1.27)
				)
			)
		)
		(property "Value" "SCD01U50V2KX-1GP"
			(at 1.1811 -2.7051 270)
			(unlocked yes)
			(layer "F.Fab")
			(hide yes)
			(effects
				(font
					(size 1.016 1.016)
					(thickness 0.1524)
				)
			)
		)
		(property "Device Type" "C402H22"
			(at 1.1811 -4.2291 270)
			(unlocked yes)
			(layer "F.Fab")
			(hide yes)
			(effects
				(font
					(size 1.016 1.016)
					(thickness 0.1524)
				)
			)
		)
		(duplicate_pad_numbers_are_jumpers no)
		(fp_rect
			(start -0.4318 0.9525)
			(end 0.4318 -0.9525)
			(stroke
				(width 0)
				(type default)
			)
			(fill no)
			(layer "F.CrtYd")
		)
		(fp_rect
			(start -0.4318 0.9525)
			(end 0.4318 -0.9525)
			(stroke
				(width 0)
				(type default)
			)
			(fill no)
			(layer "F.Fab")
		)
		(pad "1" smd custom
			(at 0 -0.4445 270)
			(size 0.1524 0.1524)
			(layers "F.Cu" "F.Mask" "F.Paste")
			(net "SAS2X28_DRIVE_RX_N_B3")
			(options
				(clearance outline)
				(anchor circle)
			)
			(primitives
				(gr_poly
					(pts
						(arc
							(start 0.3048 -0.2032)
							(mid 0.275042 -0.275042)
							(end 0.2032 -0.3048)
						)
						(arc
							(start -0.2032 -0.3048)
							(mid -0.275042 -0.275042)
							(end -0.3048 -0.2032)
						)
						(arc
							(start -0.3048 0.2032)
							(mid -0.275042 0.275042)
							(end -0.2032 0.3048)
						)
						(arc
							(start 0.2032 0.3048)
							(mid 0.275042 0.275042)
							(end 0.3048 0.2032)
						)
					)
					(width 0)
					(fill yes)
				)
			)
		)
		(pad "2" smd custom
			(at 0 0.4445 270)
			(size 0.1524 0.1524)
			(layers "F.Cu" "F.Mask" "F.Paste")
			(net "SAS2X28_B_HDD3_RX_-")
			(options
				(clearance outline)
				(anchor circle)
			)
			(primitives
				(gr_poly
					(pts
						(arc
							(start 0.3048 -0.2032)
							(mid 0.275042 -0.275042)
							(end 0.2032 -0.3048)
						)
						(arc
							(start -0.2032 -0.3048)
							(mid -0.275042 -0.275042)
							(end -0.3048 -0.2032)
						)
						(arc
							(start -0.3048 0.2032)
							(mid -0.275042 0.275042)
							(end -0.2032 0.3048)
						)
						(arc
							(start 0.2032 0.3048)
							(mid 0.275042 0.275042)
							(end 0.3048 0.2032)
						)
					)
					(width 0)
					(fill yes)
				)
			)
		)
	)
	(footprint ""
		(layer "F.Cu")
		(at 216.941654 -437.3245 180)
		(property "Reference" "PL7"
			(at 0 0 180)
			(layer "F.SilkS")
			(hide yes)
			(effects
				(font
					(size 1.27 1.27)
				)
			)
		)
		(property "Value" "IND-22UH-169-GP"
			(at -4.7498 0.5588 180)
			(unlocked yes)
			(layer "F.Fab")
			(hide yes)
			(effects
				(font
					(size 1.016 1.016)
					(thickness 0.1524)
				)
			)
		)
		(property "Device Type" "L6362-D620H119"
			(at -4.7498 -0.9652 180)
			(unlocked yes)
			(layer "F.Fab")
			(hide yes)
			(effects
				(font
					(size 1.016 1.016)
					(thickness 0.1524)
				)
			)
		)
		(duplicate_pad_numbers_are_jumpers no)
		(fp_line
			(start 3.3528 2.213356)
			(end 1.667256 3.8989)
			(stroke
				(width 0.1524)
				(type default)
			)
			(layer "F.SilkS")
		)
		(fp_line
			(start 3.3528 -2.213356)
			(end 3.3528 2.213356)
			(stroke
				(width 0.1524)
				(type default)
			)
			(layer "F.SilkS")
		)
		(fp_line
			(start 1.667256 3.8989)
			(end -1.667256 3.8989)
			(stroke
				(width 0.1524)
				(type default)
			)
			(layer "F.SilkS")
		)
		(fp_line
			(start 1.667256 -3.8989)
			(end 3.3528 -2.213356)
			(stroke
				(width 0.1524)
				(type default)
			)
			(layer "F.SilkS")
		)
		(fp_line
			(start -1.667256 3.8989)
			(end -3.3528 2.213356)
			(stroke
				(width 0.1524)
				(type default)
			)
			(layer "F.SilkS")
		)
		(fp_line
			(start -1.667256 -3.8989)
			(end 1.667256 -3.8989)
			(stroke
				(width 0.1524)
				(type default)
			)
			(layer "F.SilkS")
		)
		(fp_line
			(start -3.3528 2.213356)
			(end -3.3528 -2.213356)
			(stroke
				(width 0.1524)
				(type default)
			)
			(layer "F.SilkS")
		)
		(fp_line
			(start -3.3528 -2.213356)
			(end -1.667256 -3.8989)
			(stroke
				(width 0.1524)
				(type default)
			)
			(layer "F.SilkS")
		)
		(fp_poly
			(pts
				(xy 2.0574 3.1496) (xy -2.0574 3.1496) (xy -3.0988 2.1082) (xy -3.0988 -2.1082) (xy -2.0574 -3.1496)
				(xy 2.0574 -3.1496) (xy 3.0988 -2.1082) (xy 3.0988 2.1082)
			)
			(stroke
				(width 0)
				(type default)
			)
			(fill no)
			(layer "F.CrtYd")
		)
		(fp_poly
			(pts
				(xy 3.6068 2.318512) (xy 1.950212 3.9751) (xy -1.950212 3.9751) (xy -3.6068 2.318512) (xy -3.6068 -2.318512)
				(xy -1.950212 -3.9751) (xy 1.950212 -3.9751) (xy 3.6068 -2.318512) (xy 3.6068 -1.9177) (xy 3.0988 -1.9177)
				(xy 3.0988 -2.1082) (xy 2.0574 -3.1496) (xy -2.0574 -3.1496) (xy -3.0988 -2.1082) (xy -3.0988 2.1082)
				(xy -2.0574 3.1496) (xy 2.0574 3.1496) (xy 3.0988 2.1082) (xy 3.0988 -1.905) (xy 3.6068 -1.905)
			)
			(stroke
				(width 0)
				(type default)
			)
			(fill no)
			(layer "F.CrtYd")
		)
		(fp_poly
			(pts
				(xy -1.950212 3.9751) (xy -3.6068 2.318512) (xy -3.6068 -2.318512) (xy -1.950212 -3.9751) (xy 1.950212 -3.9751)
				(xy 3.6068 -2.318512) (xy 3.6068 2.318512) (xy 1.950212 3.9751)
			)
			(stroke
				(width 0)
				(type default)
			)
			(fill no)
			(layer "F.Fab")
		)
		(pad "1" smd rect
			(at 0 -2.895346 180)
			(size 2.2606 1.4986)
			(layers "F.Cu" "F.Mask" "F.Paste")
			(net "P3V3_LX")
		)
		(pad "2" smd rect
			(at 0 2.895346 180)
			(size 2.2606 1.4986)
			(layers "F.Cu" "F.Mask" "F.Paste")
			(net "P3V3_LX_COOPER")
		)
	)
	(footprint ""
		(layer "F.Cu")
		(at 44.068746 -230.279702 90)
		(property "Reference" "R273"
			(at 0 0 90)
			(layer "F.SilkS")
			(hide yes)
			(effects
				(font
					(size 1.27 1.27)
				)
			)
		)
		(property "Value" "2R2010J-1-GP"
			(at 0.254 -8.0772 90)
			(unlocked yes)
			(layer "F.Fab")
			(hide yes)
			(effects
				(font
					(size 1.016 1.016)
					(thickness 0.1524)
				)
			)
		)
		(property "Device Type" "R2010H28"
			(at 0.254 -9.6774 90)
			(unlocked yes)
			(layer "F.Fab")
			(hide yes)
			(effects
				(font
					(size 1.016 1.016)
					(thickness 0.1524)
				)
			)
		)
		(duplicate_pad_numbers_are_jumpers no)
		(fp_line
			(start 1.651 -3.302)
			(end -1.651 -3.302)
			(stroke
				(width 0.1524)
				(type default)
			)
			(layer "F.SilkS")
		)
		(fp_line
			(start -1.651 -3.302)
			(end -1.651 3.302)
			(stroke
				(width 0.1524)
				(type default)
			)
			(layer "F.SilkS")
		)
		(fp_line
			(start 1.651 3.302)
			(end 1.651 -3.302)
			(stroke
				(width 0.1524)
				(type default)
			)
			(layer "F.SilkS")
		)
		(fp_line
			(start -1.651 3.302)
			(end 1.651 3.302)
			(stroke
				(width 0.1524)
				(type default)
			)
			(layer "F.SilkS")
		)
		(fp_rect
			(start -1.7272 -3.3782)
			(end 1.7272 3.3782)
			(stroke
				(width 0)
				(type default)
			)
			(fill no)
			(layer "F.CrtYd")
		)
		(fp_poly
			(pts
				(xy 1.7272 3.3782) (xy 1.7272 -3.3782) (xy -1.7272 -3.3782) (xy -1.7272 3.3782)
			)
			(stroke
				(width 0)
				(type default)
			)
			(fill no)
			(layer "F.Fab")
		)
		(pad "1" smd rect
			(at 0 -2.3495 90)
			(size 2.794 1.143)
			(layers "F.Cu" "F.Mask" "F.Paste")
			(net "5V_PRE_12")
		)
		(pad "2" smd rect
			(at 0 2.3495 90)
			(size 2.794 1.143)
			(layers "F.Cu" "F.Mask" "F.Paste")
			(net "P5V_HDD12")
		)
	)
	(footprint ""
		(layer "F.Cu")
		(at 38.163246 -129.060702 90)
		(property "Reference" "R289"
			(at 0 0 90)
			(layer "F.SilkS")
			(hide yes)
			(effects
				(font
					(size 1.27 1.27)
				)
			)
		)
		(property "Value" "2R2010J-1-GP"
			(at 0.254 -8.0772 90)
			(unlocked yes)
			(layer "F.Fab")
			(hide yes)
			(effects
				(font
					(size 1.016 1.016)
					(thickness 0.1524)
				)
			)
		)
		(property "Device Type" "R2010H28"
			(at 0.254 -9.6774 90)
			(unlocked yes)
			(layer "F.Fab")
			(hide yes)
			(effects
				(font
					(size 1.016 1.016)
					(thickness 0.1524)
				)
			)
		)
		(duplicate_pad_numbers_are_jumpers no)
		(fp_line
			(start 1.651 -3.302)
			(end -1.651 -3.302)
			(stroke
				(width 0.1524)
				(type default)
			)
			(layer "F.SilkS")
		)
		(fp_line
			(start -1.651 -3.302)
			(end -1.651 3.302)
			(stroke
				(width 0.1524)
				(type default)
			)
			(layer "F.SilkS")
		)
		(fp_line
			(start 1.651 3.302)
			(end 1.651 -3.302)
			(stroke
				(width 0.1524)
				(type default)
			)
			(layer "F.SilkS")
		)
		(fp_line
			(start -1.651 3.302)
			(end 1.651 3.302)
			(stroke
				(width 0.1524)
				(type default)
			)
			(layer "F.SilkS")
		)
		(fp_rect
			(start -1.7272 -3.3782)
			(end 1.7272 3.3782)
			(stroke
				(width 0)
				(type default)
			)
			(fill no)
			(layer "F.CrtYd")
		)
		(fp_poly
			(pts
				(xy 1.7272 3.3782) (xy 1.7272 -3.3782) (xy -1.7272 -3.3782) (xy -1.7272 3.3782)
			)
			(stroke
				(width 0)
				(type default)
			)
			(fill no)
			(layer "F.Fab")
		)
		(pad "1" smd rect
			(at 0 -2.3495 90)
			(size 2.794 1.143)
			(layers "F.Cu" "F.Mask" "F.Paste")
			(net "5V_PRE_13")
		)
		(pad "2" smd rect
			(at 0 2.3495 90)
			(size 2.794 1.143)
			(layers "F.Cu" "F.Mask" "F.Paste")
			(net "P5V_HDD13")
		)
	)
	(footprint ""
		(layer "F.Cu")
		(at 230.364284 -143.988028 90)
		(property "Reference" "R144"
			(at 0 0 90)
			(layer "F.SilkS")
			(hide yes)
			(effects
				(font
					(size 1.27 1.27)
				)
			)
		)
		(property "Value" "0R2J-2-GP"
			(at 0.064008 -3.993896 90)
			(unlocked yes)
			(layer "F.Fab")
			(hide yes)
			(effects
				(font
					(size 1.016 1.016)
					(thickness 0.1524)
				)
			)
		)
		(property "Device Type" "R402H16"
			(at 0.064008 -5.517896 90)
			(unlocked yes)
			(layer "F.Fab")
			(hide yes)
			(effects
				(font
					(size 1.016 1.016)
					(thickness 0.1524)
				)
			)
		)
		(duplicate_pad_numbers_are_jumpers no)
		(fp_line
			(start 0.508 -0.9398)
			(end -0.508 -0.9398)
			(stroke
				(width 0.1524)
				(type default)
			)
			(layer "F.SilkS")
		)
		(fp_line
			(start -0.508 -0.9398)
			(end -0.508 0.9398)
			(stroke
				(width 0.1524)
				(type default)
			)
			(layer "F.SilkS")
		)
		(fp_rect
			(start -0.508 0.9398)
			(end 0.508 -0.9398)
			(stroke
				(width 0)
				(type default)
			)
			(fill no)
			(layer "F.CrtYd")
		)
		(fp_rect
			(start -0.508 0.9398)
			(end 0.508 -0.9398)
			(stroke
				(width 0)
				(type default)
			)
			(fill no)
			(layer "F.Fab")
		)
		(pad "1" smd custom
			(at 0 -0.4445 90)
			(size 0.1397 0.1397)
			(layers "F.Cu" "F.Mask" "F.Paste")
			(net "DRV_ACT_NET3")
			(options
				(clearance outline)
				(anchor circle)
			)
			(primitives
				(gr_poly
					(pts
						(arc
							(start -0.1778 -0.2794)
							(mid -0.249642 -0.249642)
							(end -0.2794 -0.1778)
						)
						(arc
							(start -0.2794 0.1778)
							(mid -0.249642 0.249642)
							(end -0.1778 0.2794)
						)
						(arc
							(start 0.1778 0.2794)
							(mid 0.249642 0.249642)
							(end 0.2794 0.1778)
						)
						(arc
							(start 0.2794 -0.1778)
							(mid 0.249642 -0.249642)
							(end 0.1778 -0.2794)
						)
					)
					(width 0)
					(fill yes)
				)
			)
		)
		(pad "2" smd custom
			(at 0 0.4445 90)
			(size 0.1397 0.1397)
			(layers "F.Cu" "F.Mask" "F.Paste")
			(net "DRIVE_ACT_3")
			(options
				(clearance outline)
				(anchor circle)
			)
			(primitives
				(gr_poly
					(pts
						(arc
							(start -0.1778 -0.2794)
							(mid -0.249642 -0.249642)
							(end -0.2794 -0.1778)
						)
						(arc
							(start -0.2794 0.1778)
							(mid -0.249642 0.249642)
							(end -0.1778 0.2794)
						)
						(arc
							(start 0.1778 0.2794)
							(mid 0.249642 0.249642)
							(end 0.2794 0.1778)
						)
						(arc
							(start 0.2794 -0.1778)
							(mid 0.249642 -0.249642)
							(end 0.1778 -0.2794)
						)
					)
					(width 0)
					(fill yes)
				)
			)
		)
	)
	(footprint ""
		(layer "F.Cu")
		(at 61.5442 -68.5038 -90)
		(property "Reference" "R395"
			(at 0 0 270)
			(layer "F.SilkS")
			(hide yes)
			(effects
				(font
					(size 1.27 1.27)
				)
			)
		)
		(property "Value" "10KR2F-2-GP"
			(at 0.064008 -3.993896 270)
			(unlocked yes)
			(layer "F.Fab")
			(hide yes)
			(effects
				(font
					(size 1.016 1.016)
					(thickness 0.1524)
				)
			)
		)
		(property "Device Type" "R402H16"
			(at 0.064008 -5.517896 270)
			(unlocked yes)
			(layer "F.Fab")
			(hide yes)
			(effects
				(font
					(size 1.016 1.016)
					(thickness 0.1524)
				)
			)
		)
		(duplicate_pad_numbers_are_jumpers no)
		(fp_line
			(start -0.508 -0.9398)
			(end -0.508 0.9398)
			(stroke
				(width 0.1524)
				(type default)
			)
			(layer "F.SilkS")
		)
		(fp_line
			(start 0.508 -0.9398)
			(end -0.508 -0.9398)
			(stroke
				(width 0.1524)
				(type default)
			)
			(layer "F.SilkS")
		)
		(fp_rect
			(start -0.508 0.9398)
			(end 0.508 -0.9398)
			(stroke
				(width 0)
				(type default)
			)
			(fill no)
			(layer "F.CrtYd")
		)
		(fp_rect
			(start -0.508 0.9398)
			(end 0.508 -0.9398)
			(stroke
				(width 0)
				(type default)
			)
			(fill no)
			(layer "F.Fab")
		)
		(pad "1" smd custom
			(at 0 -0.4445 270)
			(size 0.1397 0.1397)
			(layers "F.Cu" "F.Mask" "F.Paste")
			(net "P12V")
			(options
				(clearance outline)
				(anchor circle)
			)
			(primitives
				(gr_poly
					(pts
						(arc
							(start -0.1778 -0.2794)
							(mid -0.249642 -0.249642)
							(end -0.2794 -0.1778)
						)
						(arc
							(start -0.2794 0.1778)
							(mid -0.249642 0.249642)
							(end -0.1778 0.2794)
						)
						(arc
							(start 0.1778 0.2794)
							(mid 0.249642 0.249642)
							(end 0.2794 0.1778)
						)
						(arc
							(start 0.2794 -0.1778)
							(mid 0.249642 -0.249642)
							(end 0.1778 -0.2794)
						)
					)
					(width 0)
					(fill yes)
				)
			)
		)
		(pad "2" smd custom
			(at 0 0.4445 270)
			(size 0.1397 0.1397)
			(layers "F.Cu" "F.Mask" "F.Paste")
			(net "HDD9_LED_G")
			(options
				(clearance outline)
				(anchor circle)
			)
			(primitives
				(gr_poly
					(pts
						(arc
							(start -0.1778 -0.2794)
							(mid -0.249642 -0.249642)
							(end -0.2794 -0.1778)
						)
						(arc
							(start -0.2794 0.1778)
							(mid -0.249642 0.249642)
							(end -0.1778 0.2794)
						)
						(arc
							(start 0.1778 0.2794)
							(mid 0.249642 0.249642)
							(end 0.2794 0.1778)
						)
						(arc
							(start 0.2794 -0.1778)
							(mid 0.249642 -0.249642)
							(end 0.1778 -0.2794)
						)
					)
					(width 0)
					(fill yes)
				)
			)
		)
	)
	(footprint ""
		(layer "F.Cu")
		(at 46.8884 -349.1992 180)
		(property "Reference" "R185"
			(at 0 0 180)
			(layer "F.SilkS")
			(hide yes)
			(effects
				(font
					(size 1.27 1.27)
				)
			)
		)
		(property "Value" "402R2F-GP"
			(at 0.064008 -3.993896 180)
			(unlocked yes)
			(layer "F.Fab")
			(hide yes)
			(effects
				(font
					(size 1.016 1.016)
					(thickness 0.1524)
				)
			)
		)
		(property "Device Type" "R402H16"
			(at 0.064008 -5.517896 180)
			(unlocked yes)
			(layer "F.Fab")
			(hide yes)
			(effects
				(font
					(size 1.016 1.016)
					(thickness 0.1524)
				)
			)
		)
		(duplicate_pad_numbers_are_jumpers no)
		(fp_line
			(start 0.508 -0.9398)
			(end -0.508 -0.9398)
			(stroke
				(width 0.1524)
				(type default)
			)
			(layer "F.SilkS")
		)
		(fp_line
			(start -0.508 -0.9398)
			(end -0.508 0.9398)
			(stroke
				(width 0.1524)
				(type default)
			)
			(layer "F.SilkS")
		)
		(fp_rect
			(start -0.508 0.9398)
			(end 0.508 -0.9398)
			(stroke
				(width 0)
				(type default)
			)
			(fill no)
			(layer "F.CrtYd")
		)
		(fp_rect
			(start -0.508 0.9398)
			(end 0.508 -0.9398)
			(stroke
				(width 0)
				(type default)
			)
			(fill no)
			(layer "F.Fab")
		)
		(pad "1" smd custom
			(at 0 -0.4445 180)
			(size 0.1397 0.1397)
			(layers "F.Cu" "F.Mask" "F.Paste")
			(net "P5VB_HDD6_LED")
			(options
				(clearance outline)
				(anchor circle)
			)
			(primitives
				(gr_poly
					(pts
						(arc
							(start -0.1778 -0.2794)
							(mid -0.249642 -0.249642)
							(end -0.2794 -0.1778)
						)
						(arc
							(start -0.2794 0.1778)
							(mid -0.249642 0.249642)
							(end -0.1778 0.2794)
						)
						(arc
							(start 0.1778 0.2794)
							(mid 0.249642 0.249642)
							(end 0.2794 0.1778)
						)
						(arc
							(start 0.2794 -0.1778)
							(mid 0.249642 -0.249642)
							(end 0.1778 -0.2794)
						)
					)
					(width 0)
					(fill yes)
				)
			)
		)
		(pad "2" smd custom
			(at 0 0.4445 180)
			(size 0.1397 0.1397)
			(layers "F.Cu" "F.Mask" "F.Paste")
			(net "DRV_ACT_6")
			(options
				(clearance outline)
				(anchor circle)
			)
			(primitives
				(gr_poly
					(pts
						(arc
							(start -0.1778 -0.2794)
							(mid -0.249642 -0.249642)
							(end -0.2794 -0.1778)
						)
						(arc
							(start -0.2794 0.1778)
							(mid -0.249642 0.249642)
							(end -0.1778 0.2794)
						)
						(arc
							(start 0.1778 0.2794)
							(mid 0.249642 0.249642)
							(end 0.2794 0.1778)
						)
						(arc
							(start 0.2794 -0.1778)
							(mid 0.249642 -0.249642)
							(end 0.1778 -0.2794)
						)
					)
					(width 0)
					(fill yes)
				)
			)
		)
	)
	(footprint ""
		(layer "F.Cu")
		(at 223.647 -437.261 -90)
		(property "Reference" "D14"
			(at 0 0 270)
			(layer "F.SilkS")
			(hide yes)
			(effects
				(font
					(size 1.27 1.27)
				)
			)
		)
		(property "Value" "NSR0520V2T1G-GP"
			(at 0 -4.690618 270)
			(unlocked yes)
			(layer "F.Fab")
			(hide yes)
			(effects
				(font
					(size 1.016 1.016)
					(thickness 0.1524)
				)
			)
		)
		(property "Device Type" "SOD523AKH28"
			(at 0 -6.214618 270)
			(unlocked yes)
			(layer "F.Fab")
			(hide yes)
			(effects
				(font
					(size 1.016 1.016)
					(thickness 0.1524)
				)
			)
		)
		(duplicate_pad_numbers_are_jumpers no)
		(fp_line
			(start -0.7112 1.7018)
			(end 0.7112 1.7018)
			(stroke
				(width 0.508)
				(type default)
			)
			(layer "F.SilkS")
		)
		(fp_line
			(start 0.7112 1.7018)
			(end 0.7112 0.4699)
			(stroke
				(width 0.508)
				(type default)
			)
			(layer "F.SilkS")
		)
		(fp_line
			(start -0.5334 1.524)
			(end 0.5334 1.524)
			(stroke
				(width 0.1524)
				(type default)
			)
			(layer "F.SilkS")
		)
		(fp_line
			(start 0.5334 1.524)
			(end 0.5334 -1.524)
			(stroke
				(width 0.1524)
				(type default)
			)
			(layer "F.SilkS")
		)
		(fp_line
			(start -0.7112 0.4699)
			(end -0.7112 1.7018)
			(stroke
				(width 0.508)
				(type default)
			)
			(layer "F.SilkS")
		)
		(fp_line
			(start -0.5334 -1.524)
			(end -0.5334 1.524)
			(stroke
				(width 0.1524)
				(type default)
			)
			(layer "F.SilkS")
		)
		(fp_line
			(start -0.5334 -1.524)
			(end 0.5334 -1.524)
			(stroke
				(width 0.1524)
				(type default)
			)
			(layer "F.SilkS")
		)
		(fp_poly
			(pts
				(xy -0.1524 0.8001) (xy -0.1524 0.5969) (xy -0.4064 0.5969) (xy -0.4064 -0.5969) (xy -0.1524 -0.5969)
				(xy -0.1524 -0.8001) (xy 0.1524 -0.8001) (xy 0.1524 -0.5969) (xy 0.4064 -0.5969) (xy 0.4064 0.5969)
				(xy 0.1524 0.5969) (xy 0.1524 0.8001)
			)
			(stroke
				(width 0)
				(type default)
			)
			(fill no)
			(layer "F.CrtYd")
		)
		(fp_poly
			(pts
				(xy -0.6096 1.6002) (xy -0.6096 -1.6002) (xy 0.6096 -1.6002) (xy 0.6096 -0.1397) (xy 0.4064 -0.1397)
				(xy 0.4064 -0.5969) (xy 0.1524 -0.5969) (xy 0.1524 -0.8001) (xy -0.1524 -0.8001) (xy -0.1524 -0.5969)
				(xy -0.4064 -0.5969) (xy -0.4064 0.5969) (xy -0.1524 0.5969) (xy -0.1524 0.8001) (xy 0.1524 0.8001)
				(xy 0.1524 0.5969) (xy 0.4064 0.5969) (xy 0.4064 -0.127) (xy 0.6096 -0.127) (xy 0.6096 1.6002)
			)
			(stroke
				(width 0)
				(type default)
			)
			(fill no)
			(layer "F.CrtYd")
		)
		(fp_rect
			(start -0.6096 1.6002)
			(end 0.6096 -1.6002)
			(stroke
				(width 0)
				(type default)
			)
			(fill no)
			(layer "F.Fab")
		)
		(pad "A" smd rect
			(at 0 -0.762 270)
			(size 0.5588 1.016)
			(layers "F.Cu" "F.Mask" "F.Paste")
			(net "P3V3_EN")
		)
		(pad "K" smd rect
			(at 0 0.762 270)
			(size 0.5588 1.016)
			(layers "F.Cu" "F.Mask" "F.Paste")
			(net "P3V3_IN")
		)
	)
	(footprint ""
		(layer "F.Cu")
		(at 189.865 -292.989)
		(property "Reference" "R137"
			(at 0 0 0)
			(layer "F.SilkS")
			(hide yes)
			(effects
				(font
					(size 1.27 1.27)
				)
			)
		)
		(property "Value" "200KR2F-L-GP"
			(at 0.064008 -3.993896 0)
			(unlocked yes)
			(layer "F.Fab")
			(hide yes)
			(effects
				(font
					(size 1.016 1.016)
					(thickness 0.1524)
				)
			)
		)
		(property "Device Type" "R402H16"
			(at 0.064008 -5.517896 0)
			(unlocked yes)
			(layer "F.Fab")
			(hide yes)
			(effects
				(font
					(size 1.016 1.016)
					(thickness 0.1524)
				)
			)
		)
		(duplicate_pad_numbers_are_jumpers no)
		(fp_line
			(start -0.508 -0.9398)
			(end -0.508 0.9398)
			(stroke
				(width 0.1524)
				(type default)
			)
			(layer "F.SilkS")
		)
		(fp_line
			(start 0.508 -0.9398)
			(end -0.508 -0.9398)
			(stroke
				(width 0.1524)
				(type default)
			)
			(layer "F.SilkS")
		)
		(fp_rect
			(start -0.508 0.9398)
			(end 0.508 -0.9398)
			(stroke
				(width 0)
				(type default)
			)
			(fill no)
			(layer "F.CrtYd")
		)
		(fp_rect
			(start -0.508 0.9398)
			(end 0.508 -0.9398)
			(stroke
				(width 0)
				(type default)
			)
			(fill no)
			(layer "F.Fab")
		)
		(pad "1" smd custom
			(at 0 -0.4445)
			(size 0.1397 0.1397)
			(layers "F.Cu" "F.Mask" "F.Paste")
			(net "P12V")
			(options
				(clearance outline)
				(anchor circle)
			)
			(primitives
				(gr_poly
					(pts
						(arc
							(start -0.1778 -0.2794)
							(mid -0.249642 -0.249642)
							(end -0.2794 -0.1778)
						)
						(arc
							(start -0.2794 0.1778)
							(mid -0.249642 0.249642)
							(end -0.1778 0.2794)
						)
						(arc
							(start 0.1778 0.2794)
							(mid 0.249642 0.249642)
							(end 0.2794 0.1778)
						)
						(arc
							(start 0.2794 -0.1778)
							(mid 0.249642 -0.249642)
							(end 0.1778 -0.2794)
						)
					)
					(width 0)
					(fill yes)
				)
			)
		)
		(pad "2" smd custom
			(at 0 0.4445)
			(size 0.1397 0.1397)
			(layers "F.Cu" "F.Mask" "F.Paste")
			(net "SW_HDD2_P")
			(options
				(clearance outline)
				(anchor circle)
			)
			(primitives
				(gr_poly
					(pts
						(arc
							(start -0.1778 -0.2794)
							(mid -0.249642 -0.249642)
							(end -0.2794 -0.1778)
						)
						(arc
							(start -0.2794 0.1778)
							(mid -0.249642 0.249642)
							(end -0.1778 0.2794)
						)
						(arc
							(start 0.1778 0.2794)
							(mid 0.249642 0.249642)
							(end 0.2794 0.1778)
						)
						(arc
							(start 0.2794 -0.1778)
							(mid 0.249642 -0.249642)
							(end 0.1778 -0.2794)
						)
					)
					(width 0)
					(fill yes)
				)
			)
		)
	)
	(footprint ""
		(layer "F.Cu")
		(at 9.651746 -488.0737 -90)
		(property "Reference" "PC33"
			(at 0 0 270)
			(layer "F.SilkS")
			(hide yes)
			(effects
				(font
					(size 1.27 1.27)
				)
			)
		)
		(property "Value" "SC2200P50V2KX-2GP"
			(at 1.1811 -2.7051 270)
			(unlocked yes)
			(layer "F.Fab")
			(hide yes)
			(effects
				(font
					(size 1.016 1.016)
					(thickness 0.1524)
				)
			)
		)
		(property "Device Type" "C402H22"
			(at 1.1811 -4.2291 270)
			(unlocked yes)
			(layer "F.Fab")
			(hide yes)
			(effects
				(font
					(size 1.016 1.016)
					(thickness 0.1524)
				)
			)
		)
		(duplicate_pad_numbers_are_jumpers no)
		(fp_rect
			(start -0.4318 0.9525)
			(end 0.4318 -0.9525)
			(stroke
				(width 0)
				(type default)
			)
			(fill no)
			(layer "F.CrtYd")
		)
		(fp_rect
			(start -0.4318 0.9525)
			(end 0.4318 -0.9525)
			(stroke
				(width 0)
				(type default)
			)
			(fill no)
			(layer "F.Fab")
		)
		(pad "1" smd custom
			(at 0 -0.4445 270)
			(size 0.1524 0.1524)
			(layers "F.Cu" "F.Mask" "F.Paste")
			(net "P5VC_LL")
			(options
				(clearance outline)
				(anchor circle)
			)
			(primitives
				(gr_poly
					(pts
						(arc
							(start 0.3048 -0.2032)
							(mid 0.275042 -0.275042)
							(end 0.2032 -0.3048)
						)
						(arc
							(start -0.2032 -0.3048)
							(mid -0.275042 -0.275042)
							(end -0.3048 -0.2032)
						)
						(arc
							(start -0.3048 0.2032)
							(mid -0.275042 0.275042)
							(end -0.2032 0.3048)
						)
						(arc
							(start 0.2032 0.3048)
							(mid 0.275042 0.275042)
							(end 0.3048 0.2032)
						)
					)
					(width 0)
					(fill yes)
				)
			)
		)
		(pad "2" smd custom
			(at 0 0.4445 270)
			(size 0.1524 0.1524)
			(layers "F.Cu" "F.Mask" "F.Paste")
			(net "P5VC_SNB")
			(options
				(clearance outline)
				(anchor circle)
			)
			(primitives
				(gr_poly
					(pts
						(arc
							(start 0.3048 -0.2032)
							(mid 0.275042 -0.275042)
							(end 0.2032 -0.3048)
						)
						(arc
							(start -0.2032 -0.3048)
							(mid -0.275042 -0.275042)
							(end -0.3048 -0.2032)
						)
						(arc
							(start -0.3048 0.2032)
							(mid -0.275042 0.275042)
							(end -0.2032 0.3048)
						)
						(arc
							(start 0.2032 0.3048)
							(mid 0.275042 0.275042)
							(end 0.3048 0.2032)
						)
					)
					(width 0)
					(fill yes)
				)
			)
		)
	)
	(footprint ""
		(layer "F.Cu")
		(at 34.925 -303.784 90)
		(property "Reference" "D26"
			(at 0 0 90)
			(layer "F.SilkS")
			(hide yes)
			(effects
				(font
					(size 1.27 1.27)
				)
			)
		)
		(property "Value" "RB551V30-1-GP"
			(at 0 -6.7818 90)
			(unlocked yes)
			(layer "F.Fab")
			(hide yes)
			(effects
				(font
					(size 1.016 1.016)
					(thickness 0.1524)
				)
			)
		)
		(property "Device Type" "SOD323AKH44"
			(at 0 -8.6868 90)
			(unlocked yes)
			(layer "F.Fab")
			(hide yes)
			(effects
				(font
					(size 1.016 1.016)
					(thickness 0.1524)
				)
			)
		)
		(duplicate_pad_numbers_are_jumpers no)
		(fp_line
			(start 0.889 -1.9304)
			(end 0.889 2.159)
			(stroke
				(width 0.1524)
				(type default)
			)
			(layer "F.SilkS")
		)
		(fp_line
			(start -0.889 -1.9304)
			(end 0.889 -1.9304)
			(stroke
				(width 0.1524)
				(type default)
			)
			(layer "F.SilkS")
		)
		(fp_line
			(start 0.762 2.0574)
			(end -0.762 2.0574)
			(stroke
				(width 0.508)
				(type default)
			)
			(layer "F.SilkS")
		)
		(fp_line
			(start 0.889 2.159)
			(end -0.889 2.159)
			(stroke
				(width 0.1524)
				(type default)
			)
			(layer "F.SilkS")
		)
		(fp_line
			(start -0.889 2.159)
			(end -0.889 -1.9304)
			(stroke
				(width 0.1524)
				(type default)
			)
			(layer "F.SilkS")
		)
		(fp_rect
			(start -1.016 2.3114)
			(end 1.016 -2.0066)
			(stroke
				(width 0)
				(type default)
			)
			(fill no)
			(layer "F.CrtYd")
		)
		(fp_poly
			(pts
				(xy -1.016 -2.0066) (xy 1.016 -2.0066) (xy 1.016 2.3114) (xy -1.016 2.3114)
			)
			(stroke
				(width 0)
				(type default)
			)
			(fill no)
			(layer "F.Fab")
		)
		(pad "A" smd rect
			(at 0 -1.143 90)
			(size 0.5588 1.016)
			(layers "F.Cu" "F.Mask" "F.Paste")
			(net "SW_HDD11_R")
		)
		(pad "K" smd rect
			(at 0 1.143 90)
			(size 0.5588 1.016)
			(layers "F.Cu" "F.Mask" "F.Paste")
			(net "SW_HDD11_N")
		)
	)
	(footprint ""
		(layer "F.Cu")
		(at 26.161746 -298.9707 180)
		(property "Reference" "C224"
			(at 0 0 180)
			(layer "F.SilkS")
			(hide yes)
			(effects
				(font
					(size 1.27 1.27)
				)
			)
		)
		(property "Value" "SC10U25V6KX-1GP"
			(at -0.0762 -5.1308 180)
			(unlocked yes)
			(layer "F.Fab")
			(hide yes)
			(effects
				(font
					(size 1.016 1.016)
					(thickness 0.1524)
				)
			)
		)
		(property "Device Type" "C1206H71"
			(at -0.127 -6.6548 180)
			(unlocked yes)
			(layer "F.Fab")
			(hide yes)
			(effects
				(font
					(size 1.016 1.016)
					(thickness 0.1524)
				)
			)
		)
		(duplicate_pad_numbers_are_jumpers no)
		(fp_line
			(start 1.016 2.2352)
			(end -1.016 2.2352)
			(stroke
				(width 0.1524)
				(type default)
			)
			(layer "F.SilkS")
		)
		(fp_line
			(start 1.016 0.8382)
			(end 1.016 2.2352)
			(stroke
				(width 0.1524)
				(type default)
			)
			(layer "F.SilkS")
		)
		(fp_line
			(start 1.016 -2.2352)
			(end 1.016 -0.8382)
			(stroke
				(width 0.1524)
				(type default)
			)
			(layer "F.SilkS")
		)
		(fp_line
			(start -1.016 2.2352)
			(end -1.016 0.8382)
			(stroke
				(width 0.1524)
				(type default)
			)
			(layer "F.SilkS")
		)
		(fp_line
			(start -1.016 -0.8382)
			(end -1.016 -2.2352)
			(stroke
				(width 0.1524)
				(type default)
			)
			(layer "F.SilkS")
		)
		(fp_line
			(start -1.016 -2.2352)
			(end 1.016 -2.2352)
			(stroke
				(width 0.1524)
				(type default)
			)
			(layer "F.SilkS")
		)
		(fp_rect
			(start -1.0922 2.3114)
			(end 1.0922 -2.3114)
			(stroke
				(width 0)
				(type default)
			)
			(fill no)
			(layer "F.CrtYd")
		)
		(fp_poly
			(pts
				(xy 1.0922 -2.3114) (xy 1.0922 2.3114) (xy -1.0922 2.3114) (xy -1.0922 -2.3114)
			)
			(stroke
				(width 0)
				(type default)
			)
			(fill no)
			(layer "F.Fab")
		)
		(pad "1" smd rect
			(at 0 -1.397 180)
			(size 1.651 1.27)
			(layers "F.Cu" "F.Mask" "F.Paste")
			(net "P12V_HDD7")
		)
		(pad "2" smd rect
			(at 0 1.397 180)
			(size 1.651 1.27)
			(layers "F.Cu" "F.Mask" "F.Paste")
			(net "GND")
		)
	)
	(footprint ""
		(layer "F.Cu")
		(at 17.855946 -165.5826 90)
		(property "Reference" "Q47"
			(at 0 0 90)
			(layer "F.SilkS")
			(hide yes)
			(effects
				(font
					(size 1.27 1.27)
				)
			)
		)
		(property "Value" "PMBS3904-1-GP"
			(at 0 -9.0932 90)
			(unlocked yes)
			(layer "F.Fab")
			(hide yes)
			(effects
				(font
					(size 1.016 1.016)
					(thickness 0.1524)
				)
			)
		)
		(property "Device Type" "SOT-23-10H44"
			(at 0 -10.6172 90)
			(unlocked yes)
			(layer "F.Fab")
			(hide yes)
			(effects
				(font
					(size 1.016 1.016)
					(thickness 0.1524)
				)
			)
		)
		(duplicate_pad_numbers_are_jumpers no)
		(fp_line
			(start 1.651 -1.778)
			(end -1.651 -1.778)
			(stroke
				(width 0.1524)
				(type default)
			)
			(layer "F.SilkS")
		)
		(fp_line
			(start -1.651 -1.778)
			(end -1.651 1.778)
			(stroke
				(width 0.1524)
				(type default)
			)
			(layer "F.SilkS")
		)
		(fp_line
			(start 1.651 1.778)
			(end 1.651 -1.778)
			(stroke
				(width 0.1524)
				(type default)
			)
			(layer "F.SilkS")
		)
		(fp_line
			(start -1.651 1.778)
			(end 1.651 1.778)
			(stroke
				(width 0.1524)
				(type default)
			)
			(layer "F.SilkS")
		)
		(fp_line
			(start -0.9906 1.86309)
			(end -0.701294 2.15265)
			(stroke
				(width 0.0127)
				(type default)
			)
			(layer "F.SilkS")
		)
		(fp_line
			(start -0.994156 1.8669)
			(end -0.987044 1.8669)
			(stroke
				(width 0.0127)
				(type default)
			)
			(layer "F.SilkS")
		)
		(fp_line
			(start -1.003808 1.876552)
			(end -0.977646 1.876552)
			(stroke
				(width 0.0127)
				(type default)
			)
			(layer "F.SilkS")
		)
		(fp_line
			(start -0.635 1.8796)
			(end -1.7526 1.8796)
			(stroke
				(width 0.3302)
				(type default)
			)
			(layer "F.SilkS")
		)
		(fp_line
			(start -1.7526 1.8796)
			(end -1.7526 0.9906)
			(stroke
				(width 0.3302)
				(type default)
			)
			(layer "F.SilkS")
		)
		(fp_line
			(start -1.013206 1.88595)
			(end -0.967994 1.88595)
			(stroke
				(width 0.0127)
				(type default)
			)
			(layer "F.SilkS")
		)
		(fp_line
			(start -1.022858 1.895602)
			(end -0.958596 1.895602)
			(stroke
				(width 0.0127)
				(type default)
			)
			(layer "F.SilkS")
		)
		(fp_line
			(start -1.032256 1.905)
			(end -0.948944 1.905)
			(stroke
				(width 0.0127)
				(type default)
			)
			(layer "F.SilkS")
		)
		(fp_line
			(start -1.041908 1.914652)
			(end -0.939546 1.914652)
			(stroke
				(width 0.0127)
				(type default)
			)
			(layer "F.SilkS")
		)
		(fp_line
			(start -1.051306 1.92405)
			(end -0.929894 1.92405)
			(stroke
				(width 0.0127)
				(type default)
			)
			(layer "F.SilkS")
		)
		(fp_line
			(start -1.060958 1.933702)
			(end -0.920496 1.933702)
			(stroke
				(width 0.0127)
				(type default)
			)
			(layer "F.SilkS")
		)
		(fp_line
			(start -1.070356 1.9431)
			(end -0.910844 1.9431)
			(stroke
				(width 0.0127)
				(type default)
			)
			(layer "F.SilkS")
		)
		(fp_line
			(start -1.080008 1.952752)
			(end -0.901446 1.952752)
			(stroke
				(width 0.0127)
				(type default)
			)
			(layer "F.SilkS")
		)
		(fp_line
			(start -1.089406 1.96215)
			(end -0.891794 1.96215)
			(stroke
				(width 0.0127)
				(type default)
			)
			(layer "F.SilkS")
		)
		(fp_line
			(start -1.099058 1.971802)
			(end -0.882396 1.971802)
			(stroke
				(width 0.0127)
				(type default)
			)
			(layer "F.SilkS")
		)
		(fp_line
			(start -1.108456 1.9812)
			(end -0.872744 1.9812)
			(stroke
				(width 0.0127)
				(type default)
			)
			(layer "F.SilkS")
		)
		(fp_line
			(start -1.118108 1.990852)
			(end -0.863346 1.990852)
			(stroke
				(width 0.0127)
				(type default)
			)
			(layer "F.SilkS")
		)
		(fp_line
			(start -1.127506 2.00025)
			(end -0.853694 2.00025)
			(stroke
				(width 0.0127)
				(type default)
			)
			(layer "F.SilkS")
		)
		(fp_line
			(start -1.137158 2.009902)
			(end -0.844296 2.009902)
			(stroke
				(width 0.0127)
				(type default)
			)
			(layer "F.SilkS")
		)
		(fp_line
			(start -1.146556 2.0193)
			(end -0.834644 2.0193)
			(stroke
				(width 0.0127)
				(type default)
			)
			(layer "F.SilkS")
		)
		(fp_line
			(start -1.156208 2.028952)
			(end -0.825246 2.028952)
			(stroke
				(width 0.0127)
				(type default)
			)
			(layer "F.SilkS")
		)
		(fp_line
			(start -1.165606 2.03835)
			(end -0.815594 2.03835)
			(stroke
				(width 0.0127)
				(type default)
			)
			(layer "F.SilkS")
		)
		(fp_line
			(start -1.175258 2.048002)
			(end -0.806196 2.048002)
			(stroke
				(width 0.0127)
				(type default)
			)
			(layer "F.SilkS")
		)
		(fp_line
			(start -1.184656 2.0574)
			(end -0.796544 2.0574)
			(stroke
				(width 0.0127)
				(type default)
			)
			(layer "F.SilkS")
		)
		(fp_line
			(start -1.194308 2.067052)
			(end -0.787146 2.067052)
			(stroke
				(width 0.0127)
				(type default)
			)
			(layer "F.SilkS")
		)
		(fp_line
			(start -1.203706 2.07645)
			(end -0.777494 2.07645)
			(stroke
				(width 0.0127)
				(type default)
			)
			(layer "F.SilkS")
		)
		(fp_line
			(start -1.213358 2.086102)
			(end -0.768096 2.086102)
			(stroke
				(width 0.0127)
				(type default)
			)
			(layer "F.SilkS")
		)
		(fp_line
			(start -1.222756 2.0955)
			(end -0.758444 2.0955)
			(stroke
				(width 0.0127)
				(type default)
			)
			(layer "F.SilkS")
		)
		(fp_line
			(start -1.232408 2.105152)
			(end -0.749046 2.105152)
			(stroke
				(width 0.0127)
				(type default)
			)
			(layer "F.SilkS")
		)
		(fp_line
			(start -1.241806 2.11455)
			(end -0.739394 2.11455)
			(stroke
				(width 0.0127)
				(type default)
			)
			(layer "F.SilkS")
		)
		(fp_line
			(start -1.251458 2.124202)
			(end -0.729996 2.124202)
			(stroke
				(width 0.0127)
				(type default)
			)
			(layer "F.SilkS")
		)
		(fp_line
			(start -1.260856 2.1336)
			(end -0.720344 2.1336)
			(stroke
				(width 0.0127)
				(type default)
			)
			(layer "F.SilkS")
		)
		(fp_line
			(start -0.719074 2.145538)
			(end -1.265936 2.14122)
			(stroke
				(width 0.0127)
				(type default)
			)
			(layer "F.SilkS")
		)
		(fp_line
			(start -1.279398 2.152142)
			(end -0.9906 1.86309)
			(stroke
				(width 0.0127)
				(type default)
			)
			(layer "F.SilkS")
		)
		(fp_line
			(start -0.71628 2.15265)
			(end -1.26492 2.15265)
			(stroke
				(width 0.0127)
				(type default)
			)
			(layer "F.SilkS")
		)
		(fp_line
			(start -1.279144 2.15265)
			(end -0.701294 2.15265)
			(stroke
				(width 0.0127)
				(type default)
			)
			(layer "F.SilkS")
		)
		(fp_poly
			(pts
				(xy -1.285748 2.159) (xy -1.285748 1.8796) (xy -1.778 1.8796) (xy -1.778 -1.8796) (xy 1.778 -1.8796)
				(xy 1.778 1.8796) (xy -0.694944 1.8796) (xy -0.694944 2.159)
			)
			(stroke
				(width 0)
				(type default)
			)
			(fill no)
			(layer "F.CrtYd")
		)
		(fp_poly
			(pts
				(xy -1.285748 2.159) (xy -1.285748 1.8796) (xy -1.778 1.8796) (xy -1.778 -1.8796) (xy 1.778 -1.8796)
				(xy 1.778 1.8796) (xy -0.694944 1.8796) (xy -0.694944 2.159)
			)
			(stroke
				(width 0)
				(type default)
			)
			(fill no)
			(layer "F.Fab")
		)
		(pad "1" smd rect
			(at -0.98425 0.9525 90)
			(size 0.762 1.143)
			(layers "F.Cu" "F.Mask" "F.Paste")
			(net "FLT_HDD13_B")
		)
		(pad "2" smd rect
			(at 0.98425 0.9525 90)
			(size 0.762 1.143)
			(layers "F.Cu" "F.Mask" "F.Paste")
			(net "GND")
		)
		(pad "3" smd rect
			(at 0 -0.9525 90)
			(size 0.762 1.143)
			(layers "F.Cu" "F.Mask" "F.Paste")
			(net "DRIVE_ACT_13")
		)
	)
	(footprint ""
		(layer "F.Cu")
		(at 46.481746 -24.1427 -90)
		(property "Reference" "PR24"
			(at 0 0 270)
			(layer "F.SilkS")
			(hide yes)
			(effects
				(font
					(size 1.27 1.27)
				)
			)
		)
		(property "Value" "0R3J-0-U-GP"
			(at -0.0254 -2.5146 270)
			(unlocked yes)
			(layer "F.Fab")
			(hide yes)
			(effects
				(font
					(size 1.016 1.016)
					(thickness 0.1524)
				)
			)
		)
		(property "Device Type" "R603H22"
			(at -0.0254 -4.0386 270)
			(unlocked yes)
			(layer "F.Fab")
			(hide yes)
			(effects
				(font
					(size 1.016 1.016)
					(thickness 0.1524)
				)
			)
		)
		(duplicate_pad_numbers_are_jumpers no)
		(fp_line
			(start -0.4826 0)
			(end -0.2032 0)
			(stroke
				(width 0.2032)
				(type default)
			)
			(layer "F.SilkS")
		)
		(fp_line
			(start 0.2032 0)
			(end 0.4826 0)
			(stroke
				(width 0.2032)
				(type default)
			)
			(layer "F.SilkS")
		)
		(fp_rect
			(start -0.5842 1.3335)
			(end 0.5842 -1.3335)
			(stroke
				(width 0)
				(type default)
			)
			(fill no)
			(layer "F.CrtYd")
		)
		(fp_rect
			(start -0.5842 1.3335)
			(end 0.5842 -1.3335)
			(stroke
				(width 0)
				(type default)
			)
			(fill no)
			(layer "F.Fab")
		)
		(pad "1" smd custom
			(at 0 -0.762 270)
			(size 0.2159 0.2159)
			(layers "F.Cu" "F.Mask" "F.Paste")
			(net "P5VB_VBST")
			(options
				(clearance outline)
				(anchor circle)
			)
			(primitives
				(gr_poly
					(pts
						(arc
							(start -0.3302 -0.4318)
							(mid -0.402042 -0.402042)
							(end -0.4318 -0.3302)
						)
						(arc
							(start -0.4318 0.3302)
							(mid -0.402042 0.402042)
							(end -0.3302 0.4318)
						)
						(arc
							(start 0.3302 0.4318)
							(mid 0.402042 0.402042)
							(end 0.4318 0.3302)
						)
						(arc
							(start 0.4318 -0.3302)
							(mid 0.402042 -0.402042)
							(end 0.3302 -0.4318)
						)
					)
					(width 0)
					(fill yes)
				)
			)
		)
		(pad "2" smd custom
			(at 0 0.762 270)
			(size 0.2159 0.2159)
			(layers "F.Cu" "F.Mask" "F.Paste")
			(net "P5VB_VBST_NET")
			(options
				(clearance outline)
				(anchor circle)
			)
			(primitives
				(gr_poly
					(pts
						(arc
							(start -0.3302 -0.4318)
							(mid -0.402042 -0.402042)
							(end -0.4318 -0.3302)
						)
						(arc
							(start -0.4318 0.3302)
							(mid -0.402042 0.402042)
							(end -0.3302 0.4318)
						)
						(arc
							(start 0.3302 0.4318)
							(mid 0.402042 0.402042)
							(end 0.4318 0.3302)
						)
						(arc
							(start 0.4318 -0.3302)
							(mid 0.402042 -0.402042)
							(end 0.3302 -0.4318)
						)
					)
					(width 0)
					(fill yes)
				)
			)
		)
	)
	(footprint ""
		(layer "F.Cu")
		(at 55.498746 -183.4007 180)
		(property "Reference" "C236"
			(at 0 0 180)
			(layer "F.SilkS")
			(hide yes)
			(effects
				(font
					(size 1.27 1.27)
				)
			)
		)
		(property "Value" "SC1U16V3KX-5GP"
			(at 0 -2.8194 180)
			(unlocked yes)
			(layer "F.Fab")
			(hide yes)
			(effects
				(font
					(size 1.016 1.016)
					(thickness 0.1524)
				)
			)
		)
		(property "Device Type" "C603H36"
			(at 0 -4.3434 180)
			(unlocked yes)
			(layer "F.Fab")
			(hide yes)
			(effects
				(font
					(size 1.016 1.016)
					(thickness 0.1524)
				)
			)
		)
		(duplicate_pad_numbers_are_jumpers no)
		(fp_line
			(start 0.508 0)
			(end -0.508 0)
			(stroke
				(width 0.2032)
				(type default)
			)
			(layer "F.SilkS")
		)
		(fp_rect
			(start -0.5842 1.3335)
			(end 0.5842 -1.3335)
			(stroke
				(width 0)
				(type default)
			)
			(fill no)
			(layer "F.CrtYd")
		)
		(fp_rect
			(start -0.5842 1.3335)
			(end 0.5842 -1.3335)
			(stroke
				(width 0)
				(type default)
			)
			(fill no)
			(layer "F.Fab")
		)
		(pad "1" smd custom
			(at 0 -0.762 180)
			(size 0.2159 0.2159)
			(layers "F.Cu" "F.Mask" "F.Paste")
			(net "P5V_HDD8")
			(options
				(clearance outline)
				(anchor circle)
			)
			(primitives
				(gr_poly
					(pts
						(arc
							(start -0.3302 -0.4318)
							(mid -0.402042 -0.402042)
							(end -0.4318 -0.3302)
						)
						(arc
							(start -0.4318 0.3302)
							(mid -0.402042 0.402042)
							(end -0.3302 0.4318)
						)
						(arc
							(start 0.3302 0.4318)
							(mid 0.402042 0.402042)
							(end 0.4318 0.3302)
						)
						(arc
							(start 0.4318 -0.3302)
							(mid 0.402042 -0.402042)
							(end 0.3302 -0.4318)
						)
					)
					(width 0)
					(fill yes)
				)
			)
		)
		(pad "2" smd custom
			(at 0 0.762 180)
			(size 0.2159 0.2159)
			(layers "F.Cu" "F.Mask" "F.Paste")
			(net "GND")
			(options
				(clearance outline)
				(anchor circle)
			)
			(primitives
				(gr_poly
					(pts
						(arc
							(start -0.3302 -0.4318)
							(mid -0.402042 -0.402042)
							(end -0.4318 -0.3302)
						)
						(arc
							(start -0.4318 0.3302)
							(mid -0.402042 0.402042)
							(end -0.3302 0.4318)
						)
						(arc
							(start 0.3302 0.4318)
							(mid 0.402042 0.402042)
							(end 0.4318 0.3302)
						)
						(arc
							(start 0.4318 -0.3302)
							(mid 0.402042 -0.402042)
							(end 0.3302 -0.4318)
						)
					)
					(width 0)
					(fill yes)
				)
			)
		)
	)
	(footprint ""
		(layer "F.Cu")
		(at 26.55443 -242.948206 90)
		(property "Reference" "C294"
			(at 0 0 90)
			(layer "F.SilkS")
			(hide yes)
			(effects
				(font
					(size 1.27 1.27)
				)
			)
		)
		(property "Value" "SCD01U50V2KX-1GP"
			(at 1.1811 -2.7051 90)
			(unlocked yes)
			(layer "F.Fab")
			(hide yes)
			(effects
				(font
					(size 1.016 1.016)
					(thickness 0.1524)
				)
			)
		)
		(property "Device Type" "C402H22"
			(at 1.1811 -4.2291 90)
			(unlocked yes)
			(layer "F.Fab")
			(hide yes)
			(effects
				(font
					(size 1.016 1.016)
					(thickness 0.1524)
				)
			)
		)
		(duplicate_pad_numbers_are_jumpers no)
		(fp_rect
			(start -0.4318 0.9525)
			(end 0.4318 -0.9525)
			(stroke
				(width 0)
				(type default)
			)
			(fill no)
			(layer "F.CrtYd")
		)
		(fp_rect
			(start -0.4318 0.9525)
			(end 0.4318 -0.9525)
			(stroke
				(width 0)
				(type default)
			)
			(fill no)
			(layer "F.Fab")
		)
		(pad "1" smd custom
			(at 0 -0.4445 90)
			(size 0.1524 0.1524)
			(layers "F.Cu" "F.Mask" "F.Paste")
			(net "SAS2X28_DRIVE_RX_N_A12")
			(options
				(clearance outline)
				(anchor circle)
			)
			(primitives
				(gr_poly
					(pts
						(arc
							(start 0.3048 -0.2032)
							(mid 0.275042 -0.275042)
							(end 0.2032 -0.3048)
						)
						(arc
							(start -0.2032 -0.3048)
							(mid -0.275042 -0.275042)
							(end -0.3048 -0.2032)
						)
						(arc
							(start -0.3048 0.2032)
							(mid -0.275042 0.275042)
							(end -0.2032 0.3048)
						)
						(arc
							(start 0.2032 0.3048)
							(mid 0.275042 0.275042)
							(end 0.3048 0.2032)
						)
					)
					(width 0)
					(fill yes)
				)
			)
		)
		(pad "2" smd custom
			(at 0 0.4445 90)
			(size 0.1524 0.1524)
			(layers "F.Cu" "F.Mask" "F.Paste")
			(net "SAS2X28_A_HDD12_RX_-")
			(options
				(clearance outline)
				(anchor circle)
			)
			(primitives
				(gr_poly
					(pts
						(arc
							(start 0.3048 -0.2032)
							(mid 0.275042 -0.275042)
							(end 0.2032 -0.3048)
						)
						(arc
							(start -0.2032 -0.3048)
							(mid -0.275042 -0.275042)
							(end -0.3048 -0.2032)
						)
						(arc
							(start -0.3048 0.2032)
							(mid -0.275042 0.275042)
							(end -0.2032 0.3048)
						)
						(arc
							(start 0.2032 0.3048)
							(mid 0.275042 0.275042)
							(end 0.3048 0.2032)
						)
					)
					(width 0)
					(fill yes)
				)
			)
		)
	)
	(footprint ""
		(layer "F.Cu")
		(at 81.279746 -188.8617 -90)
		(property "Reference" "U27"
			(at 0 0 270)
			(layer "F.SilkS")
			(hide yes)
			(effects
				(font
					(size 1.27 1.27)
				)
			)
		)
		(property "Value" "74LVC1G08GW-1-GP"
			(at -2.3368 -8.6868 270)
			(unlocked yes)
			(layer "F.Fab")
			(hide yes)
			(effects
				(font
					(size 1.016 1.016)
					(thickness 0.1524)
				)
			)
		)
		(property "Device Type" "SC70-5H44"
			(at -2.3114 -10.414 270)
			(unlocked yes)
			(layer "F.Fab")
			(hide yes)
			(effects
				(font
					(size 1.016 1.016)
					(thickness 0.1524)
				)
			)
		)
		(duplicate_pad_numbers_are_jumpers no)
		(fp_line
			(start -1.27 1.7018)
			(end -1.27 -1.7018)
			(stroke
				(width 0.1524)
				(type default)
			)
			(layer "F.SilkS")
		)
		(fp_line
			(start 1.27 1.7018)
			(end -1.27 1.7018)
			(stroke
				(width 0.1524)
				(type default)
			)
			(layer "F.SilkS")
		)
		(fp_line
			(start -1.27 -1.7018)
			(end 1.27 -1.7018)
			(stroke
				(width 0.1524)
				(type default)
			)
			(layer "F.SilkS")
		)
		(fp_line
			(start 1.27 -1.7018)
			(end 1.27 1.7018)
			(stroke
				(width 0.1524)
				(type default)
			)
			(layer "F.SilkS")
		)
		(fp_line
			(start 0.6604 -1.8034)
			(end 1.3843 -1.8034)
			(stroke
				(width 0.3302)
				(type default)
			)
			(layer "F.SilkS")
		)
		(fp_line
			(start 1.3843 -1.8034)
			(end 1.3843 -1.1176)
			(stroke
				(width 0.3302)
				(type default)
			)
			(layer "F.SilkS")
		)
		(fp_rect
			(start -1.524 1.9558)
			(end 1.524 -1.9558)
			(stroke
				(width 0)
				(type default)
			)
			(fill no)
			(layer "F.CrtYd")
		)
		(fp_poly
			(pts
				(xy -1.524 -1.9558) (xy 1.524 -1.9558) (xy 1.524 1.9558) (xy -1.524 1.9558)
			)
			(stroke
				(width 0)
				(type default)
			)
			(fill no)
			(layer "F.Fab")
		)
		(pad "1" smd rect
			(at 0.65024 -0.8255 270)
			(size 0.4064 1.2192)
			(layers "F.Cu" "F.Mask" "F.Paste")
			(net "SAS_EXP_B_PWR8")
		)
		(pad "2" smd rect
			(at 0 -0.8255 270)
			(size 0.4064 1.2192)
			(layers "F.Cu" "F.Mask" "F.Paste")
			(net "SAS_EXP_A_PWR8")
		)
		(pad "3" smd rect
			(at -0.65024 -0.8255 270)
			(size 0.4064 1.2192)
			(layers "F.Cu" "F.Mask" "F.Paste")
			(net "GND")
		)
		(pad "4" smd rect
			(at -0.65024 0.8255 270)
			(size 0.4064 1.2192)
			(layers "F.Cu" "F.Mask" "F.Paste")
			(net "DRIVE_PWR8")
		)
		(pad "5" smd rect
			(at 0.65024 0.8255 270)
			(size 0.4064 1.2192)
			(layers "F.Cu" "F.Mask" "F.Paste")
			(net "P3V3")
		)
	)
	(footprint ""
		(layer "F.Cu")
		(at 187.464446 -460.790036 90)
		(property "Reference" "R345"
			(at 0 0 90)
			(layer "F.SilkS")
			(hide yes)
			(effects
				(font
					(size 1.27 1.27)
				)
			)
		)
		(property "Value" "4K7R2J-2-GP"
			(at 0.064008 -3.993896 90)
			(unlocked yes)
			(layer "F.Fab")
			(hide yes)
			(effects
				(font
					(size 1.016 1.016)
					(thickness 0.1524)
				)
			)
		)
		(property "Device Type" "R402H16"
			(at 0.064008 -5.517896 90)
			(unlocked yes)
			(layer "F.Fab")
			(hide yes)
			(effects
				(font
					(size 1.016 1.016)
					(thickness 0.1524)
				)
			)
		)
		(duplicate_pad_numbers_are_jumpers no)
		(fp_line
			(start 0.508 -0.9398)
			(end -0.508 -0.9398)
			(stroke
				(width 0.1524)
				(type default)
			)
			(layer "F.SilkS")
		)
		(fp_line
			(start -0.508 -0.9398)
			(end -0.508 0.9398)
			(stroke
				(width 0.1524)
				(type default)
			)
			(layer "F.SilkS")
		)
		(fp_rect
			(start -0.508 0.9398)
			(end 0.508 -0.9398)
			(stroke
				(width 0)
				(type default)
			)
			(fill no)
			(layer "F.CrtYd")
		)
		(fp_rect
			(start -0.508 0.9398)
			(end 0.508 -0.9398)
			(stroke
				(width 0)
				(type default)
			)
			(fill no)
			(layer "F.Fab")
		)
		(pad "1" smd custom
			(at 0 -0.4445 90)
			(size 0.1397 0.1397)
			(layers "F.Cu" "F.Mask" "F.Paste")
			(net "P3V3")
			(options
				(clearance outline)
				(anchor circle)
			)
			(primitives
				(gr_poly
					(pts
						(arc
							(start -0.1778 -0.2794)
							(mid -0.249642 -0.249642)
							(end -0.2794 -0.1778)
						)
						(arc
							(start -0.2794 0.1778)
							(mid -0.249642 0.249642)
							(end -0.1778 0.2794)
						)
						(arc
							(start 0.1778 0.2794)
							(mid 0.249642 0.249642)
							(end 0.2794 0.1778)
						)
						(arc
							(start 0.2794 -0.1778)
							(mid 0.249642 -0.249642)
							(end 0.1778 -0.2794)
						)
					)
					(width 0)
					(fill yes)
				)
			)
		)
		(pad "2" smd custom
			(at 0 0.4445 90)
			(size 0.1397 0.1397)
			(layers "F.Cu" "F.Mask" "F.Paste")
			(net "EEPROM_A0")
			(options
				(clearance outline)
				(anchor circle)
			)
			(primitives
				(gr_poly
					(pts
						(arc
							(start -0.1778 -0.2794)
							(mid -0.249642 -0.249642)
							(end -0.2794 -0.1778)
						)
						(arc
							(start -0.2794 0.1778)
							(mid -0.249642 0.249642)
							(end -0.1778 0.2794)
						)
						(arc
							(start 0.1778 0.2794)
							(mid 0.249642 0.249642)
							(end 0.2794 0.1778)
						)
						(arc
							(start 0.2794 -0.1778)
							(mid 0.249642 -0.249642)
							(end 0.1778 -0.2794)
						)
					)
					(width 0)
					(fill yes)
				)
			)
		)
	)
	(footprint ""
		(layer "F.Cu")
		(at 8.127746 -499.5037)
		(property "Reference" "PR44"
			(at 0 0 0)
			(layer "F.SilkS")
			(hide yes)
			(effects
				(font
					(size 1.27 1.27)
				)
			)
		)
		(property "Value" "0R2J-2-GP"
			(at 0.064008 -3.993896 0)
			(unlocked yes)
			(layer "F.Fab")
			(hide yes)
			(effects
				(font
					(size 1.016 1.016)
					(thickness 0.1524)
				)
			)
		)
		(property "Device Type" "R402H16"
			(at 0.064008 -5.517896 0)
			(unlocked yes)
			(layer "F.Fab")
			(hide yes)
			(effects
				(font
					(size 1.016 1.016)
					(thickness 0.1524)
				)
			)
		)
		(duplicate_pad_numbers_are_jumpers no)
		(fp_line
			(start -0.508 -0.9398)
			(end -0.508 0.9398)
			(stroke
				(width 0.1524)
				(type default)
			)
			(layer "F.SilkS")
		)
		(fp_line
			(start 0.508 -0.9398)
			(end -0.508 -0.9398)
			(stroke
				(width 0.1524)
				(type default)
			)
			(layer "F.SilkS")
		)
		(fp_rect
			(start -0.508 0.9398)
			(end 0.508 -0.9398)
			(stroke
				(width 0)
				(type default)
			)
			(fill no)
			(layer "F.CrtYd")
		)
		(fp_rect
			(start -0.508 0.9398)
			(end 0.508 -0.9398)
			(stroke
				(width 0)
				(type default)
			)
			(fill no)
			(layer "F.Fab")
		)
		(pad "1" smd custom
			(at 0 -0.4445)
			(size 0.1397 0.1397)
			(layers "F.Cu" "F.Mask" "F.Paste")
			(net "P5VC_MODE_PG")
			(options
				(clearance outline)
				(anchor circle)
			)
			(primitives
				(gr_poly
					(pts
						(arc
							(start -0.1778 -0.2794)
							(mid -0.249642 -0.249642)
							(end -0.2794 -0.1778)
						)
						(arc
							(start -0.2794 0.1778)
							(mid -0.249642 0.249642)
							(end -0.1778 0.2794)
						)
						(arc
							(start 0.1778 0.2794)
							(mid 0.249642 0.249642)
							(end 0.2794 0.1778)
						)
						(arc
							(start 0.2794 -0.1778)
							(mid 0.249642 -0.249642)
							(end 0.1778 -0.2794)
						)
					)
					(width 0)
					(fill yes)
				)
			)
		)
		(pad "2" smd custom
			(at 0 0.4445)
			(size 0.1397 0.1397)
			(layers "F.Cu" "F.Mask" "F.Paste")
			(net "P5VC_MODE")
			(options
				(clearance outline)
				(anchor circle)
			)
			(primitives
				(gr_poly
					(pts
						(arc
							(start -0.1778 -0.2794)
							(mid -0.249642 -0.249642)
							(end -0.2794 -0.1778)
						)
						(arc
							(start -0.2794 0.1778)
							(mid -0.249642 0.249642)
							(end -0.1778 0.2794)
						)
						(arc
							(start 0.1778 0.2794)
							(mid 0.249642 0.249642)
							(end 0.2794 0.1778)
						)
						(arc
							(start 0.2794 -0.1778)
							(mid 0.249642 -0.249642)
							(end 0.1778 -0.2794)
						)
					)
					(width 0)
					(fill yes)
				)
			)
		)
	)
	(footprint ""
		(layer "F.Cu")
		(at 217.799412 -64.242696 -90)
		(property "Reference" "C169"
			(at 0 0 270)
			(layer "F.SilkS")
			(hide yes)
			(effects
				(font
					(size 1.27 1.27)
				)
			)
		)
		(property "Value" "SCD01U50V2KX-1GP"
			(at 1.1811 -2.7051 270)
			(unlocked yes)
			(layer "F.Fab")
			(hide yes)
			(effects
				(font
					(size 1.016 1.016)
					(thickness 0.1524)
				)
			)
		)
		(property "Device Type" "C402H22"
			(at 1.1811 -4.2291 270)
			(unlocked yes)
			(layer "F.Fab")
			(hide yes)
			(effects
				(font
					(size 1.016 1.016)
					(thickness 0.1524)
				)
			)
		)
		(duplicate_pad_numbers_are_jumpers no)
		(fp_rect
			(start -0.4318 0.9525)
			(end 0.4318 -0.9525)
			(stroke
				(width 0)
				(type default)
			)
			(fill no)
			(layer "F.CrtYd")
		)
		(fp_rect
			(start -0.4318 0.9525)
			(end 0.4318 -0.9525)
			(stroke
				(width 0)
				(type default)
			)
			(fill no)
			(layer "F.Fab")
		)
		(pad "1" smd custom
			(at 0 -0.4445 270)
			(size 0.1524 0.1524)
			(layers "F.Cu" "F.Mask" "F.Paste")
			(net "SAS2X28_DRIVE_RX_P_B4")
			(options
				(clearance outline)
				(anchor circle)
			)
			(primitives
				(gr_poly
					(pts
						(arc
							(start 0.3048 -0.2032)
							(mid 0.275042 -0.275042)
							(end 0.2032 -0.3048)
						)
						(arc
							(start -0.2032 -0.3048)
							(mid -0.275042 -0.275042)
							(end -0.3048 -0.2032)
						)
						(arc
							(start -0.3048 0.2032)
							(mid -0.275042 0.275042)
							(end -0.2032 0.3048)
						)
						(arc
							(start 0.2032 0.3048)
							(mid 0.275042 0.275042)
							(end 0.3048 0.2032)
						)
					)
					(width 0)
					(fill yes)
				)
			)
		)
		(pad "2" smd custom
			(at 0 0.4445 270)
			(size 0.1524 0.1524)
			(layers "F.Cu" "F.Mask" "F.Paste")
			(net "SAS2X28_B_HDD4_RX_+")
			(options
				(clearance outline)
				(anchor circle)
			)
			(primitives
				(gr_poly
					(pts
						(arc
							(start 0.3048 -0.2032)
							(mid 0.275042 -0.275042)
							(end 0.2032 -0.3048)
						)
						(arc
							(start -0.2032 -0.3048)
							(mid -0.275042 -0.275042)
							(end -0.3048 -0.2032)
						)
						(arc
							(start -0.3048 0.2032)
							(mid -0.275042 0.275042)
							(end -0.2032 0.3048)
						)
						(arc
							(start 0.2032 0.3048)
							(mid 0.275042 0.275042)
							(end 0.3048 0.2032)
						)
					)
					(width 0)
					(fill yes)
				)
			)
		)
	)
	(footprint ""
		(layer "F.Cu")
		(at 41.960546 -133.3119 -90)
		(property "Reference" "R324"
			(at 0 0 270)
			(layer "F.SilkS")
			(hide yes)
			(effects
				(font
					(size 1.27 1.27)
				)
			)
		)
		(property "Value" "4K7R2J-2-GP"
			(at 0.064008 -3.993896 270)
			(unlocked yes)
			(layer "F.Fab")
			(hide yes)
			(effects
				(font
					(size 1.016 1.016)
					(thickness 0.1524)
				)
			)
		)
		(property "Device Type" "R402H16"
			(at 0.064008 -5.517896 270)
			(unlocked yes)
			(layer "F.Fab")
			(hide yes)
			(effects
				(font
					(size 1.016 1.016)
					(thickness 0.1524)
				)
			)
		)
		(duplicate_pad_numbers_are_jumpers no)
		(fp_line
			(start -0.508 -0.9398)
			(end -0.508 0.9398)
			(stroke
				(width 0.1524)
				(type default)
			)
			(layer "F.SilkS")
		)
		(fp_line
			(start 0.508 -0.9398)
			(end -0.508 -0.9398)
			(stroke
				(width 0.1524)
				(type default)
			)
			(layer "F.SilkS")
		)
		(fp_rect
			(start -0.508 0.9398)
			(end 0.508 -0.9398)
			(stroke
				(width 0)
				(type default)
			)
			(fill no)
			(layer "F.CrtYd")
		)
		(fp_rect
			(start -0.508 0.9398)
			(end 0.508 -0.9398)
			(stroke
				(width 0)
				(type default)
			)
			(fill no)
			(layer "F.Fab")
		)
		(pad "1" smd custom
			(at 0 -0.4445 270)
			(size 0.1397 0.1397)
			(layers "F.Cu" "F.Mask" "F.Paste")
			(net "I2C_B_TMP2_A1")
			(options
				(clearance outline)
				(anchor circle)
			)
			(primitives
				(gr_poly
					(pts
						(arc
							(start -0.1778 -0.2794)
							(mid -0.249642 -0.249642)
							(end -0.2794 -0.1778)
						)
						(arc
							(start -0.2794 0.1778)
							(mid -0.249642 0.249642)
							(end -0.1778 0.2794)
						)
						(arc
							(start 0.1778 0.2794)
							(mid 0.249642 0.249642)
							(end 0.2794 0.1778)
						)
						(arc
							(start 0.2794 -0.1778)
							(mid 0.249642 -0.249642)
							(end 0.1778 -0.2794)
						)
					)
					(width 0)
					(fill yes)
				)
			)
		)
		(pad "2" smd custom
			(at 0 0.4445 270)
			(size 0.1397 0.1397)
			(layers "F.Cu" "F.Mask" "F.Paste")
			(net "GND")
			(options
				(clearance outline)
				(anchor circle)
			)
			(primitives
				(gr_poly
					(pts
						(arc
							(start -0.1778 -0.2794)
							(mid -0.249642 -0.249642)
							(end -0.2794 -0.1778)
						)
						(arc
							(start -0.2794 0.1778)
							(mid -0.249642 0.249642)
							(end -0.1778 0.2794)
						)
						(arc
							(start 0.1778 0.2794)
							(mid 0.249642 0.249642)
							(end 0.2794 0.1778)
						)
						(arc
							(start 0.2794 -0.1778)
							(mid 0.249642 -0.249642)
							(end 0.1778 -0.2794)
						)
					)
					(width 0)
					(fill yes)
				)
			)
		)
	)
	(footprint ""
		(layer "F.Cu")
		(at 32.12592 -277.998428 -90)
		(property "Reference" "R451"
			(at 0 0 270)
			(layer "F.SilkS")
			(hide yes)
			(effects
				(font
					(size 1.27 1.27)
				)
			)
		)
		(property "Value" "4K7R2J-2-GP"
			(at 0.064008 -3.993896 270)
			(unlocked yes)
			(layer "F.Fab")
			(hide yes)
			(effects
				(font
					(size 1.016 1.016)
					(thickness 0.1524)
				)
			)
		)
		(property "Device Type" "R402H16"
			(at 0.064008 -5.517896 270)
			(unlocked yes)
			(layer "F.Fab")
			(hide yes)
			(effects
				(font
					(size 1.016 1.016)
					(thickness 0.1524)
				)
			)
		)
		(duplicate_pad_numbers_are_jumpers no)
		(fp_line
			(start -0.508 -0.9398)
			(end -0.508 0.9398)
			(stroke
				(width 0.1524)
				(type default)
			)
			(layer "F.SilkS")
		)
		(fp_line
			(start 0.508 -0.9398)
			(end -0.508 -0.9398)
			(stroke
				(width 0.1524)
				(type default)
			)
			(layer "F.SilkS")
		)
		(fp_rect
			(start -0.508 0.9398)
			(end 0.508 -0.9398)
			(stroke
				(width 0)
				(type default)
			)
			(fill no)
			(layer "F.CrtYd")
		)
		(fp_rect
			(start -0.508 0.9398)
			(end 0.508 -0.9398)
			(stroke
				(width 0)
				(type default)
			)
			(fill no)
			(layer "F.Fab")
		)
		(pad "1" smd custom
			(at 0 -0.4445 270)
			(size 0.1397 0.1397)
			(layers "F.Cu" "F.Mask" "F.Paste")
			(net "P3V3")
			(options
				(clearance outline)
				(anchor circle)
			)
			(primitives
				(gr_poly
					(pts
						(arc
							(start -0.1778 -0.2794)
							(mid -0.249642 -0.249642)
							(end -0.2794 -0.1778)
						)
						(arc
							(start -0.2794 0.1778)
							(mid -0.249642 0.249642)
							(end -0.1778 0.2794)
						)
						(arc
							(start 0.1778 0.2794)
							(mid 0.249642 0.249642)
							(end 0.2794 0.1778)
						)
						(arc
							(start 0.2794 -0.1778)
							(mid 0.249642 -0.249642)
							(end 0.1778 -0.2794)
						)
					)
					(width 0)
					(fill yes)
				)
			)
		)
		(pad "2" smd custom
			(at 0 0.4445 270)
			(size 0.1397 0.1397)
			(layers "F.Cu" "F.Mask" "F.Paste")
			(net "SAS_EXP_B_PWR7")
			(options
				(clearance outline)
				(anchor circle)
			)
			(primitives
				(gr_poly
					(pts
						(arc
							(start -0.1778 -0.2794)
							(mid -0.249642 -0.249642)
							(end -0.2794 -0.1778)
						)
						(arc
							(start -0.2794 0.1778)
							(mid -0.249642 0.249642)
							(end -0.1778 0.2794)
						)
						(arc
							(start 0.1778 0.2794)
							(mid 0.249642 0.249642)
							(end 0.2794 0.1778)
						)
						(arc
							(start 0.2794 -0.1778)
							(mid 0.249642 -0.249642)
							(end 0.1778 -0.2794)
						)
					)
					(width 0)
					(fill yes)
				)
			)
		)
	)
	(footprint ""
		(layer "F.Cu")
		(at 77.977746 -84.8487 -90)
		(property "Reference" "R231"
			(at 0 0 270)
			(layer "F.SilkS")
			(hide yes)
			(effects
				(font
					(size 1.27 1.27)
				)
			)
		)
		(property "Value" "1KR2F-3-GP"
			(at 0.064008 -3.993896 270)
			(unlocked yes)
			(layer "F.Fab")
			(hide yes)
			(effects
				(font
					(size 1.016 1.016)
					(thickness 0.1524)
				)
			)
		)
		(property "Device Type" "R402H16"
			(at 0.064008 -5.517896 270)
			(unlocked yes)
			(layer "F.Fab")
			(hide yes)
			(effects
				(font
					(size 1.016 1.016)
					(thickness 0.1524)
				)
			)
		)
		(duplicate_pad_numbers_are_jumpers no)
		(fp_line
			(start -0.508 -0.9398)
			(end -0.508 0.9398)
			(stroke
				(width 0.1524)
				(type default)
			)
			(layer "F.SilkS")
		)
		(fp_line
			(start 0.508 -0.9398)
			(end -0.508 -0.9398)
			(stroke
				(width 0.1524)
				(type default)
			)
			(layer "F.SilkS")
		)
		(fp_rect
			(start -0.508 0.9398)
			(end 0.508 -0.9398)
			(stroke
				(width 0)
				(type default)
			)
			(fill no)
			(layer "F.CrtYd")
		)
		(fp_rect
			(start -0.508 0.9398)
			(end 0.508 -0.9398)
			(stroke
				(width 0)
				(type default)
			)
			(fill no)
			(layer "F.Fab")
		)
		(pad "1" smd custom
			(at 0 -0.4445 270)
			(size 0.1397 0.1397)
			(layers "F.Cu" "F.Mask" "F.Paste")
			(net "P3V3")
			(options
				(clearance outline)
				(anchor circle)
			)
			(primitives
				(gr_poly
					(pts
						(arc
							(start -0.1778 -0.2794)
							(mid -0.249642 -0.249642)
							(end -0.2794 -0.1778)
						)
						(arc
							(start -0.2794 0.1778)
							(mid -0.249642 0.249642)
							(end -0.1778 0.2794)
						)
						(arc
							(start 0.1778 0.2794)
							(mid 0.249642 0.249642)
							(end 0.2794 0.1778)
						)
						(arc
							(start 0.2794 -0.1778)
							(mid 0.249642 -0.249642)
							(end 0.1778 -0.2794)
						)
					)
					(width 0)
					(fill yes)
				)
			)
		)
		(pad "2" smd custom
			(at 0 0.4445 270)
			(size 0.1397 0.1397)
			(layers "F.Cu" "F.Mask" "F.Paste")
			(net "SW_PWR_HDD9")
			(options
				(clearance outline)
				(anchor circle)
			)
			(primitives
				(gr_poly
					(pts
						(arc
							(start -0.1778 -0.2794)
							(mid -0.249642 -0.249642)
							(end -0.2794 -0.1778)
						)
						(arc
							(start -0.2794 0.1778)
							(mid -0.249642 0.249642)
							(end -0.1778 0.2794)
						)
						(arc
							(start 0.1778 0.2794)
							(mid 0.249642 0.249642)
							(end 0.2794 0.1778)
						)
						(arc
							(start 0.2794 -0.1778)
							(mid 0.249642 -0.249642)
							(end 0.1778 -0.2794)
						)
					)
					(width 0)
					(fill yes)
				)
			)
		)
	)
	(footprint ""
		(layer "F.Cu")
		(at 53.848 -129.921)
		(property "Reference" "C377"
			(at 0 0 0)
			(layer "F.SilkS")
			(hide yes)
			(effects
				(font
					(size 1.27 1.27)
				)
			)
		)
		(property "Value" "SCD033U25V2KX-GP"
			(at 1.1811 -2.7051 0)
			(unlocked yes)
			(layer "F.Fab")
			(hide yes)
			(effects
				(font
					(size 1.016 1.016)
					(thickness 0.1524)
				)
			)
		)
		(property "Device Type" "C402H22"
			(at 1.1811 -4.2291 0)
			(unlocked yes)
			(layer "F.Fab")
			(hide yes)
			(effects
				(font
					(size 1.016 1.016)
					(thickness 0.1524)
				)
			)
		)
		(duplicate_pad_numbers_are_jumpers no)
		(fp_rect
			(start -0.4318 0.9525)
			(end 0.4318 -0.9525)
			(stroke
				(width 0)
				(type default)
			)
			(fill no)
			(layer "F.CrtYd")
		)
		(fp_rect
			(start -0.4318 0.9525)
			(end 0.4318 -0.9525)
			(stroke
				(width 0)
				(type default)
			)
			(fill no)
			(layer "F.Fab")
		)
		(pad "1" smd custom
			(at 0 -0.4445)
			(size 0.1524 0.1524)
			(layers "F.Cu" "F.Mask" "F.Paste")
			(net "SW_HDD13_P")
			(options
				(clearance outline)
				(anchor circle)
			)
			(primitives
				(gr_poly
					(pts
						(arc
							(start 0.3048 -0.2032)
							(mid 0.275042 -0.275042)
							(end 0.2032 -0.3048)
						)
						(arc
							(start -0.2032 -0.3048)
							(mid -0.275042 -0.275042)
							(end -0.3048 -0.2032)
						)
						(arc
							(start -0.3048 0.2032)
							(mid -0.275042 0.275042)
							(end -0.2032 0.3048)
						)
						(arc
							(start 0.2032 0.3048)
							(mid 0.275042 0.275042)
							(end 0.3048 0.2032)
						)
					)
					(width 0)
					(fill yes)
				)
			)
		)
		(pad "2" smd custom
			(at 0 0.4445)
			(size 0.1524 0.1524)
			(layers "F.Cu" "F.Mask" "F.Paste")
			(net "GND")
			(options
				(clearance outline)
				(anchor circle)
			)
			(primitives
				(gr_poly
					(pts
						(arc
							(start 0.3048 -0.2032)
							(mid 0.275042 -0.275042)
							(end 0.2032 -0.3048)
						)
						(arc
							(start -0.2032 -0.3048)
							(mid -0.275042 -0.275042)
							(end -0.3048 -0.2032)
						)
						(arc
							(start -0.3048 0.2032)
							(mid -0.275042 0.275042)
							(end -0.2032 0.3048)
						)
						(arc
							(start 0.2032 0.3048)
							(mid 0.275042 0.275042)
							(end 0.3048 0.2032)
						)
					)
					(width 0)
					(fill yes)
				)
			)
		)
	)
	(footprint ""
		(layer "F.Cu")
		(at 233.933746 -26.1747)
		(property "Reference" "TP19"
			(at 0 0 0)
			(layer "F.SilkS")
			(hide yes)
			(effects
				(font
					(size 1.27 1.27)
				)
			)
		)
		(property "Value" "TPAD32-GP"
			(at 0 -3.166364 0)
			(unlocked yes)
			(layer "F.Fab")
			(hide yes)
			(effects
				(font
					(size 1.016 1.016)
					(thickness 0.1524)
				)
			)
		)
		(property "Device Type" "TPAD32"
			(at 0 -4.690618 0)
			(unlocked yes)
			(layer "F.Fab")
			(hide yes)
			(effects
				(font
					(size 1.016 1.016)
					(thickness 0.1524)
				)
			)
		)
		(duplicate_pad_numbers_are_jumpers no)
		(fp_poly
			(pts
				(arc
					(start 0.4064 0)
					(mid -0.4064 0)
					(end 0.4064 0)
				)
			)
			(stroke
				(width 0)
				(type default)
			)
			(fill no)
			(layer "F.CrtYd")
		)
		(fp_poly
			(pts
				(arc
					(start 0.7112 0)
					(mid -0.7112 0)
					(end 0.7112 0)
				)
			)
			(stroke
				(width 0)
				(type default)
			)
			(fill no)
			(layer "F.Fab")
		)
		(pad "1" smd circle
			(at 0 0)
			(size 0.8128 0.8128)
			(layers "F.Cu" "F.Mask" "F.Paste")
			(net "P5VA_EN")
		)
	)
	(footprint ""
		(layer "F.Cu")
		(at 16.662146 -470.3826 90)
		(property "Reference" "R500"
			(at 0 0 90)
			(layer "F.SilkS")
			(hide yes)
			(effects
				(font
					(size 1.27 1.27)
				)
			)
		)
		(property "Value" "1KR2F-3-GP"
			(at 0.064008 -3.993896 90)
			(unlocked yes)
			(layer "F.Fab")
			(hide yes)
			(effects
				(font
					(size 1.016 1.016)
					(thickness 0.1524)
				)
			)
		)
		(property "Device Type" "R402H16"
			(at 0.064008 -5.517896 90)
			(unlocked yes)
			(layer "F.Fab")
			(hide yes)
			(effects
				(font
					(size 1.016 1.016)
					(thickness 0.1524)
				)
			)
		)
		(duplicate_pad_numbers_are_jumpers no)
		(fp_line
			(start 0.508 -0.9398)
			(end -0.508 -0.9398)
			(stroke
				(width 0.1524)
				(type default)
			)
			(layer "F.SilkS")
		)
		(fp_line
			(start -0.508 -0.9398)
			(end -0.508 0.9398)
			(stroke
				(width 0.1524)
				(type default)
			)
			(layer "F.SilkS")
		)
		(fp_rect
			(start -0.508 0.9398)
			(end 0.508 -0.9398)
			(stroke
				(width 0)
				(type default)
			)
			(fill no)
			(layer "F.CrtYd")
		)
		(fp_rect
			(start -0.508 0.9398)
			(end 0.508 -0.9398)
			(stroke
				(width 0)
				(type default)
			)
			(fill no)
			(layer "F.Fab")
		)
		(pad "1" smd custom
			(at 0 -0.4445 90)
			(size 0.1397 0.1397)
			(layers "F.Cu" "F.Mask" "F.Paste")
			(net "FLT_HDD10_B")
			(options
				(clearance outline)
				(anchor circle)
			)
			(primitives
				(gr_poly
					(pts
						(arc
							(start -0.1778 -0.2794)
							(mid -0.249642 -0.249642)
							(end -0.2794 -0.1778)
						)
						(arc
							(start -0.2794 0.1778)
							(mid -0.249642 0.249642)
							(end -0.1778 0.2794)
						)
						(arc
							(start 0.1778 0.2794)
							(mid 0.249642 0.249642)
							(end 0.2794 0.1778)
						)
						(arc
							(start 0.2794 -0.1778)
							(mid 0.249642 -0.249642)
							(end 0.1778 -0.2794)
						)
					)
					(width 0)
					(fill yes)
				)
			)
		)
		(pad "2" smd custom
			(at 0 0.4445 90)
			(size 0.1397 0.1397)
			(layers "F.Cu" "F.Mask" "F.Paste")
			(net "FLT_HDD10_DRIVE")
			(options
				(clearance outline)
				(anchor circle)
			)
			(primitives
				(gr_poly
					(pts
						(arc
							(start -0.1778 -0.2794)
							(mid -0.249642 -0.249642)
							(end -0.2794 -0.1778)
						)
						(arc
							(start -0.2794 0.1778)
							(mid -0.249642 0.249642)
							(end -0.1778 0.2794)
						)
						(arc
							(start 0.1778 0.2794)
							(mid 0.249642 0.249642)
							(end 0.2794 0.1778)
						)
						(arc
							(start 0.2794 -0.1778)
							(mid 0.249642 -0.249642)
							(end 0.1778 -0.2794)
						)
					)
					(width 0)
					(fill yes)
				)
			)
		)
	)
	(footprint ""
		(layer "F.Cu")
		(at 217.473784 -188.488828 180)
		(property "Reference" "C162"
			(at 0 0 180)
			(layer "F.SilkS")
			(hide yes)
			(effects
				(font
					(size 1.27 1.27)
				)
			)
		)
		(property "Value" "SC10U25V6KX-1GP"
			(at -0.0762 -5.1308 180)
			(unlocked yes)
			(layer "F.Fab")
			(hide yes)
			(effects
				(font
					(size 1.016 1.016)
					(thickness 0.1524)
				)
			)
		)
		(property "Device Type" "C1206H71"
			(at -0.127 -6.6548 180)
			(unlocked yes)
			(layer "F.Fab")
			(hide yes)
			(effects
				(font
					(size 1.016 1.016)
					(thickness 0.1524)
				)
			)
		)
		(duplicate_pad_numbers_are_jumpers no)
		(fp_line
			(start 1.016 2.2352)
			(end -1.016 2.2352)
			(stroke
				(width 0.1524)
				(type default)
			)
			(layer "F.SilkS")
		)
		(fp_line
			(start 1.016 0.8382)
			(end 1.016 2.2352)
			(stroke
				(width 0.1524)
				(type default)
			)
			(layer "F.SilkS")
		)
		(fp_line
			(start 1.016 -2.2352)
			(end 1.016 -0.8382)
			(stroke
				(width 0.1524)
				(type default)
			)
			(layer "F.SilkS")
		)
		(fp_line
			(start -1.016 2.2352)
			(end -1.016 0.8382)
			(stroke
				(width 0.1524)
				(type default)
			)
			(layer "F.SilkS")
		)
		(fp_line
			(start -1.016 -0.8382)
			(end -1.016 -2.2352)
			(stroke
				(width 0.1524)
				(type default)
			)
			(layer "F.SilkS")
		)
		(fp_line
			(start -1.016 -2.2352)
			(end 1.016 -2.2352)
			(stroke
				(width 0.1524)
				(type default)
			)
			(layer "F.SilkS")
		)
		(fp_rect
			(start -1.0922 2.3114)
			(end 1.0922 -2.3114)
			(stroke
				(width 0)
				(type default)
			)
			(fill no)
			(layer "F.CrtYd")
		)
		(fp_poly
			(pts
				(xy 1.0922 -2.3114) (xy 1.0922 2.3114) (xy -1.0922 2.3114) (xy -1.0922 -2.3114)
			)
			(stroke
				(width 0)
				(type default)
			)
			(fill no)
			(layer "F.Fab")
		)
		(pad "1" smd rect
			(at 0 -1.397 180)
			(size 1.651 1.27)
			(layers "F.Cu" "F.Mask" "F.Paste")
			(net "P12V_HDD3")
		)
		(pad "2" smd rect
			(at 0 1.397 180)
			(size 1.651 1.27)
			(layers "F.Cu" "F.Mask" "F.Paste")
			(net "GND")
		)
	)
	(footprint ""
		(layer "F.Cu")
		(at 32.0802 -335.2546 90)
		(property "Reference" "R398"
			(at 0 0 90)
			(layer "F.SilkS")
			(hide yes)
			(effects
				(font
					(size 1.27 1.27)
				)
			)
		)
		(property "Value" "0R2J-2-GP"
			(at 0.064008 -3.993896 90)
			(unlocked yes)
			(layer "F.Fab")
			(hide yes)
			(effects
				(font
					(size 1.016 1.016)
					(thickness 0.1524)
				)
			)
		)
		(property "Device Type" "R402H16"
			(at 0.064008 -5.517896 90)
			(unlocked yes)
			(layer "F.Fab")
			(hide yes)
			(effects
				(font
					(size 1.016 1.016)
					(thickness 0.1524)
				)
			)
		)
		(duplicate_pad_numbers_are_jumpers no)
		(fp_line
			(start 0.508 -0.9398)
			(end -0.508 -0.9398)
			(stroke
				(width 0.1524)
				(type default)
			)
			(layer "F.SilkS")
		)
		(fp_line
			(start -0.508 -0.9398)
			(end -0.508 0.9398)
			(stroke
				(width 0.1524)
				(type default)
			)
			(layer "F.SilkS")
		)
		(fp_rect
			(start -0.508 0.9398)
			(end 0.508 -0.9398)
			(stroke
				(width 0)
				(type default)
			)
			(fill no)
			(layer "F.CrtYd")
		)
		(fp_rect
			(start -0.508 0.9398)
			(end 0.508 -0.9398)
			(stroke
				(width 0)
				(type default)
			)
			(fill no)
			(layer "F.Fab")
		)
		(pad "1" smd custom
			(at 0 -0.4445 90)
			(size 0.1397 0.1397)
			(layers "F.Cu" "F.Mask" "F.Paste")
			(net "HDD_PRSNT_NET11")
			(options
				(clearance outline)
				(anchor circle)
			)
			(primitives
				(gr_poly
					(pts
						(arc
							(start -0.1778 -0.2794)
							(mid -0.249642 -0.249642)
							(end -0.2794 -0.1778)
						)
						(arc
							(start -0.2794 0.1778)
							(mid -0.249642 0.249642)
							(end -0.1778 0.2794)
						)
						(arc
							(start 0.1778 0.2794)
							(mid 0.249642 0.249642)
							(end 0.2794 0.1778)
						)
						(arc
							(start 0.2794 -0.1778)
							(mid 0.249642 -0.249642)
							(end 0.1778 -0.2794)
						)
					)
					(width 0)
					(fill yes)
				)
			)
		)
		(pad "2" smd custom
			(at 0 0.4445 90)
			(size 0.1397 0.1397)
			(layers "F.Cu" "F.Mask" "F.Paste")
			(net "HDD11_LED_B")
			(options
				(clearance outline)
				(anchor circle)
			)
			(primitives
				(gr_poly
					(pts
						(arc
							(start -0.1778 -0.2794)
							(mid -0.249642 -0.249642)
							(end -0.2794 -0.1778)
						)
						(arc
							(start -0.2794 0.1778)
							(mid -0.249642 0.249642)
							(end -0.1778 0.2794)
						)
						(arc
							(start 0.1778 0.2794)
							(mid 0.249642 0.249642)
							(end 0.2794 0.1778)
						)
						(arc
							(start 0.2794 -0.1778)
							(mid 0.249642 -0.249642)
							(end 0.1778 -0.2794)
						)
					)
					(width 0)
					(fill yes)
				)
			)
		)
	)
	(footprint ""
		(layer "F.Cu")
		(at 207.8736 -67.945 -90)
		(property "Reference" "Q54"
			(at 0 0 270)
			(layer "F.SilkS")
			(hide yes)
			(effects
				(font
					(size 1.27 1.27)
				)
			)
		)
		(property "Value" "2N7002DW-7F-GP"
			(at -2.3622 -8.2042 270)
			(unlocked yes)
			(layer "F.Fab")
			(hide yes)
			(effects
				(font
					(size 1.016 1.016)
					(thickness 0.1524)
				)
			)
		)
		(property "Device Type" "SOT-363H44"
			(at -2.3622 -10.1092 270)
			(unlocked yes)
			(layer "F.Fab")
			(hide yes)
			(effects
				(font
					(size 1.016 1.016)
					(thickness 0.1524)
				)
			)
		)
		(duplicate_pad_numbers_are_jumpers no)
		(fp_line
			(start -1.4478 1.7018)
			(end 1.4478 1.7018)
			(stroke
				(width 0.1524)
				(type default)
			)
			(layer "F.SilkS")
		)
		(fp_line
			(start 1.4478 1.7018)
			(end 1.4478 -1.7018)
			(stroke
				(width 0.1524)
				(type default)
			)
			(layer "F.SilkS")
		)
		(fp_line
			(start -1.27 1.524)
			(end -1.27 0.6604)
			(stroke
				(width 0.4826)
				(type default)
			)
			(layer "F.SilkS")
		)
		(fp_line
			(start -1.4478 -1.7018)
			(end -1.4478 1.7018)
			(stroke
				(width 0.1524)
				(type default)
			)
			(layer "F.SilkS")
		)
		(fp_line
			(start 1.4478 -1.7018)
			(end -1.4478 -1.7018)
			(stroke
				(width 0.1524)
				(type default)
			)
			(layer "F.SilkS")
		)
		(fp_poly
			(pts
				(xy -1.524 -1.778) (xy 1.524 -1.778) (xy 1.524 1.778) (xy -1.524 1.778)
			)
			(stroke
				(width 0)
				(type default)
			)
			(fill no)
			(layer "F.CrtYd")
		)
		(fp_poly
			(pts
				(xy -1.524 -1.778) (xy 1.524 -1.778) (xy 1.524 1.778) (xy -1.524 1.778)
			)
			(stroke
				(width 0)
				(type default)
			)
			(fill no)
			(layer "F.Fab")
		)
		(pad "1" smd rect
			(at -0.65024 0.9398 270)
			(size 0.4064 1.016)
			(layers "F.Cu" "F.Mask" "F.Paste")
			(net "P3V3_HDD4_LED")
		)
		(pad "2" smd rect
			(at 0 0.9398 270)
			(size 0.4064 1.016)
			(layers "F.Cu" "F.Mask" "F.Paste")
			(net "HDD4_LED_G")
		)
		(pad "3" smd rect
			(at 0.65024 0.9398 270)
			(size 0.4064 1.016)
			(layers "F.Cu" "F.Mask" "F.Paste")
			(net "P5VA")
		)
		(pad "4" smd rect
			(at 0.65024 -0.9398 270)
			(size 0.4064 1.016)
			(layers "F.Cu" "F.Mask" "F.Paste")
			(net "P5VA_HDD4_LED")
		)
		(pad "5" smd rect
			(at 0 -0.9398 270)
			(size 0.4064 1.016)
			(layers "F.Cu" "F.Mask" "F.Paste")
			(net "HDD4_LED_G")
		)
		(pad "6" smd rect
			(at -0.65024 -0.9398 270)
			(size 0.4064 1.016)
			(layers "F.Cu" "F.Mask" "F.Paste")
			(net "P3V3")
		)
	)
	(footprint ""
		(layer "F.Cu")
		(at 32.892746 -314.734702)
		(property "Reference" "C288"
			(at 0 0 0)
			(layer "F.SilkS")
			(hide yes)
			(effects
				(font
					(size 1.27 1.27)
				)
			)
		)
		(property "Value" "SC10U25V6KX-1GP"
			(at -0.0762 -5.1308 0)
			(unlocked yes)
			(layer "F.Fab")
			(hide yes)
			(effects
				(font
					(size 1.016 1.016)
					(thickness 0.1524)
				)
			)
		)
		(property "Device Type" "C1206H71"
			(at -0.127 -6.6548 0)
			(unlocked yes)
			(layer "F.Fab")
			(hide yes)
			(effects
				(font
					(size 1.016 1.016)
					(thickness 0.1524)
				)
			)
		)
		(duplicate_pad_numbers_are_jumpers no)
		(fp_line
			(start -1.016 -2.2352)
			(end 1.016 -2.2352)
			(stroke
				(width 0.1524)
				(type default)
			)
			(layer "F.SilkS")
		)
		(fp_line
			(start -1.016 -0.8382)
			(end -1.016 -2.2352)
			(stroke
				(width 0.1524)
				(type default)
			)
			(layer "F.SilkS")
		)
		(fp_line
			(start -1.016 2.2352)
			(end -1.016 0.8382)
			(stroke
				(width 0.1524)
				(type default)
			)
			(layer "F.SilkS")
		)
		(fp_line
			(start 1.016 -2.2352)
			(end 1.016 -0.8382)
			(stroke
				(width 0.1524)
				(type default)
			)
			(layer "F.SilkS")
		)
		(fp_line
			(start 1.016 0.8382)
			(end 1.016 2.2352)
			(stroke
				(width 0.1524)
				(type default)
			)
			(layer "F.SilkS")
		)
		(fp_line
			(start 1.016 2.2352)
			(end -1.016 2.2352)
			(stroke
				(width 0.1524)
				(type default)
			)
			(layer "F.SilkS")
		)
		(fp_rect
			(start -1.0922 2.3114)
			(end 1.0922 -2.3114)
			(stroke
				(width 0)
				(type default)
			)
			(fill no)
			(layer "F.CrtYd")
		)
		(fp_poly
			(pts
				(xy 1.0922 -2.3114) (xy 1.0922 2.3114) (xy -1.0922 2.3114) (xy -1.0922 -2.3114)
			)
			(stroke
				(width 0)
				(type default)
			)
			(fill no)
			(layer "F.Fab")
		)
		(pad "1" smd rect
			(at 0 -1.397)
			(size 1.651 1.27)
			(layers "F.Cu" "F.Mask" "F.Paste")
			(net "P12V_HDD11")
		)
		(pad "2" smd rect
			(at 0 1.397)
			(size 1.651 1.27)
			(layers "F.Cu" "F.Mask" "F.Paste")
			(net "GND")
		)
	)
	(footprint ""
		(layer "F.Cu")
		(at 191.853058 -388.949184 -90)
		(property "Reference" "R119"
			(at 0 0 270)
			(layer "F.SilkS")
			(hide yes)
			(effects
				(font
					(size 1.27 1.27)
				)
			)
		)
		(property "Value" "1KR2F-3-GP"
			(at 0.064008 -3.993896 270)
			(unlocked yes)
			(layer "F.Fab")
			(hide yes)
			(effects
				(font
					(size 1.016 1.016)
					(thickness 0.1524)
				)
			)
		)
		(property "Device Type" "R402H16"
			(at 0.064008 -5.517896 270)
			(unlocked yes)
			(layer "F.Fab")
			(hide yes)
			(effects
				(font
					(size 1.016 1.016)
					(thickness 0.1524)
				)
			)
		)
		(duplicate_pad_numbers_are_jumpers no)
		(fp_line
			(start -0.508 -0.9398)
			(end -0.508 0.9398)
			(stroke
				(width 0.1524)
				(type default)
			)
			(layer "F.SilkS")
		)
		(fp_line
			(start 0.508 -0.9398)
			(end -0.508 -0.9398)
			(stroke
				(width 0.1524)
				(type default)
			)
			(layer "F.SilkS")
		)
		(fp_rect
			(start -0.508 0.9398)
			(end 0.508 -0.9398)
			(stroke
				(width 0)
				(type default)
			)
			(fill no)
			(layer "F.CrtYd")
		)
		(fp_rect
			(start -0.508 0.9398)
			(end 0.508 -0.9398)
			(stroke
				(width 0)
				(type default)
			)
			(fill no)
			(layer "F.Fab")
		)
		(pad "1" smd custom
			(at 0 -0.4445 270)
			(size 0.1397 0.1397)
			(layers "F.Cu" "F.Mask" "F.Paste")
			(net "P3V3")
			(options
				(clearance outline)
				(anchor circle)
			)
			(primitives
				(gr_poly
					(pts
						(arc
							(start -0.1778 -0.2794)
							(mid -0.249642 -0.249642)
							(end -0.2794 -0.1778)
						)
						(arc
							(start -0.2794 0.1778)
							(mid -0.249642 0.249642)
							(end -0.1778 0.2794)
						)
						(arc
							(start 0.1778 0.2794)
							(mid 0.249642 0.249642)
							(end 0.2794 0.1778)
						)
						(arc
							(start 0.2794 -0.1778)
							(mid 0.249642 -0.249642)
							(end 0.1778 -0.2794)
						)
					)
					(width 0)
					(fill yes)
				)
			)
		)
		(pad "2" smd custom
			(at 0 0.4445 270)
			(size 0.1397 0.1397)
			(layers "F.Cu" "F.Mask" "F.Paste")
			(net "SW_PWR_HDD1")
			(options
				(clearance outline)
				(anchor circle)
			)
			(primitives
				(gr_poly
					(pts
						(arc
							(start -0.1778 -0.2794)
							(mid -0.249642 -0.249642)
							(end -0.2794 -0.1778)
						)
						(arc
							(start -0.2794 0.1778)
							(mid -0.249642 0.249642)
							(end -0.1778 0.2794)
						)
						(arc
							(start 0.1778 0.2794)
							(mid 0.249642 0.249642)
							(end 0.2794 0.1778)
						)
						(arc
							(start 0.2794 -0.1778)
							(mid 0.249642 -0.249642)
							(end 0.1778 -0.2794)
						)
					)
					(width 0)
					(fill yes)
				)
			)
		)
	)
	(footprint ""
		(layer "F.Cu")
		(at 45.275246 -247.0277 90)
		(property "Reference" "R200"
			(at 0 0 90)
			(layer "F.SilkS")
			(hide yes)
			(effects
				(font
					(size 1.27 1.27)
				)
			)
		)
		(property "Value" "0R2J-2-GP"
			(at 0.064008 -3.993896 90)
			(unlocked yes)
			(layer "F.Fab")
			(hide yes)
			(effects
				(font
					(size 1.016 1.016)
					(thickness 0.1524)
				)
			)
		)
		(property "Device Type" "R402H16"
			(at 0.064008 -5.517896 90)
			(unlocked yes)
			(layer "F.Fab")
			(hide yes)
			(effects
				(font
					(size 1.016 1.016)
					(thickness 0.1524)
				)
			)
		)
		(duplicate_pad_numbers_are_jumpers no)
		(fp_line
			(start 0.508 -0.9398)
			(end -0.508 -0.9398)
			(stroke
				(width 0.1524)
				(type default)
			)
			(layer "F.SilkS")
		)
		(fp_line
			(start -0.508 -0.9398)
			(end -0.508 0.9398)
			(stroke
				(width 0.1524)
				(type default)
			)
			(layer "F.SilkS")
		)
		(fp_rect
			(start -0.508 0.9398)
			(end 0.508 -0.9398)
			(stroke
				(width 0)
				(type default)
			)
			(fill no)
			(layer "F.CrtYd")
		)
		(fp_rect
			(start -0.508 0.9398)
			(end 0.508 -0.9398)
			(stroke
				(width 0)
				(type default)
			)
			(fill no)
			(layer "F.Fab")
		)
		(pad "1" smd custom
			(at 0 -0.4445 90)
			(size 0.1397 0.1397)
			(layers "F.Cu" "F.Mask" "F.Paste")
			(net "DRV_ACT_NET7")
			(options
				(clearance outline)
				(anchor circle)
			)
			(primitives
				(gr_poly
					(pts
						(arc
							(start -0.1778 -0.2794)
							(mid -0.249642 -0.249642)
							(end -0.2794 -0.1778)
						)
						(arc
							(start -0.2794 0.1778)
							(mid -0.249642 0.249642)
							(end -0.1778 0.2794)
						)
						(arc
							(start 0.1778 0.2794)
							(mid 0.249642 0.249642)
							(end 0.2794 0.1778)
						)
						(arc
							(start 0.2794 -0.1778)
							(mid 0.249642 -0.249642)
							(end 0.1778 -0.2794)
						)
					)
					(width 0)
					(fill yes)
				)
			)
		)
		(pad "2" smd custom
			(at 0 0.4445 90)
			(size 0.1397 0.1397)
			(layers "F.Cu" "F.Mask" "F.Paste")
			(net "DRIVE_ACT_7")
			(options
				(clearance outline)
				(anchor circle)
			)
			(primitives
				(gr_poly
					(pts
						(arc
							(start -0.1778 -0.2794)
							(mid -0.249642 -0.249642)
							(end -0.2794 -0.1778)
						)
						(arc
							(start -0.2794 0.1778)
							(mid -0.249642 0.249642)
							(end -0.1778 0.2794)
						)
						(arc
							(start 0.1778 0.2794)
							(mid 0.249642 0.249642)
							(end 0.2794 0.1778)
						)
						(arc
							(start 0.2794 -0.1778)
							(mid 0.249642 -0.249642)
							(end 0.1778 -0.2794)
						)
					)
					(width 0)
					(fill yes)
				)
			)
		)
	)
	(footprint ""
		(layer "F.Cu")
		(at 210.946746 -285.7627)
		(property "Reference" "C142"
			(at 0 0 0)
			(layer "F.SilkS")
			(hide yes)
			(effects
				(font
					(size 1.27 1.27)
				)
			)
		)
		(property "Value" "SC10U25V6KX-1GP"
			(at -0.0762 -5.1308 0)
			(unlocked yes)
			(layer "F.Fab")
			(hide yes)
			(effects
				(font
					(size 1.016 1.016)
					(thickness 0.1524)
				)
			)
		)
		(property "Device Type" "C1206H71"
			(at -0.127 -6.6548 0)
			(unlocked yes)
			(layer "F.Fab")
			(hide yes)
			(effects
				(font
					(size 1.016 1.016)
					(thickness 0.1524)
				)
			)
		)
		(duplicate_pad_numbers_are_jumpers no)
		(fp_line
			(start -1.016 -2.2352)
			(end 1.016 -2.2352)
			(stroke
				(width 0.1524)
				(type default)
			)
			(layer "F.SilkS")
		)
		(fp_line
			(start -1.016 -0.8382)
			(end -1.016 -2.2352)
			(stroke
				(width 0.1524)
				(type default)
			)
			(layer "F.SilkS")
		)
		(fp_line
			(start -1.016 2.2352)
			(end -1.016 0.8382)
			(stroke
				(width 0.1524)
				(type default)
			)
			(layer "F.SilkS")
		)
		(fp_line
			(start 1.016 -2.2352)
			(end 1.016 -0.8382)
			(stroke
				(width 0.1524)
				(type default)
			)
			(layer "F.SilkS")
		)
		(fp_line
			(start 1.016 0.8382)
			(end 1.016 2.2352)
			(stroke
				(width 0.1524)
				(type default)
			)
			(layer "F.SilkS")
		)
		(fp_line
			(start 1.016 2.2352)
			(end -1.016 2.2352)
			(stroke
				(width 0.1524)
				(type default)
			)
			(layer "F.SilkS")
		)
		(fp_rect
			(start -1.0922 2.3114)
			(end 1.0922 -2.3114)
			(stroke
				(width 0)
				(type default)
			)
			(fill no)
			(layer "F.CrtYd")
		)
		(fp_poly
			(pts
				(xy 1.0922 -2.3114) (xy 1.0922 2.3114) (xy -1.0922 2.3114) (xy -1.0922 -2.3114)
			)
			(stroke
				(width 0)
				(type default)
			)
			(fill no)
			(layer "F.Fab")
		)
		(pad "1" smd rect
			(at 0 -1.397)
			(size 1.651 1.27)
			(layers "F.Cu" "F.Mask" "F.Paste")
			(net "P12V_HDD2")
		)
		(pad "2" smd rect
			(at 0 1.397)
			(size 1.651 1.27)
			(layers "F.Cu" "F.Mask" "F.Paste")
			(net "GND")
		)
	)
	(footprint ""
		(layer "F.Cu")
		(at 23.748746 -490.1057 90)
		(property "Reference" "PL6"
			(at 0 0 90)
			(layer "F.SilkS")
			(hide yes)
			(effects
				(font
					(size 1.27 1.27)
				)
			)
		)
		(property "Value" "IND-4D7UH-291-GP"
			(at -6.34492 -3.502152 90)
			(unlocked yes)
			(layer "F.Fab")
			(hide yes)
			(effects
				(font
					(size 1.016 1.016)
					(thickness 0.1524)
				)
			)
		)
		(property "Device Type" "L11102530H158"
			(at -6.3246 -5.08 90)
			(unlocked yes)
			(layer "F.Fab")
			(hide yes)
			(effects
				(font
					(size 1.016 1.016)
					(thickness 0.1524)
				)
			)
		)
		(duplicate_pad_numbers_are_jumpers no)
		(fp_line
			(start 5.2578 -6.3754)
			(end -5.2578 -6.3754)
			(stroke
				(width 0.1524)
				(type default)
			)
			(layer "F.SilkS")
		)
		(fp_line
			(start -5.2578 -6.3754)
			(end -5.2578 6.3754)
			(stroke
				(width 0.1524)
				(type default)
			)
			(layer "F.SilkS")
		)
		(fp_line
			(start 5.2578 6.3754)
			(end 5.2578 -6.3754)
			(stroke
				(width 0.1524)
				(type default)
			)
			(layer "F.SilkS")
		)
		(fp_line
			(start -5.2578 6.3754)
			(end 5.2578 6.3754)
			(stroke
				(width 0.1524)
				(type default)
			)
			(layer "F.SilkS")
		)
		(fp_rect
			(start -5.0038 5.4991)
			(end 5.0038 -5.4991)
			(stroke
				(width 0)
				(type default)
			)
			(fill no)
			(layer "F.CrtYd")
		)
		(fp_poly
			(pts
				(xy -5.5118 6.4516) (xy -5.5118 -6.4516) (xy 5.5118 -6.4516) (xy 5.5118 -0.8509) (xy 5.0038 -0.8509)
				(xy 5.0038 -5.4991) (xy -5.0038 -5.4991) (xy -5.0038 5.4991) (xy 5.0038 5.4991) (xy 5.0038 -0.8382)
				(xy 5.5118 -0.8382) (xy 5.5118 6.4516)
			)
			(stroke
				(width 0)
				(type default)
			)
			(fill no)
			(layer "F.CrtYd")
		)
		(fp_rect
			(start -5.5118 6.4516)
			(end 5.5118 -6.4516)
			(stroke
				(width 0)
				(type default)
			)
			(fill no)
			(layer "F.Fab")
		)
		(pad "1" smd rect
			(at 0 -4.435094 90)
			(size 3.2512 3.3782)
			(layers "F.Cu" "F.Mask" "F.Paste")
			(net "P5VC_LL")
		)
		(pad "2" smd rect
			(at 0 4.435094 90)
			(size 3.2512 3.3782)
			(layers "F.Cu" "F.Mask" "F.Paste")
			(net "P5VC")
		)
	)
	(footprint ""
		(layer "F.Cu")
		(at 4.699 -273.558 180)
		(property "Reference" "R542"
			(at 0 0 180)
			(layer "F.SilkS")
			(hide yes)
			(effects
				(font
					(size 1.27 1.27)
				)
			)
		)
		(property "Value" "2R2010J-1-GP"
			(at 0.254 -8.0772 180)
			(unlocked yes)
			(layer "F.Fab")
			(hide yes)
			(effects
				(font
					(size 1.016 1.016)
					(thickness 0.1524)
				)
			)
		)
		(property "Device Type" "R2010H28"
			(at 0.254 -9.6774 180)
			(unlocked yes)
			(layer "F.Fab")
			(hide yes)
			(effects
				(font
					(size 1.016 1.016)
					(thickness 0.1524)
				)
			)
		)
		(duplicate_pad_numbers_are_jumpers no)
		(fp_line
			(start 1.651 3.302)
			(end 1.651 -3.302)
			(stroke
				(width 0.1524)
				(type default)
			)
			(layer "F.SilkS")
		)
		(fp_line
			(start 1.651 -3.302)
			(end -1.651 -3.302)
			(stroke
				(width 0.1524)
				(type default)
			)
			(layer "F.SilkS")
		)
		(fp_line
			(start -1.651 3.302)
			(end 1.651 3.302)
			(stroke
				(width 0.1524)
				(type default)
			)
			(layer "F.SilkS")
		)
		(fp_line
			(start -1.651 -3.302)
			(end -1.651 3.302)
			(stroke
				(width 0.1524)
				(type default)
			)
			(layer "F.SilkS")
		)
		(fp_rect
			(start -1.7272 -3.3782)
			(end 1.7272 3.3782)
			(stroke
				(width 0)
				(type default)
			)
			(fill no)
			(layer "F.CrtYd")
		)
		(fp_poly
			(pts
				(xy 1.7272 3.3782) (xy 1.7272 -3.3782) (xy -1.7272 -3.3782) (xy -1.7272 3.3782)
			)
			(stroke
				(width 0)
				(type default)
			)
			(fill no)
			(layer "F.Fab")
		)
		(pad "1" smd rect
			(at 0 -2.3495 180)
			(size 2.794 1.143)
			(layers "F.Cu" "F.Mask" "F.Paste")
			(net "GND")
		)
		(pad "2" smd rect
			(at 0 2.3495 180)
			(size 2.794 1.143)
			(layers "F.Cu" "F.Mask" "F.Paste")
			(net "PRSNT_A")
		)
	)
	(footprint ""
		(layer "F.Cu")
		(at 211.576412 -81.006696)
		(property "Reference" "C174"
			(at 0 0 0)
			(layer "F.SilkS")
			(hide yes)
			(effects
				(font
					(size 1.27 1.27)
				)
			)
		)
		(property "Value" "SC10U25V6KX-1GP"
			(at -0.0762 -5.1308 0)
			(unlocked yes)
			(layer "F.Fab")
			(hide yes)
			(effects
				(font
					(size 1.016 1.016)
					(thickness 0.1524)
				)
			)
		)
		(property "Device Type" "C1206H71"
			(at -0.127 -6.6548 0)
			(unlocked yes)
			(layer "F.Fab")
			(hide yes)
			(effects
				(font
					(size 1.016 1.016)
					(thickness 0.1524)
				)
			)
		)
		(duplicate_pad_numbers_are_jumpers no)
		(fp_line
			(start -1.016 -2.2352)
			(end 1.016 -2.2352)
			(stroke
				(width 0.1524)
				(type default)
			)
			(layer "F.SilkS")
		)
		(fp_line
			(start -1.016 -0.8382)
			(end -1.016 -2.2352)
			(stroke
				(width 0.1524)
				(type default)
			)
			(layer "F.SilkS")
		)
		(fp_line
			(start -1.016 2.2352)
			(end -1.016 0.8382)
			(stroke
				(width 0.1524)
				(type default)
			)
			(layer "F.SilkS")
		)
		(fp_line
			(start 1.016 -2.2352)
			(end 1.016 -0.8382)
			(stroke
				(width 0.1524)
				(type default)
			)
			(layer "F.SilkS")
		)
		(fp_line
			(start 1.016 0.8382)
			(end 1.016 2.2352)
			(stroke
				(width 0.1524)
				(type default)
			)
			(layer "F.SilkS")
		)
		(fp_line
			(start 1.016 2.2352)
			(end -1.016 2.2352)
			(stroke
				(width 0.1524)
				(type default)
			)
			(layer "F.SilkS")
		)
		(fp_rect
			(start -1.0922 2.3114)
			(end 1.0922 -2.3114)
			(stroke
				(width 0)
				(type default)
			)
			(fill no)
			(layer "F.CrtYd")
		)
		(fp_poly
			(pts
				(xy 1.0922 -2.3114) (xy 1.0922 2.3114) (xy -1.0922 2.3114) (xy -1.0922 -2.3114)
			)
			(stroke
				(width 0)
				(type default)
			)
			(fill no)
			(layer "F.Fab")
		)
		(pad "1" smd rect
			(at 0 -1.397)
			(size 1.651 1.27)
			(layers "F.Cu" "F.Mask" "F.Paste")
			(net "P12V_HDD4")
		)
		(pad "2" smd rect
			(at 0 1.397)
			(size 1.651 1.27)
			(layers "F.Cu" "F.Mask" "F.Paste")
			(net "GND")
		)
	)
	(footprint ""
		(layer "F.Cu")
		(at 33.893252 -167.14851 -90)
		(property "Reference" "C233"
			(at 0 0 270)
			(layer "F.SilkS")
			(hide yes)
			(effects
				(font
					(size 1.27 1.27)
				)
			)
		)
		(property "Value" "SCD01U50V2KX-1GP"
			(at 1.1811 -2.7051 270)
			(unlocked yes)
			(layer "F.Fab")
			(hide yes)
			(effects
				(font
					(size 1.016 1.016)
					(thickness 0.1524)
				)
			)
		)
		(property "Device Type" "C402H22"
			(at 1.1811 -4.2291 270)
			(unlocked yes)
			(layer "F.Fab")
			(hide yes)
			(effects
				(font
					(size 1.016 1.016)
					(thickness 0.1524)
				)
			)
		)
		(duplicate_pad_numbers_are_jumpers no)
		(fp_rect
			(start -0.4318 0.9525)
			(end 0.4318 -0.9525)
			(stroke
				(width 0)
				(type default)
			)
			(fill no)
			(layer "F.CrtYd")
		)
		(fp_rect
			(start -0.4318 0.9525)
			(end 0.4318 -0.9525)
			(stroke
				(width 0)
				(type default)
			)
			(fill no)
			(layer "F.Fab")
		)
		(pad "1" smd custom
			(at 0 -0.4445 270)
			(size 0.1524 0.1524)
			(layers "F.Cu" "F.Mask" "F.Paste")
			(net "SAS2X28_DRIVE_RX_P_B8")
			(options
				(clearance outline)
				(anchor circle)
			)
			(primitives
				(gr_poly
					(pts
						(arc
							(start 0.3048 -0.2032)
							(mid 0.275042 -0.275042)
							(end 0.2032 -0.3048)
						)
						(arc
							(start -0.2032 -0.3048)
							(mid -0.275042 -0.275042)
							(end -0.3048 -0.2032)
						)
						(arc
							(start -0.3048 0.2032)
							(mid -0.275042 0.275042)
							(end -0.2032 0.3048)
						)
						(arc
							(start 0.2032 0.3048)
							(mid 0.275042 0.275042)
							(end 0.3048 0.2032)
						)
					)
					(width 0)
					(fill yes)
				)
			)
		)
		(pad "2" smd custom
			(at 0 0.4445 270)
			(size 0.1524 0.1524)
			(layers "F.Cu" "F.Mask" "F.Paste")
			(net "SAS2X28_B_HDD8_RX_+")
			(options
				(clearance outline)
				(anchor circle)
			)
			(primitives
				(gr_poly
					(pts
						(arc
							(start 0.3048 -0.2032)
							(mid 0.275042 -0.275042)
							(end 0.2032 -0.3048)
						)
						(arc
							(start -0.2032 -0.3048)
							(mid -0.275042 -0.275042)
							(end -0.3048 -0.2032)
						)
						(arc
							(start -0.3048 0.2032)
							(mid -0.275042 0.275042)
							(end -0.2032 0.3048)
						)
						(arc
							(start 0.2032 0.3048)
							(mid 0.275042 0.275042)
							(end 0.3048 0.2032)
						)
					)
					(width 0)
					(fill yes)
				)
			)
		)
	)
	(footprint ""
		(layer "F.Cu")
		(at 193.881756 -492.687102 -90)
		(property "Reference" "U3"
			(at 0 0 270)
			(layer "F.SilkS")
			(hide yes)
			(effects
				(font
					(size 1.27 1.27)
				)
			)
		)
		(property "Value" "74LVC1G08GW-1-GP"
			(at -2.3368 -8.6868 270)
			(unlocked yes)
			(layer "F.Fab")
			(hide yes)
			(effects
				(font
					(size 1.016 1.016)
					(thickness 0.1524)
				)
			)
		)
		(property "Device Type" "SC70-5H44"
			(at -2.3114 -10.414 270)
			(unlocked yes)
			(layer "F.Fab")
			(hide yes)
			(effects
				(font
					(size 1.016 1.016)
					(thickness 0.1524)
				)
			)
		)
		(duplicate_pad_numbers_are_jumpers no)
		(fp_line
			(start -1.27 1.7018)
			(end -1.27 -1.7018)
			(stroke
				(width 0.1524)
				(type default)
			)
			(layer "F.SilkS")
		)
		(fp_line
			(start 1.27 1.7018)
			(end -1.27 1.7018)
			(stroke
				(width 0.1524)
				(type default)
			)
			(layer "F.SilkS")
		)
		(fp_line
			(start -1.27 -1.7018)
			(end 1.27 -1.7018)
			(stroke
				(width 0.1524)
				(type default)
			)
			(layer "F.SilkS")
		)
		(fp_line
			(start 1.27 -1.7018)
			(end 1.27 1.7018)
			(stroke
				(width 0.1524)
				(type default)
			)
			(layer "F.SilkS")
		)
		(fp_line
			(start 0.6604 -1.8034)
			(end 1.3843 -1.8034)
			(stroke
				(width 0.3302)
				(type default)
			)
			(layer "F.SilkS")
		)
		(fp_line
			(start 1.3843 -1.8034)
			(end 1.3843 -1.1176)
			(stroke
				(width 0.3302)
				(type default)
			)
			(layer "F.SilkS")
		)
		(fp_rect
			(start -1.524 1.9558)
			(end 1.524 -1.9558)
			(stroke
				(width 0)
				(type default)
			)
			(fill no)
			(layer "F.CrtYd")
		)
		(fp_poly
			(pts
				(xy -1.524 -1.9558) (xy 1.524 -1.9558) (xy 1.524 1.9558) (xy -1.524 1.9558)
			)
			(stroke
				(width 0)
				(type default)
			)
			(fill no)
			(layer "F.Fab")
		)
		(pad "1" smd rect
			(at 0.65024 -0.8255 270)
			(size 0.4064 1.2192)
			(layers "F.Cu" "F.Mask" "F.Paste")
			(net "SAS_EXP_B_PWR0")
		)
		(pad "2" smd rect
			(at 0 -0.8255 270)
			(size 0.4064 1.2192)
			(layers "F.Cu" "F.Mask" "F.Paste")
			(net "SAS_EXP_A_PWR0")
		)
		(pad "3" smd rect
			(at -0.65024 -0.8255 270)
			(size 0.4064 1.2192)
			(layers "F.Cu" "F.Mask" "F.Paste")
			(net "GND")
		)
		(pad "4" smd rect
			(at -0.65024 0.8255 270)
			(size 0.4064 1.2192)
			(layers "F.Cu" "F.Mask" "F.Paste")
			(net "DRIVE_PWR0")
		)
		(pad "5" smd rect
			(at 0.65024 0.8255 270)
			(size 0.4064 1.2192)
			(layers "F.Cu" "F.Mask" "F.Paste")
			(net "P3V3")
		)
	)
	(footprint ""
		(layer "F.Cu")
		(at 215.471756 -482.120702 90)
		(property "Reference" "R106"
			(at 0 0 90)
			(layer "F.SilkS")
			(hide yes)
			(effects
				(font
					(size 1.27 1.27)
				)
			)
		)
		(property "Value" "4K7R2J-2-GP"
			(at 0.064008 -3.993896 90)
			(unlocked yes)
			(layer "F.Fab")
			(hide yes)
			(effects
				(font
					(size 1.016 1.016)
					(thickness 0.1524)
				)
			)
		)
		(property "Device Type" "R402H16"
			(at 0.064008 -5.517896 90)
			(unlocked yes)
			(layer "F.Fab")
			(hide yes)
			(effects
				(font
					(size 1.016 1.016)
					(thickness 0.1524)
				)
			)
		)
		(duplicate_pad_numbers_are_jumpers no)
		(fp_line
			(start 0.508 -0.9398)
			(end -0.508 -0.9398)
			(stroke
				(width 0.1524)
				(type default)
			)
			(layer "F.SilkS")
		)
		(fp_line
			(start -0.508 -0.9398)
			(end -0.508 0.9398)
			(stroke
				(width 0.1524)
				(type default)
			)
			(layer "F.SilkS")
		)
		(fp_rect
			(start -0.508 0.9398)
			(end 0.508 -0.9398)
			(stroke
				(width 0)
				(type default)
			)
			(fill no)
			(layer "F.CrtYd")
		)
		(fp_rect
			(start -0.508 0.9398)
			(end 0.508 -0.9398)
			(stroke
				(width 0)
				(type default)
			)
			(fill no)
			(layer "F.Fab")
		)
		(pad "1" smd custom
			(at 0 -0.4445 90)
			(size 0.1397 0.1397)
			(layers "F.Cu" "F.Mask" "F.Paste")
			(net "P3V3")
			(options
				(clearance outline)
				(anchor circle)
			)
			(primitives
				(gr_poly
					(pts
						(arc
							(start -0.1778 -0.2794)
							(mid -0.249642 -0.249642)
							(end -0.2794 -0.1778)
						)
						(arc
							(start -0.2794 0.1778)
							(mid -0.249642 0.249642)
							(end -0.1778 0.2794)
						)
						(arc
							(start 0.1778 0.2794)
							(mid 0.249642 0.249642)
							(end 0.2794 0.1778)
						)
						(arc
							(start 0.2794 -0.1778)
							(mid 0.249642 -0.249642)
							(end 0.1778 -0.2794)
						)
					)
					(width 0)
					(fill yes)
				)
			)
		)
		(pad "2" smd custom
			(at 0 0.4445 90)
			(size 0.1397 0.1397)
			(layers "F.Cu" "F.Mask" "F.Paste")
			(net "HDD_PRSNT_NET0")
			(options
				(clearance outline)
				(anchor circle)
			)
			(primitives
				(gr_poly
					(pts
						(arc
							(start -0.1778 -0.2794)
							(mid -0.249642 -0.249642)
							(end -0.2794 -0.1778)
						)
						(arc
							(start -0.2794 0.1778)
							(mid -0.249642 0.249642)
							(end -0.1778 0.2794)
						)
						(arc
							(start 0.1778 0.2794)
							(mid 0.249642 0.249642)
							(end 0.2794 0.1778)
						)
						(arc
							(start 0.2794 -0.1778)
							(mid 0.249642 -0.249642)
							(end 0.1778 -0.2794)
						)
					)
					(width 0)
					(fill yes)
				)
			)
		)
	)
	(footprint ""
		(layer "F.Cu")
		(at 188.988446 -460.282036)
		(property "Reference" "R348"
			(at 0 0 0)
			(layer "F.SilkS")
			(hide yes)
			(effects
				(font
					(size 1.27 1.27)
				)
			)
		)
		(property "Value" "4K7R2J-2-GP"
			(at 0.064008 -3.993896 0)
			(unlocked yes)
			(layer "F.Fab")
			(hide yes)
			(effects
				(font
					(size 1.016 1.016)
					(thickness 0.1524)
				)
			)
		)
		(property "Device Type" "R402H16"
			(at 0.064008 -5.517896 0)
			(unlocked yes)
			(layer "F.Fab")
			(hide yes)
			(effects
				(font
					(size 1.016 1.016)
					(thickness 0.1524)
				)
			)
		)
		(duplicate_pad_numbers_are_jumpers no)
		(fp_line
			(start -0.508 -0.9398)
			(end -0.508 0.9398)
			(stroke
				(width 0.1524)
				(type default)
			)
			(layer "F.SilkS")
		)
		(fp_line
			(start 0.508 -0.9398)
			(end -0.508 -0.9398)
			(stroke
				(width 0.1524)
				(type default)
			)
			(layer "F.SilkS")
		)
		(fp_rect
			(start -0.508 0.9398)
			(end 0.508 -0.9398)
			(stroke
				(width 0)
				(type default)
			)
			(fill no)
			(layer "F.CrtYd")
		)
		(fp_rect
			(start -0.508 0.9398)
			(end 0.508 -0.9398)
			(stroke
				(width 0)
				(type default)
			)
			(fill no)
			(layer "F.Fab")
		)
		(pad "1" smd custom
			(at 0 -0.4445)
			(size 0.1397 0.1397)
			(layers "F.Cu" "F.Mask" "F.Paste")
			(net "EEPROM_A0")
			(options
				(clearance outline)
				(anchor circle)
			)
			(primitives
				(gr_poly
					(pts
						(arc
							(start -0.1778 -0.2794)
							(mid -0.249642 -0.249642)
							(end -0.2794 -0.1778)
						)
						(arc
							(start -0.2794 0.1778)
							(mid -0.249642 0.249642)
							(end -0.1778 0.2794)
						)
						(arc
							(start 0.1778 0.2794)
							(mid 0.249642 0.249642)
							(end 0.2794 0.1778)
						)
						(arc
							(start 0.2794 -0.1778)
							(mid 0.249642 -0.249642)
							(end 0.1778 -0.2794)
						)
					)
					(width 0)
					(fill yes)
				)
			)
		)
		(pad "2" smd custom
			(at 0 0.4445)
			(size 0.1397 0.1397)
			(layers "F.Cu" "F.Mask" "F.Paste")
			(net "GND")
			(options
				(clearance outline)
				(anchor circle)
			)
			(primitives
				(gr_poly
					(pts
						(arc
							(start -0.1778 -0.2794)
							(mid -0.249642 -0.249642)
							(end -0.2794 -0.1778)
						)
						(arc
							(start -0.2794 0.1778)
							(mid -0.249642 0.249642)
							(end -0.1778 0.2794)
						)
						(arc
							(start 0.1778 0.2794)
							(mid 0.249642 0.249642)
							(end 0.2794 0.1778)
						)
						(arc
							(start 0.2794 -0.1778)
							(mid 0.249642 -0.249642)
							(end 0.1778 -0.2794)
						)
					)
					(width 0)
					(fill yes)
				)
			)
		)
	)
	(footprint ""
		(layer "F.Cu")
		(at 41.655746 -326.926702)
		(property "Reference" "Q23"
			(at 0 0 0)
			(layer "F.SilkS")
			(hide yes)
			(effects
				(font
					(size 1.27 1.27)
				)
			)
		)
		(property "Value" "AO4406AL-GP"
			(at -3.707384 -1.5367 0)
			(unlocked yes)
			(layer "F.Fab")
			(hide yes)
			(effects
				(font
					(size 1.016 1.016)
					(thickness 0.1524)
				)
			)
		)
		(property "Device Type" "SOIC8H69"
			(at -3.707384 -3.0607 0)
			(unlocked yes)
			(layer "F.Fab")
			(hide yes)
			(effects
				(font
					(size 1.016 1.016)
					(thickness 0.1524)
				)
			)
		)
		(duplicate_pad_numbers_are_jumpers no)
		(fp_line
			(start -2.7432 -1.4224)
			(end -2.7432 1.4224)
			(stroke
				(width 0.1524)
				(type default)
			)
			(layer "F.SilkS")
		)
		(fp_line
			(start -2.7432 1.4224)
			(end -2.6416 1.4224)
			(stroke
				(width 0.1524)
				(type default)
			)
			(layer "F.SilkS")
		)
		(fp_line
			(start -2.7432 1.4224)
			(end 2.1336 1.4224)
			(stroke
				(width 0.1524)
				(type default)
			)
			(layer "F.SilkS")
		)
		(fp_line
			(start -2.7178 -0.508)
			(end -2.1844 -0.0508)
			(stroke
				(width 0.1524)
				(type default)
			)
			(layer "F.SilkS")
		)
		(fp_line
			(start -2.6289 3.4417)
			(end -2.6289 1.4732)
			(stroke
				(width 0.381)
				(type default)
			)
			(layer "F.SilkS")
		)
		(fp_line
			(start -2.1844 -0.0508)
			(end -2.7178 0.508)
			(stroke
				(width 0.1524)
				(type default)
			)
			(layer "F.SilkS")
		)
		(fp_line
			(start 2.1336 -1.4224)
			(end -2.7432 -1.4224)
			(stroke
				(width 0.1524)
				(type default)
			)
			(layer "F.SilkS")
		)
		(fp_line
			(start 2.1336 1.4224)
			(end 2.1336 -1.4224)
			(stroke
				(width 0.1524)
				(type default)
			)
			(layer "F.SilkS")
		)
		(fp_poly
			(pts
				(xy -2.2098 -1.4224) (xy -2.2098 1.4224) (xy 2.2098 1.4224) (xy 2.2098 -1.4224)
			)
			(stroke
				(width 0)
				(type default)
			)
			(fill yes)
			(layer "F.SilkS")
		)
		(fp_rect
			(start -2.450084 2.999994)
			(end 2.450084 -2.999994)
			(stroke
				(width 0)
				(type default)
			)
			(fill no)
			(layer "F.CrtYd")
		)
		(fp_poly
			(pts
				(xy -2.8194 3.6322) (xy -2.8194 -3.6322) (xy 2.8194 -3.6322) (xy 2.8194 1.18364) (xy 2.450084 1.18364)
				(xy 2.450084 -2.999994) (xy -2.450084 -2.999994) (xy -2.450084 2.999994) (xy 2.450084 2.999994)
				(xy 2.450084 1.18618) (xy 2.8194 1.18618) (xy 2.8194 3.6322)
			)
			(stroke
				(width 0)
				(type default)
			)
			(fill no)
			(layer "F.CrtYd")
		)
		(fp_rect
			(start -2.8194 3.6322)
			(end 2.8194 -3.6322)
			(stroke
				(width 0)
				(type default)
			)
			(fill no)
			(layer "F.Fab")
		)
		(pad "1" smd rect
			(at -1.905 2.54)
			(size 0.635 1.651)
			(layers "F.Cu" "F.Mask" "F.Paste")
			(net "P5V_HDD11")
		)
		(pad "2" smd rect
			(at -0.635 2.54)
			(size 0.635 1.651)
			(layers "F.Cu" "F.Mask" "F.Paste")
			(net "P5V_HDD11")
		)
		(pad "3" smd rect
			(at 0.635 2.54)
			(size 0.635 1.651)
			(layers "F.Cu" "F.Mask" "F.Paste")
			(net "P5V_HDD11")
		)
		(pad "4" smd rect
			(at 1.905 2.54)
			(size 0.635 1.651)
			(layers "F.Cu" "F.Mask" "F.Paste")
			(net "SW_HDD11_P")
		)
		(pad "5" smd rect
			(at 1.905 -2.54)
			(size 0.635 1.651)
			(layers "F.Cu" "F.Mask" "F.Paste")
			(net "P5VC")
		)
		(pad "6" smd rect
			(at 0.635 -2.54)
			(size 0.635 1.651)
			(layers "F.Cu" "F.Mask" "F.Paste")
			(net "P5VC")
		)
		(pad "7" smd rect
			(at -0.635 -2.54)
			(size 0.635 1.651)
			(layers "F.Cu" "F.Mask" "F.Paste")
			(net "P5VC")
		)
		(pad "8" smd rect
			(at -1.905 -2.54)
			(size 0.635 1.651)
			(layers "F.Cu" "F.Mask" "F.Paste")
			(net "P5VC")
		)
	)
	(footprint ""
		(layer "F.Cu")
		(at 95.757746 -13.4747 90)
		(property "Reference" "R476"
			(at 0 0 90)
			(layer "F.SilkS")
			(hide yes)
			(effects
				(font
					(size 1.27 1.27)
				)
			)
		)
		(property "Value" "4K7R2J-2-GP"
			(at 0.064008 -3.993896 90)
			(unlocked yes)
			(layer "F.Fab")
			(hide yes)
			(effects
				(font
					(size 1.016 1.016)
					(thickness 0.1524)
				)
			)
		)
		(property "Device Type" "R402H16"
			(at 0.064008 -5.517896 90)
			(unlocked yes)
			(layer "F.Fab")
			(hide yes)
			(effects
				(font
					(size 1.016 1.016)
					(thickness 0.1524)
				)
			)
		)
		(duplicate_pad_numbers_are_jumpers no)
		(fp_line
			(start 0.508 -0.9398)
			(end -0.508 -0.9398)
			(stroke
				(width 0.1524)
				(type default)
			)
			(layer "F.SilkS")
		)
		(fp_line
			(start -0.508 -0.9398)
			(end -0.508 0.9398)
			(stroke
				(width 0.1524)
				(type default)
			)
			(layer "F.SilkS")
		)
		(fp_rect
			(start -0.508 0.9398)
			(end 0.508 -0.9398)
			(stroke
				(width 0)
				(type default)
			)
			(fill no)
			(layer "F.CrtYd")
		)
		(fp_rect
			(start -0.508 0.9398)
			(end 0.508 -0.9398)
			(stroke
				(width 0)
				(type default)
			)
			(fill no)
			(layer "F.Fab")
		)
		(pad "1" smd custom
			(at 0 -0.4445 90)
			(size 0.1397 0.1397)
			(layers "F.Cu" "F.Mask" "F.Paste")
			(net "P3V3")
			(options
				(clearance outline)
				(anchor circle)
			)
			(primitives
				(gr_poly
					(pts
						(arc
							(start -0.1778 -0.2794)
							(mid -0.249642 -0.249642)
							(end -0.2794 -0.1778)
						)
						(arc
							(start -0.2794 0.1778)
							(mid -0.249642 0.249642)
							(end -0.1778 0.2794)
						)
						(arc
							(start 0.1778 0.2794)
							(mid 0.249642 0.249642)
							(end 0.2794 0.1778)
						)
						(arc
							(start 0.2794 -0.1778)
							(mid 0.249642 -0.249642)
							(end 0.1778 -0.2794)
						)
					)
					(width 0)
					(fill yes)
				)
			)
		)
		(pad "2" smd custom
			(at 0 0.4445 90)
			(size 0.1397 0.1397)
			(layers "F.Cu" "F.Mask" "F.Paste")
			(net "SAS_EXP_A_PWR14")
			(options
				(clearance outline)
				(anchor circle)
			)
			(primitives
				(gr_poly
					(pts
						(arc
							(start -0.1778 -0.2794)
							(mid -0.249642 -0.249642)
							(end -0.2794 -0.1778)
						)
						(arc
							(start -0.2794 0.1778)
							(mid -0.249642 0.249642)
							(end -0.1778 0.2794)
						)
						(arc
							(start 0.1778 0.2794)
							(mid 0.249642 0.249642)
							(end 0.2794 0.1778)
						)
						(arc
							(start 0.2794 -0.1778)
							(mid 0.249642 -0.249642)
							(end 0.1778 -0.2794)
						)
					)
					(width 0)
					(fill yes)
				)
			)
		)
	)
	(footprint ""
		(layer "F.Cu")
		(at 72.389746 -87.2617)
		(property "Reference" "R457"
			(at 0 0 0)
			(layer "F.SilkS")
			(hide yes)
			(effects
				(font
					(size 1.27 1.27)
				)
			)
		)
		(property "Value" "4K7R2J-2-GP"
			(at 0.064008 -3.993896 0)
			(unlocked yes)
			(layer "F.Fab")
			(hide yes)
			(effects
				(font
					(size 1.016 1.016)
					(thickness 0.1524)
				)
			)
		)
		(property "Device Type" "R402H16"
			(at 0.064008 -5.517896 0)
			(unlocked yes)
			(layer "F.Fab")
			(hide yes)
			(effects
				(font
					(size 1.016 1.016)
					(thickness 0.1524)
				)
			)
		)
		(duplicate_pad_numbers_are_jumpers no)
		(fp_line
			(start -0.508 -0.9398)
			(end -0.508 0.9398)
			(stroke
				(width 0.1524)
				(type default)
			)
			(layer "F.SilkS")
		)
		(fp_line
			(start 0.508 -0.9398)
			(end -0.508 -0.9398)
			(stroke
				(width 0.1524)
				(type default)
			)
			(layer "F.SilkS")
		)
		(fp_rect
			(start -0.508 0.9398)
			(end 0.508 -0.9398)
			(stroke
				(width 0)
				(type default)
			)
			(fill no)
			(layer "F.CrtYd")
		)
		(fp_rect
			(start -0.508 0.9398)
			(end 0.508 -0.9398)
			(stroke
				(width 0)
				(type default)
			)
			(fill no)
			(layer "F.Fab")
		)
		(pad "1" smd custom
			(at 0 -0.4445)
			(size 0.1397 0.1397)
			(layers "F.Cu" "F.Mask" "F.Paste")
			(net "P3V3")
			(options
				(clearance outline)
				(anchor circle)
			)
			(primitives
				(gr_poly
					(pts
						(arc
							(start -0.1778 -0.2794)
							(mid -0.249642 -0.249642)
							(end -0.2794 -0.1778)
						)
						(arc
							(start -0.2794 0.1778)
							(mid -0.249642 0.249642)
							(end -0.1778 0.2794)
						)
						(arc
							(start 0.1778 0.2794)
							(mid 0.249642 0.249642)
							(end 0.2794 0.1778)
						)
						(arc
							(start 0.2794 -0.1778)
							(mid 0.249642 -0.249642)
							(end 0.1778 -0.2794)
						)
					)
					(width 0)
					(fill yes)
				)
			)
		)
		(pad "2" smd custom
			(at 0 0.4445)
			(size 0.1397 0.1397)
			(layers "F.Cu" "F.Mask" "F.Paste")
			(net "SAS2X28_B_HDD9_FLT")
			(options
				(clearance outline)
				(anchor circle)
			)
			(primitives
				(gr_poly
					(pts
						(arc
							(start -0.1778 -0.2794)
							(mid -0.249642 -0.249642)
							(end -0.2794 -0.1778)
						)
						(arc
							(start -0.2794 0.1778)
							(mid -0.249642 0.249642)
							(end -0.1778 0.2794)
						)
						(arc
							(start 0.1778 0.2794)
							(mid 0.249642 0.249642)
							(end 0.2794 0.1778)
						)
						(arc
							(start 0.2794 -0.1778)
							(mid 0.249642 -0.249642)
							(end 0.1778 -0.2794)
						)
					)
					(width 0)
					(fill yes)
				)
			)
		)
	)
	(footprint ""
		(layer "F.Cu")
		(at 14.604746 -52.7177 -90)
		(property "Reference" "R298"
			(at 0 0 270)
			(layer "F.SilkS")
			(hide yes)
			(effects
				(font
					(size 1.27 1.27)
				)
			)
		)
		(property "Value" "0R2J-2-GP"
			(at 0.064008 -3.993896 270)
			(unlocked yes)
			(layer "F.Fab")
			(hide yes)
			(effects
				(font
					(size 1.016 1.016)
					(thickness 0.1524)
				)
			)
		)
		(property "Device Type" "R402H16"
			(at 0.064008 -5.517896 270)
			(unlocked yes)
			(layer "F.Fab")
			(hide yes)
			(effects
				(font
					(size 1.016 1.016)
					(thickness 0.1524)
				)
			)
		)
		(duplicate_pad_numbers_are_jumpers no)
		(fp_line
			(start -0.508 -0.9398)
			(end -0.508 0.9398)
			(stroke
				(width 0.1524)
				(type default)
			)
			(layer "F.SilkS")
		)
		(fp_line
			(start 0.508 -0.9398)
			(end -0.508 -0.9398)
			(stroke
				(width 0.1524)
				(type default)
			)
			(layer "F.SilkS")
		)
		(fp_rect
			(start -0.508 0.9398)
			(end 0.508 -0.9398)
			(stroke
				(width 0)
				(type default)
			)
			(fill no)
			(layer "F.CrtYd")
		)
		(fp_rect
			(start -0.508 0.9398)
			(end 0.508 -0.9398)
			(stroke
				(width 0)
				(type default)
			)
			(fill no)
			(layer "F.Fab")
		)
		(pad "1" smd custom
			(at 0 -0.4445 270)
			(size 0.1397 0.1397)
			(layers "F.Cu" "F.Mask" "F.Paste")
			(net "DRV_ACT_NET14")
			(options
				(clearance outline)
				(anchor circle)
			)
			(primitives
				(gr_poly
					(pts
						(arc
							(start -0.1778 -0.2794)
							(mid -0.249642 -0.249642)
							(end -0.2794 -0.1778)
						)
						(arc
							(start -0.2794 0.1778)
							(mid -0.249642 0.249642)
							(end -0.1778 0.2794)
						)
						(arc
							(start 0.1778 0.2794)
							(mid 0.249642 0.249642)
							(end 0.2794 0.1778)
						)
						(arc
							(start 0.2794 -0.1778)
							(mid 0.249642 -0.249642)
							(end 0.1778 -0.2794)
						)
					)
					(width 0)
					(fill yes)
				)
			)
		)
		(pad "2" smd custom
			(at 0 0.4445 270)
			(size 0.1397 0.1397)
			(layers "F.Cu" "F.Mask" "F.Paste")
			(net "DRIVE_ACT_14")
			(options
				(clearance outline)
				(anchor circle)
			)
			(primitives
				(gr_poly
					(pts
						(arc
							(start -0.1778 -0.2794)
							(mid -0.249642 -0.249642)
							(end -0.2794 -0.1778)
						)
						(arc
							(start -0.2794 0.1778)
							(mid -0.249642 0.249642)
							(end -0.1778 0.2794)
						)
						(arc
							(start 0.1778 0.2794)
							(mid 0.249642 0.249642)
							(end 0.2794 0.1778)
						)
						(arc
							(start 0.2794 -0.1778)
							(mid 0.249642 -0.249642)
							(end 0.1778 -0.2794)
						)
					)
					(width 0)
					(fill yes)
				)
			)
		)
	)
	(footprint ""
		(layer "F.Cu")
		(at 8.788146 -403.9489)
		(property "Reference" "R355"
			(at 0 0 0)
			(layer "F.SilkS")
			(hide yes)
			(effects
				(font
					(size 1.27 1.27)
				)
			)
		)
		(property "Value" "10KR2F-2-GP"
			(at 0.064008 -3.993896 0)
			(unlocked yes)
			(layer "F.Fab")
			(hide yes)
			(effects
				(font
					(size 1.016 1.016)
					(thickness 0.1524)
				)
			)
		)
		(property "Device Type" "R402H16"
			(at 0.064008 -5.517896 0)
			(unlocked yes)
			(layer "F.Fab")
			(hide yes)
			(effects
				(font
					(size 1.016 1.016)
					(thickness 0.1524)
				)
			)
		)
		(duplicate_pad_numbers_are_jumpers no)
		(fp_line
			(start -0.508 -0.9398)
			(end -0.508 0.9398)
			(stroke
				(width 0.1524)
				(type default)
			)
			(layer "F.SilkS")
		)
		(fp_line
			(start 0.508 -0.9398)
			(end -0.508 -0.9398)
			(stroke
				(width 0.1524)
				(type default)
			)
			(layer "F.SilkS")
		)
		(fp_rect
			(start -0.508 0.9398)
			(end 0.508 -0.9398)
			(stroke
				(width 0)
				(type default)
			)
			(fill no)
			(layer "F.CrtYd")
		)
		(fp_rect
			(start -0.508 0.9398)
			(end 0.508 -0.9398)
			(stroke
				(width 0)
				(type default)
			)
			(fill no)
			(layer "F.Fab")
		)
		(pad "1" smd custom
			(at 0 -0.4445)
			(size 0.1397 0.1397)
			(layers "F.Cu" "F.Mask" "F.Paste")
			(net "P3V3")
			(options
				(clearance outline)
				(anchor circle)
			)
			(primitives
				(gr_poly
					(pts
						(arc
							(start -0.1778 -0.2794)
							(mid -0.249642 -0.249642)
							(end -0.2794 -0.1778)
						)
						(arc
							(start -0.2794 0.1778)
							(mid -0.249642 0.249642)
							(end -0.1778 0.2794)
						)
						(arc
							(start 0.1778 0.2794)
							(mid 0.249642 0.249642)
							(end 0.2794 0.1778)
						)
						(arc
							(start 0.2794 -0.1778)
							(mid 0.249642 -0.249642)
							(end 0.1778 -0.2794)
						)
					)
					(width 0)
					(fill yes)
				)
			)
		)
		(pad "2" smd custom
			(at 0 0.4445)
			(size 0.1397 0.1397)
			(layers "F.Cu" "F.Mask" "F.Paste")
			(net "TEMP_SENSOR_A_ADDR0&ID")
			(options
				(clearance outline)
				(anchor circle)
			)
			(primitives
				(gr_poly
					(pts
						(arc
							(start -0.1778 -0.2794)
							(mid -0.249642 -0.249642)
							(end -0.2794 -0.1778)
						)
						(arc
							(start -0.2794 0.1778)
							(mid -0.249642 0.249642)
							(end -0.1778 0.2794)
						)
						(arc
							(start 0.1778 0.2794)
							(mid 0.249642 0.249642)
							(end 0.2794 0.1778)
						)
						(arc
							(start 0.2794 -0.1778)
							(mid 0.249642 -0.249642)
							(end 0.1778 -0.2794)
						)
					)
					(width 0)
					(fill yes)
				)
			)
		)
	)
	(footprint ""
		(layer "F.Cu")
		(at 212.724746 -42.5577 90)
		(property "Reference" "C343"
			(at 0 0 90)
			(layer "F.SilkS")
			(hide yes)
			(effects
				(font
					(size 1.27 1.27)
				)
			)
		)
		(property "Value" "SCD1U10V2KX-5GP"
			(at 1.1811 -2.7051 90)
			(unlocked yes)
			(layer "F.Fab")
			(hide yes)
			(effects
				(font
					(size 1.016 1.016)
					(thickness 0.1524)
				)
			)
		)
		(property "Device Type" "C402H22"
			(at 1.1811 -4.2291 90)
			(unlocked yes)
			(layer "F.Fab")
			(hide yes)
			(effects
				(font
					(size 1.016 1.016)
					(thickness 0.1524)
				)
			)
		)
		(duplicate_pad_numbers_are_jumpers no)
		(fp_rect
			(start -0.4318 0.9525)
			(end 0.4318 -0.9525)
			(stroke
				(width 0)
				(type default)
			)
			(fill no)
			(layer "F.CrtYd")
		)
		(fp_rect
			(start -0.4318 0.9525)
			(end 0.4318 -0.9525)
			(stroke
				(width 0)
				(type default)
			)
			(fill no)
			(layer "F.Fab")
		)
		(pad "1" smd custom
			(at 0 -0.4445 90)
			(size 0.1524 0.1524)
			(layers "F.Cu" "F.Mask" "F.Paste")
			(net "P3V3")
			(options
				(clearance outline)
				(anchor circle)
			)
			(primitives
				(gr_poly
					(pts
						(arc
							(start 0.3048 -0.2032)
							(mid 0.275042 -0.275042)
							(end 0.2032 -0.3048)
						)
						(arc
							(start -0.2032 -0.3048)
							(mid -0.275042 -0.275042)
							(end -0.3048 -0.2032)
						)
						(arc
							(start -0.3048 0.2032)
							(mid -0.275042 0.275042)
							(end -0.2032 0.3048)
						)
						(arc
							(start 0.2032 0.3048)
							(mid 0.275042 0.275042)
							(end 0.3048 0.2032)
						)
					)
					(width 0)
					(fill yes)
				)
			)
		)
		(pad "2" smd custom
			(at 0 0.4445 90)
			(size 0.1524 0.1524)
			(layers "F.Cu" "F.Mask" "F.Paste")
			(net "GND")
			(options
				(clearance outline)
				(anchor circle)
			)
			(primitives
				(gr_poly
					(pts
						(arc
							(start 0.3048 -0.2032)
							(mid 0.275042 -0.275042)
							(end 0.2032 -0.3048)
						)
						(arc
							(start -0.2032 -0.3048)
							(mid -0.275042 -0.275042)
							(end -0.3048 -0.2032)
						)
						(arc
							(start -0.3048 0.2032)
							(mid -0.275042 0.275042)
							(end -0.2032 0.3048)
						)
						(arc
							(start 0.2032 0.3048)
							(mid 0.275042 0.275042)
							(end 0.3048 0.2032)
						)
					)
					(width 0)
					(fill yes)
				)
			)
		)
	)
	(footprint ""
		(layer "F.Cu")
		(at 217.888058 -386.028184 180)
		(property "Reference" "C122"
			(at 0 0 180)
			(layer "F.SilkS")
			(hide yes)
			(effects
				(font
					(size 1.27 1.27)
				)
			)
		)
		(property "Value" "SC1U16V3KX-5GP"
			(at 0 -2.8194 180)
			(unlocked yes)
			(layer "F.Fab")
			(hide yes)
			(effects
				(font
					(size 1.016 1.016)
					(thickness 0.1524)
				)
			)
		)
		(property "Device Type" "C603H36"
			(at 0 -4.3434 180)
			(unlocked yes)
			(layer "F.Fab")
			(hide yes)
			(effects
				(font
					(size 1.016 1.016)
					(thickness 0.1524)
				)
			)
		)
		(duplicate_pad_numbers_are_jumpers no)
		(fp_line
			(start 0.508 0)
			(end -0.508 0)
			(stroke
				(width 0.2032)
				(type default)
			)
			(layer "F.SilkS")
		)
		(fp_rect
			(start -0.5842 1.3335)
			(end 0.5842 -1.3335)
			(stroke
				(width 0)
				(type default)
			)
			(fill no)
			(layer "F.CrtYd")
		)
		(fp_rect
			(start -0.5842 1.3335)
			(end 0.5842 -1.3335)
			(stroke
				(width 0)
				(type default)
			)
			(fill no)
			(layer "F.Fab")
		)
		(pad "1" smd custom
			(at 0 -0.762 180)
			(size 0.2159 0.2159)
			(layers "F.Cu" "F.Mask" "F.Paste")
			(net "P5V_HDD1")
			(options
				(clearance outline)
				(anchor circle)
			)
			(primitives
				(gr_poly
					(pts
						(arc
							(start -0.3302 -0.4318)
							(mid -0.402042 -0.402042)
							(end -0.4318 -0.3302)
						)
						(arc
							(start -0.4318 0.3302)
							(mid -0.402042 0.402042)
							(end -0.3302 0.4318)
						)
						(arc
							(start 0.3302 0.4318)
							(mid 0.402042 0.402042)
							(end 0.4318 0.3302)
						)
						(arc
							(start 0.4318 -0.3302)
							(mid 0.402042 -0.402042)
							(end 0.3302 -0.4318)
						)
					)
					(width 0)
					(fill yes)
				)
			)
		)
		(pad "2" smd custom
			(at 0 0.762 180)
			(size 0.2159 0.2159)
			(layers "F.Cu" "F.Mask" "F.Paste")
			(net "GND")
			(options
				(clearance outline)
				(anchor circle)
			)
			(primitives
				(gr_poly
					(pts
						(arc
							(start -0.3302 -0.4318)
							(mid -0.402042 -0.402042)
							(end -0.4318 -0.3302)
						)
						(arc
							(start -0.4318 0.3302)
							(mid -0.402042 0.402042)
							(end -0.3302 0.4318)
						)
						(arc
							(start 0.3302 0.4318)
							(mid 0.402042 0.402042)
							(end 0.4318 0.3302)
						)
						(arc
							(start 0.4318 -0.3302)
							(mid 0.402042 -0.402042)
							(end 0.3302 -0.4318)
						)
					)
					(width 0)
					(fill yes)
				)
			)
		)
	)
	(footprint ""
		(layer "F.Cu")
		(at 32.86506 -373.187214 -90)
		(property "Reference" "C201"
			(at 0 0 270)
			(layer "F.SilkS")
			(hide yes)
			(effects
				(font
					(size 1.27 1.27)
				)
			)
		)
		(property "Value" "SCD01U50V2KX-1GP"
			(at 1.1811 -2.7051 270)
			(unlocked yes)
			(layer "F.Fab")
			(hide yes)
			(effects
				(font
					(size 1.016 1.016)
					(thickness 0.1524)
				)
			)
		)
		(property "Device Type" "C402H22"
			(at 1.1811 -4.2291 270)
			(unlocked yes)
			(layer "F.Fab")
			(hide yes)
			(effects
				(font
					(size 1.016 1.016)
					(thickness 0.1524)
				)
			)
		)
		(duplicate_pad_numbers_are_jumpers no)
		(fp_rect
			(start -0.4318 0.9525)
			(end 0.4318 -0.9525)
			(stroke
				(width 0)
				(type default)
			)
			(fill no)
			(layer "F.CrtYd")
		)
		(fp_rect
			(start -0.4318 0.9525)
			(end 0.4318 -0.9525)
			(stroke
				(width 0)
				(type default)
			)
			(fill no)
			(layer "F.Fab")
		)
		(pad "1" smd custom
			(at 0 -0.4445 270)
			(size 0.1524 0.1524)
			(layers "F.Cu" "F.Mask" "F.Paste")
			(net "SAS2X28_DRIVE_RX_P_B6")
			(options
				(clearance outline)
				(anchor circle)
			)
			(primitives
				(gr_poly
					(pts
						(arc
							(start 0.3048 -0.2032)
							(mid 0.275042 -0.275042)
							(end 0.2032 -0.3048)
						)
						(arc
							(start -0.2032 -0.3048)
							(mid -0.275042 -0.275042)
							(end -0.3048 -0.2032)
						)
						(arc
							(start -0.3048 0.2032)
							(mid -0.275042 0.275042)
							(end -0.2032 0.3048)
						)
						(arc
							(start 0.2032 0.3048)
							(mid 0.275042 0.275042)
							(end 0.3048 0.2032)
						)
					)
					(width 0)
					(fill yes)
				)
			)
		)
		(pad "2" smd custom
			(at 0 0.4445 270)
			(size 0.1524 0.1524)
			(layers "F.Cu" "F.Mask" "F.Paste")
			(net "SAS2X28_B_HDD6_RX_+")
			(options
				(clearance outline)
				(anchor circle)
			)
			(primitives
				(gr_poly
					(pts
						(arc
							(start 0.3048 -0.2032)
							(mid 0.275042 -0.275042)
							(end 0.2032 -0.3048)
						)
						(arc
							(start -0.2032 -0.3048)
							(mid -0.275042 -0.275042)
							(end -0.3048 -0.2032)
						)
						(arc
							(start -0.3048 0.2032)
							(mid -0.275042 0.275042)
							(end -0.2032 0.3048)
						)
						(arc
							(start 0.2032 0.3048)
							(mid 0.275042 0.275042)
							(end 0.3048 0.2032)
						)
					)
					(width 0)
					(fill yes)
				)
			)
		)
	)
	(footprint ""
		(layer "F.Cu")
		(at 64.3128 -390.5758)
		(property "Reference" "C211"
			(at 0 0 0)
			(layer "F.SilkS")
			(hide yes)
			(effects
				(font
					(size 1.27 1.27)
				)
			)
		)
		(property "Value" "SC1U25V3KX-1-GP"
			(at 0 -2.8194 0)
			(unlocked yes)
			(layer "F.Fab")
			(hide yes)
			(effects
				(font
					(size 1.016 1.016)
					(thickness 0.1524)
				)
			)
		)
		(property "Device Type" "C603H36"
			(at 0 -4.3434 0)
			(unlocked yes)
			(layer "F.Fab")
			(hide yes)
			(effects
				(font
					(size 1.016 1.016)
					(thickness 0.1524)
				)
			)
		)
		(duplicate_pad_numbers_are_jumpers no)
		(fp_line
			(start 0.508 0)
			(end -0.508 0)
			(stroke
				(width 0.2032)
				(type default)
			)
			(layer "F.SilkS")
		)
		(fp_rect
			(start -0.5842 1.3335)
			(end 0.5842 -1.3335)
			(stroke
				(width 0)
				(type default)
			)
			(fill no)
			(layer "F.CrtYd")
		)
		(fp_rect
			(start -0.5842 1.3335)
			(end 0.5842 -1.3335)
			(stroke
				(width 0)
				(type default)
			)
			(fill no)
			(layer "F.Fab")
		)
		(pad "1" smd custom
			(at 0 -0.762)
			(size 0.2159 0.2159)
			(layers "F.Cu" "F.Mask" "F.Paste")
			(net "P12V_HDD6")
			(options
				(clearance outline)
				(anchor circle)
			)
			(primitives
				(gr_poly
					(pts
						(arc
							(start -0.3302 -0.4318)
							(mid -0.402042 -0.402042)
							(end -0.4318 -0.3302)
						)
						(arc
							(start -0.4318 0.3302)
							(mid -0.402042 0.402042)
							(end -0.3302 0.4318)
						)
						(arc
							(start 0.3302 0.4318)
							(mid 0.402042 0.402042)
							(end 0.4318 0.3302)
						)
						(arc
							(start 0.4318 -0.3302)
							(mid 0.402042 -0.402042)
							(end 0.3302 -0.4318)
						)
					)
					(width 0)
					(fill yes)
				)
			)
		)
		(pad "2" smd custom
			(at 0 0.762)
			(size 0.2159 0.2159)
			(layers "F.Cu" "F.Mask" "F.Paste")
			(net "GND")
			(options
				(clearance outline)
				(anchor circle)
			)
			(primitives
				(gr_poly
					(pts
						(arc
							(start -0.3302 -0.4318)
							(mid -0.402042 -0.402042)
							(end -0.4318 -0.3302)
						)
						(arc
							(start -0.4318 0.3302)
							(mid -0.402042 0.402042)
							(end -0.3302 0.4318)
						)
						(arc
							(start 0.3302 0.4318)
							(mid 0.402042 0.402042)
							(end 0.4318 0.3302)
						)
						(arc
							(start 0.4318 -0.3302)
							(mid 0.402042 -0.402042)
							(end 0.3302 -0.4318)
						)
					)
					(width 0)
					(fill yes)
				)
			)
		)
	)
	(footprint ""
		(layer "F.Cu")
		(at 207.009746 -452.6407 180)
		(property "Reference" "R328"
			(at 0 0 180)
			(layer "F.SilkS")
			(hide yes)
			(effects
				(font
					(size 1.27 1.27)
				)
			)
		)
		(property "Value" "4K7R2J-2-GP"
			(at 0.064008 -3.993896 180)
			(unlocked yes)
			(layer "F.Fab")
			(hide yes)
			(effects
				(font
					(size 1.016 1.016)
					(thickness 0.1524)
				)
			)
		)
		(property "Device Type" "R402H16"
			(at 0.064008 -5.517896 180)
			(unlocked yes)
			(layer "F.Fab")
			(hide yes)
			(effects
				(font
					(size 1.016 1.016)
					(thickness 0.1524)
				)
			)
		)
		(duplicate_pad_numbers_are_jumpers no)
		(fp_line
			(start 0.508 -0.9398)
			(end -0.508 -0.9398)
			(stroke
				(width 0.1524)
				(type default)
			)
			(layer "F.SilkS")
		)
		(fp_line
			(start -0.508 -0.9398)
			(end -0.508 0.9398)
			(stroke
				(width 0.1524)
				(type default)
			)
			(layer "F.SilkS")
		)
		(fp_rect
			(start -0.508 0.9398)
			(end 0.508 -0.9398)
			(stroke
				(width 0)
				(type default)
			)
			(fill no)
			(layer "F.CrtYd")
		)
		(fp_rect
			(start -0.508 0.9398)
			(end 0.508 -0.9398)
			(stroke
				(width 0)
				(type default)
			)
			(fill no)
			(layer "F.Fab")
		)
		(pad "1" smd custom
			(at 0 -0.4445 180)
			(size 0.1397 0.1397)
			(layers "F.Cu" "F.Mask" "F.Paste")
			(net "P3V3")
			(options
				(clearance outline)
				(anchor circle)
			)
			(primitives
				(gr_poly
					(pts
						(arc
							(start -0.1778 -0.2794)
							(mid -0.249642 -0.249642)
							(end -0.2794 -0.1778)
						)
						(arc
							(start -0.2794 0.1778)
							(mid -0.249642 0.249642)
							(end -0.1778 0.2794)
						)
						(arc
							(start 0.1778 0.2794)
							(mid 0.249642 0.249642)
							(end 0.2794 0.1778)
						)
						(arc
							(start 0.2794 -0.1778)
							(mid 0.249642 -0.249642)
							(end 0.1778 -0.2794)
						)
					)
					(width 0)
					(fill yes)
				)
			)
		)
		(pad "2" smd custom
			(at 0 0.4445 180)
			(size 0.1397 0.1397)
			(layers "F.Cu" "F.Mask" "F.Paste")
			(net "I2C_B_TMP3_A2")
			(options
				(clearance outline)
				(anchor circle)
			)
			(primitives
				(gr_poly
					(pts
						(arc
							(start -0.1778 -0.2794)
							(mid -0.249642 -0.249642)
							(end -0.2794 -0.1778)
						)
						(arc
							(start -0.2794 0.1778)
							(mid -0.249642 0.249642)
							(end -0.1778 0.2794)
						)
						(arc
							(start 0.1778 0.2794)
							(mid 0.249642 0.249642)
							(end 0.2794 0.1778)
						)
						(arc
							(start 0.2794 -0.1778)
							(mid 0.249642 -0.249642)
							(end 0.1778 -0.2794)
						)
					)
					(width 0)
					(fill yes)
				)
			)
		)
	)
	(footprint ""
		(layer "F.Cu")
		(at 79.304134 -495.022886 -90)
		(property "Reference" "R183"
			(at 0 0 270)
			(layer "F.SilkS")
			(hide yes)
			(effects
				(font
					(size 1.27 1.27)
				)
			)
		)
		(property "Value" "0R2J-2-GP"
			(at 0.064008 -3.993896 270)
			(unlocked yes)
			(layer "F.Fab")
			(hide yes)
			(effects
				(font
					(size 1.016 1.016)
					(thickness 0.1524)
				)
			)
		)
		(property "Device Type" "R402H16"
			(at 0.064008 -5.517896 270)
			(unlocked yes)
			(layer "F.Fab")
			(hide yes)
			(effects
				(font
					(size 1.016 1.016)
					(thickness 0.1524)
				)
			)
		)
		(duplicate_pad_numbers_are_jumpers no)
		(fp_line
			(start -0.508 -0.9398)
			(end -0.508 0.9398)
			(stroke
				(width 0.1524)
				(type default)
			)
			(layer "F.SilkS")
		)
		(fp_line
			(start 0.508 -0.9398)
			(end -0.508 -0.9398)
			(stroke
				(width 0.1524)
				(type default)
			)
			(layer "F.SilkS")
		)
		(fp_rect
			(start -0.508 0.9398)
			(end 0.508 -0.9398)
			(stroke
				(width 0)
				(type default)
			)
			(fill no)
			(layer "F.CrtYd")
		)
		(fp_rect
			(start -0.508 0.9398)
			(end 0.508 -0.9398)
			(stroke
				(width 0)
				(type default)
			)
			(fill no)
			(layer "F.Fab")
		)
		(pad "1" smd custom
			(at 0 -0.4445 270)
			(size 0.1397 0.1397)
			(layers "F.Cu" "F.Mask" "F.Paste")
			(net "DRIVE_PWR5")
			(options
				(clearance outline)
				(anchor circle)
			)
			(primitives
				(gr_poly
					(pts
						(arc
							(start -0.1778 -0.2794)
							(mid -0.249642 -0.249642)
							(end -0.2794 -0.1778)
						)
						(arc
							(start -0.2794 0.1778)
							(mid -0.249642 0.249642)
							(end -0.1778 0.2794)
						)
						(arc
							(start 0.1778 0.2794)
							(mid 0.249642 0.249642)
							(end 0.2794 0.1778)
						)
						(arc
							(start 0.2794 -0.1778)
							(mid 0.249642 -0.249642)
							(end 0.1778 -0.2794)
						)
					)
					(width 0)
					(fill yes)
				)
			)
		)
		(pad "2" smd custom
			(at 0 0.4445 270)
			(size 0.1397 0.1397)
			(layers "F.Cu" "F.Mask" "F.Paste")
			(net "SW_PWR_HDD5")
			(options
				(clearance outline)
				(anchor circle)
			)
			(primitives
				(gr_poly
					(pts
						(arc
							(start -0.1778 -0.2794)
							(mid -0.249642 -0.249642)
							(end -0.2794 -0.1778)
						)
						(arc
							(start -0.2794 0.1778)
							(mid -0.249642 0.249642)
							(end -0.1778 0.2794)
						)
						(arc
							(start 0.1778 0.2794)
							(mid 0.249642 0.249642)
							(end 0.2794 0.1778)
						)
						(arc
							(start 0.2794 -0.1778)
							(mid 0.249642 -0.249642)
							(end 0.1778 -0.2794)
						)
					)
					(width 0)
					(fill yes)
				)
			)
		)
	)
	(footprint ""
		(layer "F.Cu")
		(at 197.103746 -185.0517 -90)
		(property "Reference" "R436"
			(at 0 0 270)
			(layer "F.SilkS")
			(hide yes)
			(effects
				(font
					(size 1.27 1.27)
				)
			)
		)
		(property "Value" "4K7R2J-2-GP"
			(at 0.064008 -3.993896 270)
			(unlocked yes)
			(layer "F.Fab")
			(hide yes)
			(effects
				(font
					(size 1.016 1.016)
					(thickness 0.1524)
				)
			)
		)
		(property "Device Type" "R402H16"
			(at 0.064008 -5.517896 270)
			(unlocked yes)
			(layer "F.Fab")
			(hide yes)
			(effects
				(font
					(size 1.016 1.016)
					(thickness 0.1524)
				)
			)
		)
		(duplicate_pad_numbers_are_jumpers no)
		(fp_line
			(start -0.508 -0.9398)
			(end -0.508 0.9398)
			(stroke
				(width 0.1524)
				(type default)
			)
			(layer "F.SilkS")
		)
		(fp_line
			(start 0.508 -0.9398)
			(end -0.508 -0.9398)
			(stroke
				(width 0.1524)
				(type default)
			)
			(layer "F.SilkS")
		)
		(fp_rect
			(start -0.508 0.9398)
			(end 0.508 -0.9398)
			(stroke
				(width 0)
				(type default)
			)
			(fill no)
			(layer "F.CrtYd")
		)
		(fp_rect
			(start -0.508 0.9398)
			(end 0.508 -0.9398)
			(stroke
				(width 0)
				(type default)
			)
			(fill no)
			(layer "F.Fab")
		)
		(pad "1" smd custom
			(at 0 -0.4445 270)
			(size 0.1397 0.1397)
			(layers "F.Cu" "F.Mask" "F.Paste")
			(net "P3V3")
			(options
				(clearance outline)
				(anchor circle)
			)
			(primitives
				(gr_poly
					(pts
						(arc
							(start -0.1778 -0.2794)
							(mid -0.249642 -0.249642)
							(end -0.2794 -0.1778)
						)
						(arc
							(start -0.2794 0.1778)
							(mid -0.249642 0.249642)
							(end -0.1778 0.2794)
						)
						(arc
							(start 0.1778 0.2794)
							(mid 0.249642 0.249642)
							(end 0.2794 0.1778)
						)
						(arc
							(start 0.2794 -0.1778)
							(mid 0.249642 -0.249642)
							(end 0.1778 -0.2794)
						)
					)
					(width 0)
					(fill yes)
				)
			)
		)
		(pad "2" smd custom
			(at 0 0.4445 270)
			(size 0.1397 0.1397)
			(layers "F.Cu" "F.Mask" "F.Paste")
			(net "SAS_EXP_A_PWR3")
			(options
				(clearance outline)
				(anchor circle)
			)
			(primitives
				(gr_poly
					(pts
						(arc
							(start -0.1778 -0.2794)
							(mid -0.249642 -0.249642)
							(end -0.2794 -0.1778)
						)
						(arc
							(start -0.2794 0.1778)
							(mid -0.249642 0.249642)
							(end -0.1778 0.2794)
						)
						(arc
							(start 0.1778 0.2794)
							(mid 0.249642 0.249642)
							(end 0.2794 0.1778)
						)
						(arc
							(start 0.2794 -0.1778)
							(mid 0.249642 -0.249642)
							(end 0.1778 -0.2794)
						)
					)
					(width 0)
					(fill yes)
				)
			)
		)
	)
	(footprint ""
		(layer "F.Cu")
		(at 217.254582 -283.182568 180)
		(property "Reference" "C138"
			(at 0 0 180)
			(layer "F.SilkS")
			(hide yes)
			(effects
				(font
					(size 1.27 1.27)
				)
			)
		)
		(property "Value" "SC1U16V3KX-5GP"
			(at 0 -2.8194 180)
			(unlocked yes)
			(layer "F.Fab")
			(hide yes)
			(effects
				(font
					(size 1.016 1.016)
					(thickness 0.1524)
				)
			)
		)
		(property "Device Type" "C603H36"
			(at 0 -4.3434 180)
			(unlocked yes)
			(layer "F.Fab")
			(hide yes)
			(effects
				(font
					(size 1.016 1.016)
					(thickness 0.1524)
				)
			)
		)
		(duplicate_pad_numbers_are_jumpers no)
		(fp_line
			(start 0.508 0)
			(end -0.508 0)
			(stroke
				(width 0.2032)
				(type default)
			)
			(layer "F.SilkS")
		)
		(fp_rect
			(start -0.5842 1.3335)
			(end 0.5842 -1.3335)
			(stroke
				(width 0)
				(type default)
			)
			(fill no)
			(layer "F.CrtYd")
		)
		(fp_rect
			(start -0.5842 1.3335)
			(end 0.5842 -1.3335)
			(stroke
				(width 0)
				(type default)
			)
			(fill no)
			(layer "F.Fab")
		)
		(pad "1" smd custom
			(at 0 -0.762 180)
			(size 0.2159 0.2159)
			(layers "F.Cu" "F.Mask" "F.Paste")
			(net "P5V_HDD2")
			(options
				(clearance outline)
				(anchor circle)
			)
			(primitives
				(gr_poly
					(pts
						(arc
							(start -0.3302 -0.4318)
							(mid -0.402042 -0.402042)
							(end -0.4318 -0.3302)
						)
						(arc
							(start -0.4318 0.3302)
							(mid -0.402042 0.402042)
							(end -0.3302 0.4318)
						)
						(arc
							(start 0.3302 0.4318)
							(mid 0.402042 0.402042)
							(end 0.4318 0.3302)
						)
						(arc
							(start 0.4318 -0.3302)
							(mid 0.402042 -0.402042)
							(end 0.3302 -0.4318)
						)
					)
					(width 0)
					(fill yes)
				)
			)
		)
		(pad "2" smd custom
			(at 0 0.762 180)
			(size 0.2159 0.2159)
			(layers "F.Cu" "F.Mask" "F.Paste")
			(net "GND")
			(options
				(clearance outline)
				(anchor circle)
			)
			(primitives
				(gr_poly
					(pts
						(arc
							(start -0.3302 -0.4318)
							(mid -0.402042 -0.402042)
							(end -0.4318 -0.3302)
						)
						(arc
							(start -0.4318 0.3302)
							(mid -0.402042 0.402042)
							(end -0.3302 0.4318)
						)
						(arc
							(start 0.3302 0.4318)
							(mid 0.402042 0.402042)
							(end 0.4318 0.3302)
						)
						(arc
							(start 0.4318 -0.3302)
							(mid 0.402042 -0.402042)
							(end 0.3302 -0.4318)
						)
					)
					(width 0)
					(fill yes)
				)
			)
		)
	)
	(footprint ""
		(layer "F.Cu")
		(at 50.927 -417.957 90)
		(property "Reference" "R248"
			(at 0 0 90)
			(layer "F.SilkS")
			(hide yes)
			(effects
				(font
					(size 1.27 1.27)
				)
			)
		)
		(property "Value" "4K7R2J-2-GP"
			(at 0.064008 -3.993896 90)
			(unlocked yes)
			(layer "F.Fab")
			(hide yes)
			(effects
				(font
					(size 1.016 1.016)
					(thickness 0.1524)
				)
			)
		)
		(property "Device Type" "R402H16"
			(at 0.064008 -5.517896 90)
			(unlocked yes)
			(layer "F.Fab")
			(hide yes)
			(effects
				(font
					(size 1.016 1.016)
					(thickness 0.1524)
				)
			)
		)
		(duplicate_pad_numbers_are_jumpers no)
		(fp_line
			(start 0.508 -0.9398)
			(end -0.508 -0.9398)
			(stroke
				(width 0.1524)
				(type default)
			)
			(layer "F.SilkS")
		)
		(fp_line
			(start -0.508 -0.9398)
			(end -0.508 0.9398)
			(stroke
				(width 0.1524)
				(type default)
			)
			(layer "F.SilkS")
		)
		(fp_rect
			(start -0.508 0.9398)
			(end 0.508 -0.9398)
			(stroke
				(width 0)
				(type default)
			)
			(fill no)
			(layer "F.CrtYd")
		)
		(fp_rect
			(start -0.508 0.9398)
			(end 0.508 -0.9398)
			(stroke
				(width 0)
				(type default)
			)
			(fill no)
			(layer "F.Fab")
		)
		(pad "1" smd custom
			(at 0 -0.4445 90)
			(size 0.1397 0.1397)
			(layers "F.Cu" "F.Mask" "F.Paste")
			(net "P12V")
			(options
				(clearance outline)
				(anchor circle)
			)
			(primitives
				(gr_poly
					(pts
						(arc
							(start -0.1778 -0.2794)
							(mid -0.249642 -0.249642)
							(end -0.2794 -0.1778)
						)
						(arc
							(start -0.2794 0.1778)
							(mid -0.249642 0.249642)
							(end -0.1778 0.2794)
						)
						(arc
							(start 0.1778 0.2794)
							(mid 0.249642 0.249642)
							(end 0.2794 0.1778)
						)
						(arc
							(start 0.2794 -0.1778)
							(mid 0.249642 -0.249642)
							(end 0.1778 -0.2794)
						)
					)
					(width 0)
					(fill yes)
				)
			)
		)
		(pad "2" smd custom
			(at 0 0.4445 90)
			(size 0.1397 0.1397)
			(layers "F.Cu" "F.Mask" "F.Paste")
			(net "SW_HDD10_R")
			(options
				(clearance outline)
				(anchor circle)
			)
			(primitives
				(gr_poly
					(pts
						(arc
							(start -0.1778 -0.2794)
							(mid -0.249642 -0.249642)
							(end -0.2794 -0.1778)
						)
						(arc
							(start -0.2794 0.1778)
							(mid -0.249642 0.249642)
							(end -0.1778 0.2794)
						)
						(arc
							(start 0.1778 0.2794)
							(mid 0.249642 0.249642)
							(end 0.2794 0.1778)
						)
						(arc
							(start 0.2794 -0.1778)
							(mid 0.249642 -0.249642)
							(end 0.1778 -0.2794)
						)
					)
					(width 0)
					(fill yes)
				)
			)
		)
	)
	(footprint ""
		(layer "F.Cu")
		(at 5.079746 -496.8367 90)
		(property "Reference" "PC32"
			(at 0 0 90)
			(layer "F.SilkS")
			(hide yes)
			(effects
				(font
					(size 1.27 1.27)
				)
			)
		)
		(property "Value" "SC680P50V2KX-2GP"
			(at 1.1811 -2.7051 90)
			(unlocked yes)
			(layer "F.Fab")
			(hide yes)
			(effects
				(font
					(size 1.016 1.016)
					(thickness 0.1524)
				)
			)
		)
		(property "Device Type" "C402H22"
			(at 1.1811 -4.2291 90)
			(unlocked yes)
			(layer "F.Fab")
			(hide yes)
			(effects
				(font
					(size 1.016 1.016)
					(thickness 0.1524)
				)
			)
		)
		(duplicate_pad_numbers_are_jumpers no)
		(fp_rect
			(start -0.4318 0.9525)
			(end 0.4318 -0.9525)
			(stroke
				(width 0)
				(type default)
			)
			(fill no)
			(layer "F.CrtYd")
		)
		(fp_rect
			(start -0.4318 0.9525)
			(end 0.4318 -0.9525)
			(stroke
				(width 0)
				(type default)
			)
			(fill no)
			(layer "F.Fab")
		)
		(pad "1" smd custom
			(at 0 -0.4445 90)
			(size 0.1524 0.1524)
			(layers "F.Cu" "F.Mask" "F.Paste")
			(net "P5VC_LL_NET")
			(options
				(clearance outline)
				(anchor circle)
			)
			(primitives
				(gr_poly
					(pts
						(arc
							(start 0.3048 -0.2032)
							(mid 0.275042 -0.275042)
							(end 0.2032 -0.3048)
						)
						(arc
							(start -0.2032 -0.3048)
							(mid -0.275042 -0.275042)
							(end -0.3048 -0.2032)
						)
						(arc
							(start -0.3048 0.2032)
							(mid -0.275042 0.275042)
							(end -0.2032 0.3048)
						)
						(arc
							(start 0.2032 0.3048)
							(mid 0.275042 0.275042)
							(end 0.3048 0.2032)
						)
					)
					(width 0)
					(fill yes)
				)
			)
		)
		(pad "2" smd custom
			(at 0 0.4445 90)
			(size 0.1524 0.1524)
			(layers "F.Cu" "F.Mask" "F.Paste")
			(net "P5VC_VFB")
			(options
				(clearance outline)
				(anchor circle)
			)
			(primitives
				(gr_poly
					(pts
						(arc
							(start 0.3048 -0.2032)
							(mid 0.275042 -0.275042)
							(end 0.2032 -0.3048)
						)
						(arc
							(start -0.2032 -0.3048)
							(mid -0.275042 -0.275042)
							(end -0.3048 -0.2032)
						)
						(arc
							(start -0.3048 0.2032)
							(mid -0.275042 0.275042)
							(end -0.2032 0.3048)
						)
						(arc
							(start 0.2032 0.3048)
							(mid 0.275042 0.275042)
							(end 0.3048 0.2032)
						)
					)
					(width 0)
					(fill yes)
				)
			)
		)
	)
	(footprint ""
		(layer "F.Cu")
		(at 211.0232 -438.4548 -90)
		(property "Reference" "PC43"
			(at 0 0 270)
			(layer "F.SilkS")
			(hide yes)
			(effects
				(font
					(size 1.27 1.27)
				)
			)
		)
		(property "Value" "SC22U16V6MX-GP"
			(at -0.0762 -5.1308 270)
			(unlocked yes)
			(layer "F.Fab")
			(hide yes)
			(effects
				(font
					(size 1.016 1.016)
					(thickness 0.1524)
				)
			)
		)
		(property "Device Type" "C1206H71"
			(at -0.127 -6.6548 270)
			(unlocked yes)
			(layer "F.Fab")
			(hide yes)
			(effects
				(font
					(size 1.016 1.016)
					(thickness 0.1524)
				)
			)
		)
		(duplicate_pad_numbers_are_jumpers no)
		(fp_line
			(start -1.016 2.2352)
			(end -1.016 0.8382)
			(stroke
				(width 0.1524)
				(type default)
			)
			(layer "F.SilkS")
		)
		(fp_line
			(start 1.016 2.2352)
			(end -1.016 2.2352)
			(stroke
				(width 0.1524)
				(type default)
			)
			(layer "F.SilkS")
		)
		(fp_line
			(start 1.016 0.8382)
			(end 1.016 2.2352)
			(stroke
				(width 0.1524)
				(type default)
			)
			(layer "F.SilkS")
		)
		(fp_line
			(start -1.016 -0.8382)
			(end -1.016 -2.2352)
			(stroke
				(width 0.1524)
				(type default)
			)
			(layer "F.SilkS")
		)
		(fp_line
			(start -1.016 -2.2352)
			(end 1.016 -2.2352)
			(stroke
				(width 0.1524)
				(type default)
			)
			(layer "F.SilkS")
		)
		(fp_line
			(start 1.016 -2.2352)
			(end 1.016 -0.8382)
			(stroke
				(width 0.1524)
				(type default)
			)
			(layer "F.SilkS")
		)
		(fp_rect
			(start -1.0922 2.3114)
			(end 1.0922 -2.3114)
			(stroke
				(width 0)
				(type default)
			)
			(fill no)
			(layer "F.CrtYd")
		)
		(fp_poly
			(pts
				(xy 1.0922 -2.3114) (xy 1.0922 2.3114) (xy -1.0922 2.3114) (xy -1.0922 -2.3114)
			)
			(stroke
				(width 0)
				(type default)
			)
			(fill no)
			(layer "F.Fab")
		)
		(pad "1" smd rect
			(at 0 -1.397 270)
			(size 1.651 1.27)
			(layers "F.Cu" "F.Mask" "F.Paste")
			(net "P3V3_LX_COOPER")
		)
		(pad "2" smd rect
			(at 0 1.397 270)
			(size 1.651 1.27)
			(layers "F.Cu" "F.Mask" "F.Paste")
			(net "GND")
		)
	)
	(footprint ""
		(layer "F.Cu")
		(at 218.142058 -372.312184 -90)
		(property "Reference" "C120"
			(at 0 0 270)
			(layer "F.SilkS")
			(hide yes)
			(effects
				(font
					(size 1.27 1.27)
				)
			)
		)
		(property "Value" "SCD01U50V2KX-1GP"
			(at 1.1811 -2.7051 270)
			(unlocked yes)
			(layer "F.Fab")
			(hide yes)
			(effects
				(font
					(size 1.016 1.016)
					(thickness 0.1524)
				)
			)
		)
		(property "Device Type" "C402H22"
			(at 1.1811 -4.2291 270)
			(unlocked yes)
			(layer "F.Fab")
			(hide yes)
			(effects
				(font
					(size 1.016 1.016)
					(thickness 0.1524)
				)
			)
		)
		(duplicate_pad_numbers_are_jumpers no)
		(fp_rect
			(start -0.4318 0.9525)
			(end 0.4318 -0.9525)
			(stroke
				(width 0)
				(type default)
			)
			(fill no)
			(layer "F.CrtYd")
		)
		(fp_rect
			(start -0.4318 0.9525)
			(end 0.4318 -0.9525)
			(stroke
				(width 0)
				(type default)
			)
			(fill no)
			(layer "F.Fab")
		)
		(pad "1" smd custom
			(at 0 -0.4445 270)
			(size 0.1524 0.1524)
			(layers "F.Cu" "F.Mask" "F.Paste")
			(net "SAS2X28_DRIVE_RX_N_B1")
			(options
				(clearance outline)
				(anchor circle)
			)
			(primitives
				(gr_poly
					(pts
						(arc
							(start 0.3048 -0.2032)
							(mid 0.275042 -0.275042)
							(end 0.2032 -0.3048)
						)
						(arc
							(start -0.2032 -0.3048)
							(mid -0.275042 -0.275042)
							(end -0.3048 -0.2032)
						)
						(arc
							(start -0.3048 0.2032)
							(mid -0.275042 0.275042)
							(end -0.2032 0.3048)
						)
						(arc
							(start 0.2032 0.3048)
							(mid 0.275042 0.275042)
							(end 0.3048 0.2032)
						)
					)
					(width 0)
					(fill yes)
				)
			)
		)
		(pad "2" smd custom
			(at 0 0.4445 270)
			(size 0.1524 0.1524)
			(layers "F.Cu" "F.Mask" "F.Paste")
			(net "SAS2X28_B_HDD1_RX_-")
			(options
				(clearance outline)
				(anchor circle)
			)
			(primitives
				(gr_poly
					(pts
						(arc
							(start 0.3048 -0.2032)
							(mid 0.275042 -0.275042)
							(end 0.2032 -0.3048)
						)
						(arc
							(start -0.2032 -0.3048)
							(mid -0.275042 -0.275042)
							(end -0.3048 -0.2032)
						)
						(arc
							(start -0.3048 0.2032)
							(mid -0.275042 0.275042)
							(end -0.2032 0.3048)
						)
						(arc
							(start 0.2032 0.3048)
							(mid 0.275042 0.275042)
							(end 0.3048 0.2032)
						)
					)
					(width 0)
					(fill yes)
				)
			)
		)
	)
	(footprint ""
		(layer "F.Cu")
		(at 232.257346 -450.0118 -90)
		(property "Reference" "R488"
			(at 0 0 270)
			(layer "F.SilkS")
			(hide yes)
			(effects
				(font
					(size 1.27 1.27)
				)
			)
		)
		(property "Value" "1KR2F-3-GP"
			(at 0.064008 -3.993896 270)
			(unlocked yes)
			(layer "F.Fab")
			(hide yes)
			(effects
				(font
					(size 1.016 1.016)
					(thickness 0.1524)
				)
			)
		)
		(property "Device Type" "R402H16"
			(at 0.064008 -5.517896 270)
			(unlocked yes)
			(layer "F.Fab")
			(hide yes)
			(effects
				(font
					(size 1.016 1.016)
					(thickness 0.1524)
				)
			)
		)
		(duplicate_pad_numbers_are_jumpers no)
		(fp_line
			(start -0.508 -0.9398)
			(end -0.508 0.9398)
			(stroke
				(width 0.1524)
				(type default)
			)
			(layer "F.SilkS")
		)
		(fp_line
			(start 0.508 -0.9398)
			(end -0.508 -0.9398)
			(stroke
				(width 0.1524)
				(type default)
			)
			(layer "F.SilkS")
		)
		(fp_rect
			(start -0.508 0.9398)
			(end 0.508 -0.9398)
			(stroke
				(width 0)
				(type default)
			)
			(fill no)
			(layer "F.CrtYd")
		)
		(fp_rect
			(start -0.508 0.9398)
			(end 0.508 -0.9398)
			(stroke
				(width 0)
				(type default)
			)
			(fill no)
			(layer "F.Fab")
		)
		(pad "1" smd custom
			(at 0 -0.4445 270)
			(size 0.1397 0.1397)
			(layers "F.Cu" "F.Mask" "F.Paste")
			(net "FLT_HDD0_B")
			(options
				(clearance outline)
				(anchor circle)
			)
			(primitives
				(gr_poly
					(pts
						(arc
							(start -0.1778 -0.2794)
							(mid -0.249642 -0.249642)
							(end -0.2794 -0.1778)
						)
						(arc
							(start -0.2794 0.1778)
							(mid -0.249642 0.249642)
							(end -0.1778 0.2794)
						)
						(arc
							(start 0.1778 0.2794)
							(mid 0.249642 0.249642)
							(end 0.2794 0.1778)
						)
						(arc
							(start 0.2794 -0.1778)
							(mid 0.249642 -0.249642)
							(end 0.1778 -0.2794)
						)
					)
					(width 0)
					(fill yes)
				)
			)
		)
		(pad "2" smd custom
			(at 0 0.4445 270)
			(size 0.1397 0.1397)
			(layers "F.Cu" "F.Mask" "F.Paste")
			(net "FLT_HDD0_DRIVE")
			(options
				(clearance outline)
				(anchor circle)
			)
			(primitives
				(gr_poly
					(pts
						(arc
							(start -0.1778 -0.2794)
							(mid -0.249642 -0.249642)
							(end -0.2794 -0.1778)
						)
						(arc
							(start -0.2794 0.1778)
							(mid -0.249642 0.249642)
							(end -0.1778 0.2794)
						)
						(arc
							(start 0.1778 0.2794)
							(mid 0.249642 0.249642)
							(end 0.2794 0.1778)
						)
						(arc
							(start 0.2794 -0.1778)
							(mid 0.249642 -0.249642)
							(end 0.1778 -0.2794)
						)
					)
					(width 0)
					(fill yes)
				)
			)
		)
	)
	(footprint ""
		(layer "F.Cu")
		(at 16.705072 -500.446548 180)
		(property "Reference" "PC29"
			(at 0 0 180)
			(layer "F.SilkS")
			(hide yes)
			(effects
				(font
					(size 1.27 1.27)
				)
			)
		)
		(property "Value" "SC22U25V5MX-GP"
			(at -0.0762 -6.1214 180)
			(unlocked yes)
			(layer "F.Fab")
			(hide yes)
			(effects
				(font
					(size 1.016 1.016)
					(thickness 0.1524)
				)
			)
		)
		(property "Device Type" "C805H58"
			(at -0.0762 -8.1534 180)
			(unlocked yes)
			(layer "F.Fab")
			(hide yes)
			(effects
				(font
					(size 1.016 1.016)
					(thickness 0.1524)
				)
			)
		)
		(duplicate_pad_numbers_are_jumpers no)
		(fp_line
			(start 0.635 0)
			(end -0.635 0)
			(stroke
				(width 0.508)
				(type default)
			)
			(layer "F.SilkS")
		)
		(fp_rect
			(start -0.9652 1.778)
			(end 0.9652 -1.778)
			(stroke
				(width 0)
				(type default)
			)
			(fill no)
			(layer "F.CrtYd")
		)
		(fp_poly
			(pts
				(xy -0.9652 -1.778) (xy 0.9652 -1.778) (xy 0.9652 1.778) (xy -0.9652 1.778)
			)
			(stroke
				(width 0)
				(type default)
			)
			(fill no)
			(layer "F.Fab")
		)
		(pad "1" smd rect
			(at 0 -0.9652 180)
			(size 1.397 1.143)
			(layers "F.Cu" "F.Mask" "F.Paste")
			(net "P5VC_12VIN")
		)
		(pad "2" smd rect
			(at 0 0.9652 180)
			(size 1.397 1.143)
			(layers "F.Cu" "F.Mask" "F.Paste")
			(net "GND")
		)
	)
	(footprint ""
		(layer "F.Cu")
		(at 215.467946 -481.0379 -90)
		(property "Reference" "R343"
			(at 0 0 270)
			(layer "F.SilkS")
			(hide yes)
			(effects
				(font
					(size 1.27 1.27)
				)
			)
		)
		(property "Value" "0R2J-2-GP"
			(at 0.064008 -3.993896 270)
			(unlocked yes)
			(layer "F.Fab")
			(hide yes)
			(effects
				(font
					(size 1.016 1.016)
					(thickness 0.1524)
				)
			)
		)
		(property "Device Type" "R402H16"
			(at 0.064008 -5.517896 270)
			(unlocked yes)
			(layer "F.Fab")
			(hide yes)
			(effects
				(font
					(size 1.016 1.016)
					(thickness 0.1524)
				)
			)
		)
		(duplicate_pad_numbers_are_jumpers no)
		(fp_line
			(start -0.508 -0.9398)
			(end -0.508 0.9398)
			(stroke
				(width 0.1524)
				(type default)
			)
			(layer "F.SilkS")
		)
		(fp_line
			(start 0.508 -0.9398)
			(end -0.508 -0.9398)
			(stroke
				(width 0.1524)
				(type default)
			)
			(layer "F.SilkS")
		)
		(fp_rect
			(start -0.508 0.9398)
			(end 0.508 -0.9398)
			(stroke
				(width 0)
				(type default)
			)
			(fill no)
			(layer "F.CrtYd")
		)
		(fp_rect
			(start -0.508 0.9398)
			(end 0.508 -0.9398)
			(stroke
				(width 0)
				(type default)
			)
			(fill no)
			(layer "F.Fab")
		)
		(pad "1" smd custom
			(at 0 -0.4445 270)
			(size 0.1397 0.1397)
			(layers "F.Cu" "F.Mask" "F.Paste")
			(net "HDD_PRSNT_NET0")
			(options
				(clearance outline)
				(anchor circle)
			)
			(primitives
				(gr_poly
					(pts
						(arc
							(start -0.1778 -0.2794)
							(mid -0.249642 -0.249642)
							(end -0.2794 -0.1778)
						)
						(arc
							(start -0.2794 0.1778)
							(mid -0.249642 0.249642)
							(end -0.1778 0.2794)
						)
						(arc
							(start 0.1778 0.2794)
							(mid 0.249642 0.249642)
							(end 0.2794 0.1778)
						)
						(arc
							(start 0.2794 -0.1778)
							(mid 0.249642 -0.249642)
							(end 0.1778 -0.2794)
						)
					)
					(width 0)
					(fill yes)
				)
			)
		)
		(pad "2" smd custom
			(at 0 0.4445 270)
			(size 0.1397 0.1397)
			(layers "F.Cu" "F.Mask" "F.Paste")
			(net "HDD0_LED_B")
			(options
				(clearance outline)
				(anchor circle)
			)
			(primitives
				(gr_poly
					(pts
						(arc
							(start -0.1778 -0.2794)
							(mid -0.249642 -0.249642)
							(end -0.2794 -0.1778)
						)
						(arc
							(start -0.2794 0.1778)
							(mid -0.249642 0.249642)
							(end -0.1778 0.2794)
						)
						(arc
							(start 0.1778 0.2794)
							(mid 0.249642 0.249642)
							(end 0.2794 0.1778)
						)
						(arc
							(start 0.2794 -0.1778)
							(mid 0.249642 -0.249642)
							(end 0.1778 -0.2794)
						)
					)
					(width 0)
					(fill yes)
				)
			)
		)
	)
	(footprint ""
		(layer "F.Cu")
		(at 177.558446 -459.393036 -90)
		(property "Reference" "R386"
			(at 0 0 270)
			(layer "F.SilkS")
			(hide yes)
			(effects
				(font
					(size 1.27 1.27)
				)
			)
		)
		(property "Value" "0R2J-2-GP"
			(at 0.064008 -3.993896 270)
			(unlocked yes)
			(layer "F.Fab")
			(hide yes)
			(effects
				(font
					(size 1.016 1.016)
					(thickness 0.1524)
				)
			)
		)
		(property "Device Type" "R402H16"
			(at 0.064008 -5.517896 270)
			(unlocked yes)
			(layer "F.Fab")
			(hide yes)
			(effects
				(font
					(size 1.016 1.016)
					(thickness 0.1524)
				)
			)
		)
		(duplicate_pad_numbers_are_jumpers no)
		(fp_line
			(start -0.508 -0.9398)
			(end -0.508 0.9398)
			(stroke
				(width 0.1524)
				(type default)
			)
			(layer "F.SilkS")
		)
		(fp_line
			(start 0.508 -0.9398)
			(end -0.508 -0.9398)
			(stroke
				(width 0.1524)
				(type default)
			)
			(layer "F.SilkS")
		)
		(fp_rect
			(start -0.508 0.9398)
			(end 0.508 -0.9398)
			(stroke
				(width 0)
				(type default)
			)
			(fill no)
			(layer "F.CrtYd")
		)
		(fp_rect
			(start -0.508 0.9398)
			(end 0.508 -0.9398)
			(stroke
				(width 0)
				(type default)
			)
			(fill no)
			(layer "F.Fab")
		)
		(pad "1" smd custom
			(at 0 -0.4445 270)
			(size 0.1397 0.1397)
			(layers "F.Cu" "F.Mask" "F.Paste")
			(net "P12V_DIV")
			(options
				(clearance outline)
				(anchor circle)
			)
			(primitives
				(gr_poly
					(pts
						(arc
							(start -0.1778 -0.2794)
							(mid -0.249642 -0.249642)
							(end -0.2794 -0.1778)
						)
						(arc
							(start -0.2794 0.1778)
							(mid -0.249642 0.249642)
							(end -0.1778 0.2794)
						)
						(arc
							(start 0.1778 0.2794)
							(mid 0.249642 0.249642)
							(end 0.2794 0.1778)
						)
						(arc
							(start 0.2794 -0.1778)
							(mid 0.249642 -0.249642)
							(end 0.1778 -0.2794)
						)
					)
					(width 0)
					(fill yes)
				)
			)
		)
		(pad "2" smd custom
			(at 0 0.4445 270)
			(size 0.1397 0.1397)
			(layers "F.Cu" "F.Mask" "F.Paste")
			(net "P12V_SENSE")
			(options
				(clearance outline)
				(anchor circle)
			)
			(primitives
				(gr_poly
					(pts
						(arc
							(start -0.1778 -0.2794)
							(mid -0.249642 -0.249642)
							(end -0.2794 -0.1778)
						)
						(arc
							(start -0.2794 0.1778)
							(mid -0.249642 0.249642)
							(end -0.1778 0.2794)
						)
						(arc
							(start 0.1778 0.2794)
							(mid 0.249642 0.249642)
							(end 0.2794 0.1778)
						)
						(arc
							(start 0.2794 -0.1778)
							(mid 0.249642 -0.249642)
							(end 0.1778 -0.2794)
						)
					)
					(width 0)
					(fill yes)
				)
			)
		)
	)
	(footprint ""
		(layer "F.Cu")
		(at 207.264 -379.984)
		(property "Reference" "C365"
			(at 0 0 0)
			(layer "F.SilkS")
			(hide yes)
			(effects
				(font
					(size 1.27 1.27)
				)
			)
		)
		(property "Value" "SCD033U25V2KX-GP"
			(at 1.1811 -2.7051 0)
			(unlocked yes)
			(layer "F.Fab")
			(hide yes)
			(effects
				(font
					(size 1.016 1.016)
					(thickness 0.1524)
				)
			)
		)
		(property "Device Type" "C402H22"
			(at 1.1811 -4.2291 0)
			(unlocked yes)
			(layer "F.Fab")
			(hide yes)
			(effects
				(font
					(size 1.016 1.016)
					(thickness 0.1524)
				)
			)
		)
		(duplicate_pad_numbers_are_jumpers no)
		(fp_rect
			(start -0.4318 0.9525)
			(end 0.4318 -0.9525)
			(stroke
				(width 0)
				(type default)
			)
			(fill no)
			(layer "F.CrtYd")
		)
		(fp_rect
			(start -0.4318 0.9525)
			(end 0.4318 -0.9525)
			(stroke
				(width 0)
				(type default)
			)
			(fill no)
			(layer "F.Fab")
		)
		(pad "1" smd custom
			(at 0 -0.4445)
			(size 0.1524 0.1524)
			(layers "F.Cu" "F.Mask" "F.Paste")
			(net "SW_HDD1_P")
			(options
				(clearance outline)
				(anchor circle)
			)
			(primitives
				(gr_poly
					(pts
						(arc
							(start 0.3048 -0.2032)
							(mid 0.275042 -0.275042)
							(end 0.2032 -0.3048)
						)
						(arc
							(start -0.2032 -0.3048)
							(mid -0.275042 -0.275042)
							(end -0.3048 -0.2032)
						)
						(arc
							(start -0.3048 0.2032)
							(mid -0.275042 0.275042)
							(end -0.2032 0.3048)
						)
						(arc
							(start 0.2032 0.3048)
							(mid 0.275042 0.275042)
							(end 0.3048 0.2032)
						)
					)
					(width 0)
					(fill yes)
				)
			)
		)
		(pad "2" smd custom
			(at 0 0.4445)
			(size 0.1524 0.1524)
			(layers "F.Cu" "F.Mask" "F.Paste")
			(net "GND")
			(options
				(clearance outline)
				(anchor circle)
			)
			(primitives
				(gr_poly
					(pts
						(arc
							(start 0.3048 -0.2032)
							(mid 0.275042 -0.275042)
							(end 0.2032 -0.3048)
						)
						(arc
							(start -0.2032 -0.3048)
							(mid -0.275042 -0.275042)
							(end -0.3048 -0.2032)
						)
						(arc
							(start -0.3048 0.2032)
							(mid -0.275042 0.275042)
							(end -0.2032 0.3048)
						)
						(arc
							(start 0.2032 0.3048)
							(mid 0.275042 0.275042)
							(end 0.3048 0.2032)
						)
					)
					(width 0)
					(fill yes)
				)
			)
		)
	)
	(footprint ""
		(layer "F.Cu")
		(at 73.913746 -194.3227 90)
		(property "Reference" "U26"
			(at 0 0 90)
			(layer "F.SilkS")
			(hide yes)
			(effects
				(font
					(size 1.27 1.27)
				)
			)
		)
		(property "Value" "P2003EVG-GP"
			(at 0 -11.1252 90)
			(unlocked yes)
			(layer "F.Fab")
			(hide yes)
			(effects
				(font
					(size 1.016 1.016)
					(thickness 0.1524)
				)
			)
		)
		(property "Device Type" "SOIC8H79"
			(at 0 -12.6492 90)
			(unlocked yes)
			(layer "F.Fab")
			(hide yes)
			(effects
				(font
					(size 1.016 1.016)
					(thickness 0.1524)
				)
			)
		)
		(duplicate_pad_numbers_are_jumpers no)
		(fp_line
			(start 2.1336 -1.4224)
			(end -2.7432 -1.4224)
			(stroke
				(width 0.1524)
				(type default)
			)
			(layer "F.SilkS")
		)
		(fp_line
			(start -2.7432 -1.4224)
			(end -2.7432 1.4224)
			(stroke
				(width 0.1524)
				(type default)
			)
			(layer "F.SilkS")
		)
		(fp_line
			(start -2.7432 -0.508)
			(end -2.2352 0)
			(stroke
				(width 0.1524)
				(type default)
			)
			(layer "F.SilkS")
		)
		(fp_line
			(start -2.2352 0)
			(end -2.7432 0.508)
			(stroke
				(width 0.1524)
				(type default)
			)
			(layer "F.SilkS")
		)
		(fp_line
			(start 2.1336 1.4224)
			(end 2.1336 -1.4224)
			(stroke
				(width 0.1524)
				(type default)
			)
			(layer "F.SilkS")
		)
		(fp_line
			(start -2.7432 1.4224)
			(end 2.1336 1.4224)
			(stroke
				(width 0.1524)
				(type default)
			)
			(layer "F.SilkS")
		)
		(fp_line
			(start -2.6162 3.429)
			(end -2.6162 1.4732)
			(stroke
				(width 0.4064)
				(type default)
			)
			(layer "F.SilkS")
		)
		(fp_poly
			(pts
				(xy 2.2098 -1.4224) (xy 2.2098 1.4224) (xy -2.2225 1.4224) (xy -2.2225 -1.4224)
			)
			(stroke
				(width 0)
				(type default)
			)
			(fill yes)
			(layer "F.SilkS")
		)
		(fp_rect
			(start -2.4511 2.9972)
			(end 2.4511 -2.9972)
			(stroke
				(width 0)
				(type default)
			)
			(fill no)
			(layer "F.CrtYd")
		)
		(fp_poly
			(pts
				(xy -2.8194 3.6322) (xy -2.8194 -3.6322) (xy 2.8194 -3.6322) (xy 2.8194 -2.2987) (xy 2.4511 -2.2987)
				(xy 2.4511 -2.9972) (xy -2.4511 -2.9972) (xy -2.4511 2.9972) (xy 2.4511 2.9972) (xy 2.4511 -2.286)
				(xy 2.8194 -2.286) (xy 2.8194 3.6322)
			)
			(stroke
				(width 0)
				(type default)
			)
			(fill no)
			(layer "F.CrtYd")
		)
		(fp_rect
			(start -2.8194 3.6322)
			(end 2.8194 -3.6322)
			(stroke
				(width 0)
				(type default)
			)
			(fill no)
			(layer "F.Fab")
		)
		(pad "1" smd rect
			(at -1.905 2.54 90)
			(size 0.635 1.651)
			(layers "F.Cu" "F.Mask" "F.Paste")
			(net "P12V")
		)
		(pad "2" smd rect
			(at -0.635 2.54 90)
			(size 0.635 1.651)
			(layers "F.Cu" "F.Mask" "F.Paste")
			(net "P12V")
		)
		(pad "3" smd rect
			(at 0.635 2.54 90)
			(size 0.635 1.651)
			(layers "F.Cu" "F.Mask" "F.Paste")
			(net "P12V")
		)
		(pad "4" smd rect
			(at 1.905 2.54 90)
			(size 0.635 1.651)
			(layers "F.Cu" "F.Mask" "F.Paste")
			(net "SW_HDD8_N")
		)
		(pad "5" smd rect
			(at 1.905 -2.54 90)
			(size 0.635 1.651)
			(layers "F.Cu" "F.Mask" "F.Paste")
			(net "P12V_HDD8")
		)
		(pad "6" smd rect
			(at 0.635 -2.54 90)
			(size 0.635 1.651)
			(layers "F.Cu" "F.Mask" "F.Paste")
			(net "P12V_HDD8")
		)
		(pad "7" smd rect
			(at -0.635 -2.54 90)
			(size 0.635 1.651)
			(layers "F.Cu" "F.Mask" "F.Paste")
			(net "P12V_HDD8")
		)
		(pad "8" smd rect
			(at -1.905 -2.54 90)
			(size 0.635 1.651)
			(layers "F.Cu" "F.Mask" "F.Paste")
			(net "P12V_HDD8")
		)
	)
	(footprint ""
		(layer "F.Cu")
		(at 38.7604 -427.4566 180)
		(property "Reference" "R396"
			(at 0 0 180)
			(layer "F.SilkS")
			(hide yes)
			(effects
				(font
					(size 1.27 1.27)
				)
			)
		)
		(property "Value" "0R2J-2-GP"
			(at 0.064008 -3.993896 180)
			(unlocked yes)
			(layer "F.Fab")
			(hide yes)
			(effects
				(font
					(size 1.016 1.016)
					(thickness 0.1524)
				)
			)
		)
		(property "Device Type" "R402H16"
			(at 0.064008 -5.517896 180)
			(unlocked yes)
			(layer "F.Fab")
			(hide yes)
			(effects
				(font
					(size 1.016 1.016)
					(thickness 0.1524)
				)
			)
		)
		(duplicate_pad_numbers_are_jumpers no)
		(fp_line
			(start 0.508 -0.9398)
			(end -0.508 -0.9398)
			(stroke
				(width 0.1524)
				(type default)
			)
			(layer "F.SilkS")
		)
		(fp_line
			(start -0.508 -0.9398)
			(end -0.508 0.9398)
			(stroke
				(width 0.1524)
				(type default)
			)
			(layer "F.SilkS")
		)
		(fp_rect
			(start -0.508 0.9398)
			(end 0.508 -0.9398)
			(stroke
				(width 0)
				(type default)
			)
			(fill no)
			(layer "F.CrtYd")
		)
		(fp_rect
			(start -0.508 0.9398)
			(end 0.508 -0.9398)
			(stroke
				(width 0)
				(type default)
			)
			(fill no)
			(layer "F.Fab")
		)
		(pad "1" smd custom
			(at 0 -0.4445 180)
			(size 0.1397 0.1397)
			(layers "F.Cu" "F.Mask" "F.Paste")
			(net "HDD_PRSNT_NET10")
			(options
				(clearance outline)
				(anchor circle)
			)
			(primitives
				(gr_poly
					(pts
						(arc
							(start -0.1778 -0.2794)
							(mid -0.249642 -0.249642)
							(end -0.2794 -0.1778)
						)
						(arc
							(start -0.2794 0.1778)
							(mid -0.249642 0.249642)
							(end -0.1778 0.2794)
						)
						(arc
							(start 0.1778 0.2794)
							(mid 0.249642 0.249642)
							(end 0.2794 0.1778)
						)
						(arc
							(start 0.2794 -0.1778)
							(mid 0.249642 -0.249642)
							(end 0.1778 -0.2794)
						)
					)
					(width 0)
					(fill yes)
				)
			)
		)
		(pad "2" smd custom
			(at 0 0.4445 180)
			(size 0.1397 0.1397)
			(layers "F.Cu" "F.Mask" "F.Paste")
			(net "HDD10_LED_B")
			(options
				(clearance outline)
				(anchor circle)
			)
			(primitives
				(gr_poly
					(pts
						(arc
							(start -0.1778 -0.2794)
							(mid -0.249642 -0.249642)
							(end -0.2794 -0.1778)
						)
						(arc
							(start -0.2794 0.1778)
							(mid -0.249642 0.249642)
							(end -0.1778 0.2794)
						)
						(arc
							(start 0.1778 0.2794)
							(mid 0.249642 0.249642)
							(end 0.2794 0.1778)
						)
						(arc
							(start 0.2794 -0.1778)
							(mid 0.249642 -0.249642)
							(end 0.1778 -0.2794)
						)
					)
					(width 0)
					(fill yes)
				)
			)
		)
	)
	(footprint ""
		(layer "F.Cu")
		(at 26.880312 -345.046808 90)
		(property "Reference" "C279"
			(at 0 0 90)
			(layer "F.SilkS")
			(hide yes)
			(effects
				(font
					(size 1.27 1.27)
				)
			)
		)
		(property "Value" "SCD01U50V2KX-1GP"
			(at 1.1811 -2.7051 90)
			(unlocked yes)
			(layer "F.Fab")
			(hide yes)
			(effects
				(font
					(size 1.016 1.016)
					(thickness 0.1524)
				)
			)
		)
		(property "Device Type" "C402H22"
			(at 1.1811 -4.2291 90)
			(unlocked yes)
			(layer "F.Fab")
			(hide yes)
			(effects
				(font
					(size 1.016 1.016)
					(thickness 0.1524)
				)
			)
		)
		(duplicate_pad_numbers_are_jumpers no)
		(fp_rect
			(start -0.4318 0.9525)
			(end 0.4318 -0.9525)
			(stroke
				(width 0)
				(type default)
			)
			(fill no)
			(layer "F.CrtYd")
		)
		(fp_rect
			(start -0.4318 0.9525)
			(end 0.4318 -0.9525)
			(stroke
				(width 0)
				(type default)
			)
			(fill no)
			(layer "F.Fab")
		)
		(pad "1" smd custom
			(at 0 -0.4445 90)
			(size 0.1524 0.1524)
			(layers "F.Cu" "F.Mask" "F.Paste")
			(net "SAS2X28_DRIVE_RX_P_A11")
			(options
				(clearance outline)
				(anchor circle)
			)
			(primitives
				(gr_poly
					(pts
						(arc
							(start 0.3048 -0.2032)
							(mid 0.275042 -0.275042)
							(end 0.2032 -0.3048)
						)
						(arc
							(start -0.2032 -0.3048)
							(mid -0.275042 -0.275042)
							(end -0.3048 -0.2032)
						)
						(arc
							(start -0.3048 0.2032)
							(mid -0.275042 0.275042)
							(end -0.2032 0.3048)
						)
						(arc
							(start 0.2032 0.3048)
							(mid 0.275042 0.275042)
							(end 0.3048 0.2032)
						)
					)
					(width 0)
					(fill yes)
				)
			)
		)
		(pad "2" smd custom
			(at 0 0.4445 90)
			(size 0.1524 0.1524)
			(layers "F.Cu" "F.Mask" "F.Paste")
			(net "SAS2X28_A_HDD11_RX_+")
			(options
				(clearance outline)
				(anchor circle)
			)
			(primitives
				(gr_poly
					(pts
						(arc
							(start 0.3048 -0.2032)
							(mid 0.275042 -0.275042)
							(end 0.2032 -0.3048)
						)
						(arc
							(start -0.2032 -0.3048)
							(mid -0.275042 -0.275042)
							(end -0.3048 -0.2032)
						)
						(arc
							(start -0.3048 0.2032)
							(mid -0.275042 0.275042)
							(end -0.2032 0.3048)
						)
						(arc
							(start 0.2032 0.3048)
							(mid 0.275042 0.275042)
							(end 0.3048 0.2032)
						)
					)
					(width 0)
					(fill yes)
				)
			)
		)
	)
	(footprint ""
		(layer "F.Cu")
		(at 60.908946 -291.2491)
		(property "Reference" "Q15"
			(at 0 0 0)
			(layer "F.SilkS")
			(hide yes)
			(effects
				(font
					(size 1.27 1.27)
				)
			)
		)
		(property "Value" "AO4406AL-GP"
			(at -3.707384 -1.5367 0)
			(unlocked yes)
			(layer "F.Fab")
			(hide yes)
			(effects
				(font
					(size 1.016 1.016)
					(thickness 0.1524)
				)
			)
		)
		(property "Device Type" "SOIC8H69"
			(at -3.707384 -3.0607 0)
			(unlocked yes)
			(layer "F.Fab")
			(hide yes)
			(effects
				(font
					(size 1.016 1.016)
					(thickness 0.1524)
				)
			)
		)
		(duplicate_pad_numbers_are_jumpers no)
		(fp_line
			(start -2.7432 -1.4224)
			(end -2.7432 1.4224)
			(stroke
				(width 0.1524)
				(type default)
			)
			(layer "F.SilkS")
		)
		(fp_line
			(start -2.7432 1.4224)
			(end -2.6416 1.4224)
			(stroke
				(width 0.1524)
				(type default)
			)
			(layer "F.SilkS")
		)
		(fp_line
			(start -2.7432 1.4224)
			(end 2.1336 1.4224)
			(stroke
				(width 0.1524)
				(type default)
			)
			(layer "F.SilkS")
		)
		(fp_line
			(start -2.7178 -0.508)
			(end -2.1844 -0.0508)
			(stroke
				(width 0.1524)
				(type default)
			)
			(layer "F.SilkS")
		)
		(fp_line
			(start -2.6289 3.4417)
			(end -2.6289 1.4732)
			(stroke
				(width 0.381)
				(type default)
			)
			(layer "F.SilkS")
		)
		(fp_line
			(start -2.1844 -0.0508)
			(end -2.7178 0.508)
			(stroke
				(width 0.1524)
				(type default)
			)
			(layer "F.SilkS")
		)
		(fp_line
			(start 2.1336 -1.4224)
			(end -2.7432 -1.4224)
			(stroke
				(width 0.1524)
				(type default)
			)
			(layer "F.SilkS")
		)
		(fp_line
			(start 2.1336 1.4224)
			(end 2.1336 -1.4224)
			(stroke
				(width 0.1524)
				(type default)
			)
			(layer "F.SilkS")
		)
		(fp_poly
			(pts
				(xy -2.2098 -1.4224) (xy -2.2098 1.4224) (xy 2.2098 1.4224) (xy 2.2098 -1.4224)
			)
			(stroke
				(width 0)
				(type default)
			)
			(fill yes)
			(layer "F.SilkS")
		)
		(fp_rect
			(start -2.450084 2.999994)
			(end 2.450084 -2.999994)
			(stroke
				(width 0)
				(type default)
			)
			(fill no)
			(layer "F.CrtYd")
		)
		(fp_poly
			(pts
				(xy -2.8194 3.6322) (xy -2.8194 -3.6322) (xy 2.8194 -3.6322) (xy 2.8194 1.18364) (xy 2.450084 1.18364)
				(xy 2.450084 -2.999994) (xy -2.450084 -2.999994) (xy -2.450084 2.999994) (xy 2.450084 2.999994)
				(xy 2.450084 1.18618) (xy 2.8194 1.18618) (xy 2.8194 3.6322)
			)
			(stroke
				(width 0)
				(type default)
			)
			(fill no)
			(layer "F.CrtYd")
		)
		(fp_rect
			(start -2.8194 3.6322)
			(end 2.8194 -3.6322)
			(stroke
				(width 0)
				(type default)
			)
			(fill no)
			(layer "F.Fab")
		)
		(pad "1" smd rect
			(at -1.905 2.54)
			(size 0.635 1.651)
			(layers "F.Cu" "F.Mask" "F.Paste")
			(net "P5V_HDD7")
		)
		(pad "2" smd rect
			(at -0.635 2.54)
			(size 0.635 1.651)
			(layers "F.Cu" "F.Mask" "F.Paste")
			(net "P5V_HDD7")
		)
		(pad "3" smd rect
			(at 0.635 2.54)
			(size 0.635 1.651)
			(layers "F.Cu" "F.Mask" "F.Paste")
			(net "P5V_HDD7")
		)
		(pad "4" smd rect
			(at 1.905 2.54)
			(size 0.635 1.651)
			(layers "F.Cu" "F.Mask" "F.Paste")
			(net "SW_HDD7_P")
		)
		(pad "5" smd rect
			(at 1.905 -2.54)
			(size 0.635 1.651)
			(layers "F.Cu" "F.Mask" "F.Paste")
			(net "P5VB")
		)
		(pad "6" smd rect
			(at 0.635 -2.54)
			(size 0.635 1.651)
			(layers "F.Cu" "F.Mask" "F.Paste")
			(net "P5VB")
		)
		(pad "7" smd rect
			(at -0.635 -2.54)
			(size 0.635 1.651)
			(layers "F.Cu" "F.Mask" "F.Paste")
			(net "P5VB")
		)
		(pad "8" smd rect
			(at -1.905 -2.54)
			(size 0.635 1.651)
			(layers "F.Cu" "F.Mask" "F.Paste")
			(net "P5VB")
		)
	)
	(footprint ""
		(layer "F.Cu")
		(at 42.500042 -247.160034 180)
		(property "Reference" "LED8"
			(at 0 0 180)
			(layer "F.SilkS")
			(hide yes)
			(effects
				(font
					(size 1.27 1.27)
				)
			)
		)
		(property "Value" "LED-RB-4-GP"
			(at 5.88899 1.80848 180)
			(unlocked yes)
			(layer "F.Fab")
			(hide yes)
			(effects
				(font
					(size 1.016 1.016)
					(thickness 0.1524)
				)
			)
		)
		(property "Device Type" "LED1613-4PH20"
			(at 5.88899 0.28448 180)
			(unlocked yes)
			(layer "F.Fab")
			(hide yes)
			(effects
				(font
					(size 1.016 1.016)
					(thickness 0.1524)
				)
			)
		)
		(duplicate_pad_numbers_are_jumpers no)
		(fp_line
			(start 1.4478 0.9652)
			(end -1.4478 0.9652)
			(stroke
				(width 0.1524)
				(type default)
			)
			(layer "F.SilkS")
		)
		(fp_line
			(start 1.4478 -0.9652)
			(end 1.4478 0.9652)
			(stroke
				(width 0.1524)
				(type default)
			)
			(layer "F.SilkS")
		)
		(fp_line
			(start -1.4478 0.9652)
			(end -1.4478 -0.9652)
			(stroke
				(width 0.1524)
				(type default)
			)
			(layer "F.SilkS")
		)
		(fp_line
			(start -1.4478 0.9652)
			(end -1.4478 -0.9652)
			(stroke
				(width 0.508)
				(type default)
			)
			(layer "F.SilkS")
		)
		(fp_line
			(start -1.4478 -0.9652)
			(end 1.4478 -0.9652)
			(stroke
				(width 0.1524)
				(type default)
			)
			(layer "F.SilkS")
		)
		(fp_rect
			(start -0.8001 0.6477)
			(end 0.8001 -0.6477)
			(stroke
				(width 0)
				(type default)
			)
			(fill no)
			(layer "F.CrtYd")
		)
		(fp_poly
			(pts
				(xy -1.7018 1.2192) (xy -1.7018 -0.06223) (xy -0.8001 -0.06223) (xy -0.8001 0.6477) (xy 0.8001 0.6477)
				(xy 0.8001 -0.6477) (xy -0.8001 -0.6477) (xy -0.8001 -0.0635) (xy -1.7018 -0.0635) (xy -1.7018 -1.2192)
				(xy 1.7018 -1.2192) (xy 1.7018 1.2192)
			)
			(stroke
				(width 0)
				(type default)
			)
			(fill no)
			(layer "F.CrtYd")
		)
		(fp_rect
			(start -1.7018 1.2192)
			(end 1.7018 -1.2192)
			(stroke
				(width 0)
				(type default)
			)
			(fill no)
			(layer "F.Fab")
		)
		(pad "1" smd rect
			(at -0.73025 0.4064 180)
			(size 0.9144 0.6096)
			(layers "F.Cu" "F.Mask" "F.Paste")
			(net "DRV_ACT_NET7")
		)
		(pad "2" smd rect
			(at -0.73025 -0.4064 180)
			(size 0.9144 0.6096)
			(layers "F.Cu" "F.Mask" "F.Paste")
			(net "FLT_NET_HDD7")
		)
		(pad "3" smd rect
			(at 0.73025 -0.4064 180)
			(size 0.9144 0.6096)
			(layers "F.Cu" "F.Mask" "F.Paste")
			(net "FLT_HDD7")
		)
		(pad "4" smd rect
			(at 0.73025 0.4064 180)
			(size 0.9144 0.6096)
			(layers "F.Cu" "F.Mask" "F.Paste")
			(net "DRV_ACT_7")
		)
	)
	(footprint ""
		(layer "F.Cu")
		(at 20.192746 -52.9717 -90)
		(property "Reference" "R299"
			(at 0 0 270)
			(layer "F.SilkS")
			(hide yes)
			(effects
				(font
					(size 1.27 1.27)
				)
			)
		)
		(property "Value" "330R2F-GP"
			(at 0.064008 -3.993896 270)
			(unlocked yes)
			(layer "F.Fab")
			(hide yes)
			(effects
				(font
					(size 1.016 1.016)
					(thickness 0.1524)
				)
			)
		)
		(property "Device Type" "R402H16"
			(at 0.064008 -5.517896 270)
			(unlocked yes)
			(layer "F.Fab")
			(hide yes)
			(effects
				(font
					(size 1.016 1.016)
					(thickness 0.1524)
				)
			)
		)
		(duplicate_pad_numbers_are_jumpers no)
		(fp_line
			(start -0.508 -0.9398)
			(end -0.508 0.9398)
			(stroke
				(width 0.1524)
				(type default)
			)
			(layer "F.SilkS")
		)
		(fp_line
			(start 0.508 -0.9398)
			(end -0.508 -0.9398)
			(stroke
				(width 0.1524)
				(type default)
			)
			(layer "F.SilkS")
		)
		(fp_rect
			(start -0.508 0.9398)
			(end 0.508 -0.9398)
			(stroke
				(width 0)
				(type default)
			)
			(fill no)
			(layer "F.CrtYd")
		)
		(fp_rect
			(start -0.508 0.9398)
			(end 0.508 -0.9398)
			(stroke
				(width 0)
				(type default)
			)
			(fill no)
			(layer "F.Fab")
		)
		(pad "1" smd custom
			(at 0 -0.4445 270)
			(size 0.1397 0.1397)
			(layers "F.Cu" "F.Mask" "F.Paste")
			(net "P3V3_HDD14_LED")
			(options
				(clearance outline)
				(anchor circle)
			)
			(primitives
				(gr_poly
					(pts
						(arc
							(start -0.1778 -0.2794)
							(mid -0.249642 -0.249642)
							(end -0.2794 -0.1778)
						)
						(arc
							(start -0.2794 0.1778)
							(mid -0.249642 0.249642)
							(end -0.1778 0.2794)
						)
						(arc
							(start 0.1778 0.2794)
							(mid 0.249642 0.249642)
							(end 0.2794 0.1778)
						)
						(arc
							(start 0.2794 -0.1778)
							(mid 0.249642 -0.249642)
							(end 0.1778 -0.2794)
						)
					)
					(width 0)
					(fill yes)
				)
			)
		)
		(pad "2" smd custom
			(at 0 0.4445 270)
			(size 0.1397 0.1397)
			(layers "F.Cu" "F.Mask" "F.Paste")
			(net "FLT_HDD14")
			(options
				(clearance outline)
				(anchor circle)
			)
			(primitives
				(gr_poly
					(pts
						(arc
							(start -0.1778 -0.2794)
							(mid -0.249642 -0.249642)
							(end -0.2794 -0.1778)
						)
						(arc
							(start -0.2794 0.1778)
							(mid -0.249642 0.249642)
							(end -0.1778 0.2794)
						)
						(arc
							(start 0.1778 0.2794)
							(mid 0.249642 0.249642)
							(end 0.2794 0.1778)
						)
						(arc
							(start 0.2794 -0.1778)
							(mid 0.249642 -0.249642)
							(end 0.1778 -0.2794)
						)
					)
					(width 0)
					(fill yes)
				)
			)
		)
	)
	(footprint ""
		(layer "F.Cu")
		(at 176.161446 -457.234036)
		(property "Reference" "C361"
			(at 0 0 0)
			(layer "F.SilkS")
			(hide yes)
			(effects
				(font
					(size 1.27 1.27)
				)
			)
		)
		(property "Value" "SCD1U16V2KX-3GP"
			(at 1.1811 -2.7051 0)
			(unlocked yes)
			(layer "F.Fab")
			(hide yes)
			(effects
				(font
					(size 1.016 1.016)
					(thickness 0.1524)
				)
			)
		)
		(property "Device Type" "C402H22"
			(at 1.1811 -4.2291 0)
			(unlocked yes)
			(layer "F.Fab")
			(hide yes)
			(effects
				(font
					(size 1.016 1.016)
					(thickness 0.1524)
				)
			)
		)
		(duplicate_pad_numbers_are_jumpers no)
		(fp_rect
			(start -0.4318 0.9525)
			(end 0.4318 -0.9525)
			(stroke
				(width 0)
				(type default)
			)
			(fill no)
			(layer "F.CrtYd")
		)
		(fp_rect
			(start -0.4318 0.9525)
			(end 0.4318 -0.9525)
			(stroke
				(width 0)
				(type default)
			)
			(fill no)
			(layer "F.Fab")
		)
		(pad "1" smd custom
			(at 0 -0.4445)
			(size 0.1524 0.1524)
			(layers "F.Cu" "F.Mask" "F.Paste")
			(net "P5VC_SENSE")
			(options
				(clearance outline)
				(anchor circle)
			)
			(primitives
				(gr_poly
					(pts
						(arc
							(start 0.3048 -0.2032)
							(mid 0.275042 -0.275042)
							(end 0.2032 -0.3048)
						)
						(arc
							(start -0.2032 -0.3048)
							(mid -0.275042 -0.275042)
							(end -0.3048 -0.2032)
						)
						(arc
							(start -0.3048 0.2032)
							(mid -0.275042 0.275042)
							(end -0.2032 0.3048)
						)
						(arc
							(start 0.2032 0.3048)
							(mid 0.275042 0.275042)
							(end 0.3048 0.2032)
						)
					)
					(width 0)
					(fill yes)
				)
			)
		)
		(pad "2" smd custom
			(at 0 0.4445)
			(size 0.1524 0.1524)
			(layers "F.Cu" "F.Mask" "F.Paste")
			(net "GND")
			(options
				(clearance outline)
				(anchor circle)
			)
			(primitives
				(gr_poly
					(pts
						(arc
							(start 0.3048 -0.2032)
							(mid 0.275042 -0.275042)
							(end 0.2032 -0.3048)
						)
						(arc
							(start -0.2032 -0.3048)
							(mid -0.275042 -0.275042)
							(end -0.3048 -0.2032)
						)
						(arc
							(start -0.3048 0.2032)
							(mid -0.275042 0.275042)
							(end -0.2032 0.3048)
						)
						(arc
							(start 0.2032 0.3048)
							(mid 0.275042 0.275042)
							(end 0.3048 0.2032)
						)
					)
					(width 0)
					(fill yes)
				)
			)
		)
	)
	(footprint ""
		(layer "F.Cu")
		(at 64.389 -485.013)
		(property "Reference" "C369"
			(at 0 0 0)
			(layer "F.SilkS")
			(hide yes)
			(effects
				(font
					(size 1.27 1.27)
				)
			)
		)
		(property "Value" "SCD033U25V2KX-GP"
			(at 1.1811 -2.7051 0)
			(unlocked yes)
			(layer "F.Fab")
			(hide yes)
			(effects
				(font
					(size 1.016 1.016)
					(thickness 0.1524)
				)
			)
		)
		(property "Device Type" "C402H22"
			(at 1.1811 -4.2291 0)
			(unlocked yes)
			(layer "F.Fab")
			(hide yes)
			(effects
				(font
					(size 1.016 1.016)
					(thickness 0.1524)
				)
			)
		)
		(duplicate_pad_numbers_are_jumpers no)
		(fp_rect
			(start -0.4318 0.9525)
			(end 0.4318 -0.9525)
			(stroke
				(width 0)
				(type default)
			)
			(fill no)
			(layer "F.CrtYd")
		)
		(fp_rect
			(start -0.4318 0.9525)
			(end 0.4318 -0.9525)
			(stroke
				(width 0)
				(type default)
			)
			(fill no)
			(layer "F.Fab")
		)
		(pad "1" smd custom
			(at 0 -0.4445)
			(size 0.1524 0.1524)
			(layers "F.Cu" "F.Mask" "F.Paste")
			(net "SW_HDD5_P")
			(options
				(clearance outline)
				(anchor circle)
			)
			(primitives
				(gr_poly
					(pts
						(arc
							(start 0.3048 -0.2032)
							(mid 0.275042 -0.275042)
							(end 0.2032 -0.3048)
						)
						(arc
							(start -0.2032 -0.3048)
							(mid -0.275042 -0.275042)
							(end -0.3048 -0.2032)
						)
						(arc
							(start -0.3048 0.2032)
							(mid -0.275042 0.275042)
							(end -0.2032 0.3048)
						)
						(arc
							(start 0.2032 0.3048)
							(mid 0.275042 0.275042)
							(end 0.3048 0.2032)
						)
					)
					(width 0)
					(fill yes)
				)
			)
		)
		(pad "2" smd custom
			(at 0 0.4445)
			(size 0.1524 0.1524)
			(layers "F.Cu" "F.Mask" "F.Paste")
			(net "GND")
			(options
				(clearance outline)
				(anchor circle)
			)
			(primitives
				(gr_poly
					(pts
						(arc
							(start 0.3048 -0.2032)
							(mid 0.275042 -0.275042)
							(end 0.2032 -0.3048)
						)
						(arc
							(start -0.2032 -0.3048)
							(mid -0.275042 -0.275042)
							(end -0.3048 -0.2032)
						)
						(arc
							(start -0.3048 0.2032)
							(mid -0.275042 0.275042)
							(end -0.2032 0.3048)
						)
						(arc
							(start 0.2032 0.3048)
							(mid 0.275042 0.275042)
							(end 0.3048 0.2032)
						)
					)
					(width 0)
					(fill yes)
				)
			)
		)
	)
	(footprint ""
		(layer "F.Cu")
		(at 195.326 -498.475)
		(property "Reference" "C379"
			(at 0 0 0)
			(layer "F.SilkS")
			(hide yes)
			(effects
				(font
					(size 1.27 1.27)
				)
			)
		)
		(property "Value" "SCD033U25V2KX-GP"
			(at 1.1811 -2.7051 0)
			(unlocked yes)
			(layer "F.Fab")
			(hide yes)
			(effects
				(font
					(size 1.016 1.016)
					(thickness 0.1524)
				)
			)
		)
		(property "Device Type" "C402H22"
			(at 1.1811 -4.2291 0)
			(unlocked yes)
			(layer "F.Fab")
			(hide yes)
			(effects
				(font
					(size 1.016 1.016)
					(thickness 0.1524)
				)
			)
		)
		(duplicate_pad_numbers_are_jumpers no)
		(fp_rect
			(start -0.4318 0.9525)
			(end 0.4318 -0.9525)
			(stroke
				(width 0)
				(type default)
			)
			(fill no)
			(layer "F.CrtYd")
		)
		(fp_rect
			(start -0.4318 0.9525)
			(end 0.4318 -0.9525)
			(stroke
				(width 0)
				(type default)
			)
			(fill no)
			(layer "F.Fab")
		)
		(pad "1" smd custom
			(at 0 -0.4445)
			(size 0.1524 0.1524)
			(layers "F.Cu" "F.Mask" "F.Paste")
			(net "P12V")
			(options
				(clearance outline)
				(anchor circle)
			)
			(primitives
				(gr_poly
					(pts
						(arc
							(start 0.3048 -0.2032)
							(mid 0.275042 -0.275042)
							(end 0.2032 -0.3048)
						)
						(arc
							(start -0.2032 -0.3048)
							(mid -0.275042 -0.275042)
							(end -0.3048 -0.2032)
						)
						(arc
							(start -0.3048 0.2032)
							(mid -0.275042 0.275042)
							(end -0.2032 0.3048)
						)
						(arc
							(start 0.2032 0.3048)
							(mid 0.275042 0.275042)
							(end 0.3048 0.2032)
						)
					)
					(width 0)
					(fill yes)
				)
			)
		)
		(pad "2" smd custom
			(at 0 0.4445)
			(size 0.1524 0.1524)
			(layers "F.Cu" "F.Mask" "F.Paste")
			(net "SW_HDD0_N")
			(options
				(clearance outline)
				(anchor circle)
			)
			(primitives
				(gr_poly
					(pts
						(arc
							(start 0.3048 -0.2032)
							(mid 0.275042 -0.275042)
							(end 0.2032 -0.3048)
						)
						(arc
							(start -0.2032 -0.3048)
							(mid -0.275042 -0.275042)
							(end -0.3048 -0.2032)
						)
						(arc
							(start -0.3048 0.2032)
							(mid -0.275042 0.275042)
							(end -0.2032 0.3048)
						)
						(arc
							(start 0.2032 0.3048)
							(mid 0.275042 0.275042)
							(end 0.3048 0.2032)
						)
					)
					(width 0)
					(fill yes)
				)
			)
		)
	)
	(footprint ""
		(layer "F.Cu")
		(at 55.955692 -87.912956 180)
		(property "Reference" "C258"
			(at 0 0 180)
			(layer "F.SilkS")
			(hide yes)
			(effects
				(font
					(size 1.27 1.27)
				)
			)
		)
		(property "Value" "SC10U25V6KX-1GP"
			(at -0.0762 -5.1308 180)
			(unlocked yes)
			(layer "F.Fab")
			(hide yes)
			(effects
				(font
					(size 1.016 1.016)
					(thickness 0.1524)
				)
			)
		)
		(property "Device Type" "C1206H71"
			(at -0.127 -6.6548 180)
			(unlocked yes)
			(layer "F.Fab")
			(hide yes)
			(effects
				(font
					(size 1.016 1.016)
					(thickness 0.1524)
				)
			)
		)
		(duplicate_pad_numbers_are_jumpers no)
		(fp_line
			(start 1.016 2.2352)
			(end -1.016 2.2352)
			(stroke
				(width 0.1524)
				(type default)
			)
			(layer "F.SilkS")
		)
		(fp_line
			(start 1.016 0.8382)
			(end 1.016 2.2352)
			(stroke
				(width 0.1524)
				(type default)
			)
			(layer "F.SilkS")
		)
		(fp_line
			(start 1.016 -2.2352)
			(end 1.016 -0.8382)
			(stroke
				(width 0.1524)
				(type default)
			)
			(layer "F.SilkS")
		)
		(fp_line
			(start -1.016 2.2352)
			(end -1.016 0.8382)
			(stroke
				(width 0.1524)
				(type default)
			)
			(layer "F.SilkS")
		)
		(fp_line
			(start -1.016 -0.8382)
			(end -1.016 -2.2352)
			(stroke
				(width 0.1524)
				(type default)
			)
			(layer "F.SilkS")
		)
		(fp_line
			(start -1.016 -2.2352)
			(end 1.016 -2.2352)
			(stroke
				(width 0.1524)
				(type default)
			)
			(layer "F.SilkS")
		)
		(fp_rect
			(start -1.0922 2.3114)
			(end 1.0922 -2.3114)
			(stroke
				(width 0)
				(type default)
			)
			(fill no)
			(layer "F.CrtYd")
		)
		(fp_poly
			(pts
				(xy 1.0922 -2.3114) (xy 1.0922 2.3114) (xy -1.0922 2.3114) (xy -1.0922 -2.3114)
			)
			(stroke
				(width 0)
				(type default)
			)
			(fill no)
			(layer "F.Fab")
		)
		(pad "1" smd rect
			(at 0 -1.397 180)
			(size 1.651 1.27)
			(layers "F.Cu" "F.Mask" "F.Paste")
			(net "P12V_HDD9")
		)
		(pad "2" smd rect
			(at 0 1.397 180)
			(size 1.651 1.27)
			(layers "F.Cu" "F.Mask" "F.Paste")
			(net "GND")
		)
	)
	(footprint ""
		(layer "F.Cu")
		(at 202.945746 -84.3407 -90)
		(property "Reference" "R439"
			(at 0 0 270)
			(layer "F.SilkS")
			(hide yes)
			(effects
				(font
					(size 1.27 1.27)
				)
			)
		)
		(property "Value" "4K7R2J-2-GP"
			(at 0.064008 -3.993896 270)
			(unlocked yes)
			(layer "F.Fab")
			(hide yes)
			(effects
				(font
					(size 1.016 1.016)
					(thickness 0.1524)
				)
			)
		)
		(property "Device Type" "R402H16"
			(at 0.064008 -5.517896 270)
			(unlocked yes)
			(layer "F.Fab")
			(hide yes)
			(effects
				(font
					(size 1.016 1.016)
					(thickness 0.1524)
				)
			)
		)
		(duplicate_pad_numbers_are_jumpers no)
		(fp_line
			(start -0.508 -0.9398)
			(end -0.508 0.9398)
			(stroke
				(width 0.1524)
				(type default)
			)
			(layer "F.SilkS")
		)
		(fp_line
			(start 0.508 -0.9398)
			(end -0.508 -0.9398)
			(stroke
				(width 0.1524)
				(type default)
			)
			(layer "F.SilkS")
		)
		(fp_rect
			(start -0.508 0.9398)
			(end 0.508 -0.9398)
			(stroke
				(width 0)
				(type default)
			)
			(fill no)
			(layer "F.CrtYd")
		)
		(fp_rect
			(start -0.508 0.9398)
			(end 0.508 -0.9398)
			(stroke
				(width 0)
				(type default)
			)
			(fill no)
			(layer "F.Fab")
		)
		(pad "1" smd custom
			(at 0 -0.4445 270)
			(size 0.1397 0.1397)
			(layers "F.Cu" "F.Mask" "F.Paste")
			(net "P3V3")
			(options
				(clearance outline)
				(anchor circle)
			)
			(primitives
				(gr_poly
					(pts
						(arc
							(start -0.1778 -0.2794)
							(mid -0.249642 -0.249642)
							(end -0.2794 -0.1778)
						)
						(arc
							(start -0.2794 0.1778)
							(mid -0.249642 0.249642)
							(end -0.1778 0.2794)
						)
						(arc
							(start 0.1778 0.2794)
							(mid 0.249642 0.249642)
							(end 0.2794 0.1778)
						)
						(arc
							(start 0.2794 -0.1778)
							(mid 0.249642 -0.249642)
							(end 0.1778 -0.2794)
						)
					)
					(width 0)
					(fill yes)
				)
			)
		)
		(pad "2" smd custom
			(at 0 0.4445 270)
			(size 0.1397 0.1397)
			(layers "F.Cu" "F.Mask" "F.Paste")
			(net "SAS2X28_B_HDD4_FLT")
			(options
				(clearance outline)
				(anchor circle)
			)
			(primitives
				(gr_poly
					(pts
						(arc
							(start -0.1778 -0.2794)
							(mid -0.249642 -0.249642)
							(end -0.2794 -0.1778)
						)
						(arc
							(start -0.2794 0.1778)
							(mid -0.249642 0.249642)
							(end -0.1778 0.2794)
						)
						(arc
							(start 0.1778 0.2794)
							(mid 0.249642 0.249642)
							(end 0.2794 0.1778)
						)
						(arc
							(start 0.2794 -0.1778)
							(mid 0.249642 -0.249642)
							(end 0.1778 -0.2794)
						)
					)
					(width 0)
					(fill yes)
				)
			)
		)
	)
	(footprint ""
		(layer "F.Cu")
		(at 46.006004 -20.936712 90)
		(property "Reference" "PR20"
			(at 0 0 90)
			(layer "F.SilkS")
			(hide yes)
			(effects
				(font
					(size 1.27 1.27)
				)
			)
		)
		(property "Value" "3D01R2F-GP"
			(at 0.064008 -3.993896 90)
			(unlocked yes)
			(layer "F.Fab")
			(hide yes)
			(effects
				(font
					(size 1.016 1.016)
					(thickness 0.1524)
				)
			)
		)
		(property "Device Type" "R402H16"
			(at 0.064008 -5.517896 90)
			(unlocked yes)
			(layer "F.Fab")
			(hide yes)
			(effects
				(font
					(size 1.016 1.016)
					(thickness 0.1524)
				)
			)
		)
		(duplicate_pad_numbers_are_jumpers no)
		(fp_line
			(start 0.508 -0.9398)
			(end -0.508 -0.9398)
			(stroke
				(width 0.1524)
				(type default)
			)
			(layer "F.SilkS")
		)
		(fp_line
			(start -0.508 -0.9398)
			(end -0.508 0.9398)
			(stroke
				(width 0.1524)
				(type default)
			)
			(layer "F.SilkS")
		)
		(fp_rect
			(start -0.508 0.9398)
			(end 0.508 -0.9398)
			(stroke
				(width 0)
				(type default)
			)
			(fill no)
			(layer "F.CrtYd")
		)
		(fp_rect
			(start -0.508 0.9398)
			(end 0.508 -0.9398)
			(stroke
				(width 0)
				(type default)
			)
			(fill no)
			(layer "F.Fab")
		)
		(pad "1" smd custom
			(at 0 -0.4445 90)
			(size 0.1397 0.1397)
			(layers "F.Cu" "F.Mask" "F.Paste")
			(net "GND")
			(options
				(clearance outline)
				(anchor circle)
			)
			(primitives
				(gr_poly
					(pts
						(arc
							(start -0.1778 -0.2794)
							(mid -0.249642 -0.249642)
							(end -0.2794 -0.1778)
						)
						(arc
							(start -0.2794 0.1778)
							(mid -0.249642 0.249642)
							(end -0.1778 0.2794)
						)
						(arc
							(start 0.1778 0.2794)
							(mid 0.249642 0.249642)
							(end 0.2794 0.1778)
						)
						(arc
							(start 0.2794 -0.1778)
							(mid 0.249642 -0.249642)
							(end 0.1778 -0.2794)
						)
					)
					(width 0)
					(fill yes)
				)
			)
		)
		(pad "2" smd custom
			(at 0 0.4445 90)
			(size 0.1397 0.1397)
			(layers "F.Cu" "F.Mask" "F.Paste")
			(net "P5VB_SNB")
			(options
				(clearance outline)
				(anchor circle)
			)
			(primitives
				(gr_poly
					(pts
						(arc
							(start -0.1778 -0.2794)
							(mid -0.249642 -0.249642)
							(end -0.2794 -0.1778)
						)
						(arc
							(start -0.2794 0.1778)
							(mid -0.249642 0.249642)
							(end -0.1778 0.2794)
						)
						(arc
							(start 0.1778 0.2794)
							(mid 0.249642 0.249642)
							(end 0.2794 0.1778)
						)
						(arc
							(start 0.2794 -0.1778)
							(mid 0.249642 -0.249642)
							(end 0.1778 -0.2794)
						)
					)
					(width 0)
					(fill yes)
				)
			)
		)
	)
	(footprint ""
		(layer "F.Cu")
		(at 28.828746 -498.8687 180)
		(property "Reference" "PL5"
			(at 0 0 180)
			(layer "F.SilkS")
			(hide yes)
			(effects
				(font
					(size 1.27 1.27)
				)
			)
		)
		(property "Value" "BLM41PG600-GP"
			(at -3.690874 -7.441184 180)
			(unlocked yes)
			(layer "F.Fab")
			(hide yes)
			(effects
				(font
					(size 1.016 1.016)
					(thickness 0.1524)
				)
			)
		)
		(property "Device Type" "L451616H71"
			(at -3.690874 -5.917184 180)
			(unlocked yes)
			(layer "F.Fab")
			(hide yes)
			(effects
				(font
					(size 1.016 1.016)
					(thickness 0.1524)
				)
			)
		)
		(duplicate_pad_numbers_are_jumpers no)
		(fp_line
			(start 2.8702 1.2954)
			(end 2.8702 -1.2954)
			(stroke
				(width 0.1524)
				(type default)
			)
			(layer "F.SilkS")
		)
		(fp_line
			(start 2.8702 1.2954)
			(end 2.8702 -1.2954)
			(stroke
				(width 0.1524)
				(type default)
			)
			(layer "F.SilkS")
		)
		(fp_line
			(start 2.8702 -1.2954)
			(end -2.8702 -1.2954)
			(stroke
				(width 0.1524)
				(type default)
			)
			(layer "F.SilkS")
		)
		(fp_line
			(start 2.8702 -1.2954)
			(end -2.8702 -1.2954)
			(stroke
				(width 0.1524)
				(type default)
			)
			(layer "F.SilkS")
		)
		(fp_line
			(start -2.8702 1.2954)
			(end 2.8702 1.2954)
			(stroke
				(width 0.1524)
				(type default)
			)
			(layer "F.SilkS")
		)
		(fp_line
			(start -2.8702 1.2954)
			(end 2.8702 1.2954)
			(stroke
				(width 0.1524)
				(type default)
			)
			(layer "F.SilkS")
		)
		(fp_line
			(start -2.8702 -1.2954)
			(end -2.8702 1.2954)
			(stroke
				(width 0.1524)
				(type default)
			)
			(layer "F.SilkS")
		)
		(fp_line
			(start -2.8702 -1.2954)
			(end -2.8702 1.2954)
			(stroke
				(width 0.1524)
				(type default)
			)
			(layer "F.SilkS")
		)
		(fp_poly
			(pts
				(xy -2.8702 1.2954) (xy 2.8702 1.2954) (xy 2.8702 -1.2954) (xy -2.8702 -1.2954)
			)
			(stroke
				(width 0)
				(type default)
			)
			(fill no)
			(layer "F.CrtYd")
		)
		(fp_poly
			(pts
				(xy -2.8702 1.2954) (xy 2.8702 1.2954) (xy 2.8702 -1.2954) (xy -2.8702 -1.2954)
			)
			(stroke
				(width 0)
				(type default)
			)
			(fill no)
			(layer "F.Fab")
		)
		(pad "1" smd rect
			(at -1.9685 0 180)
			(size 1.3716 1.8796)
			(layers "F.Cu" "F.Mask" "F.Paste")
			(net "P12V")
		)
		(pad "2" smd rect
			(at 1.9685 0 180)
			(size 1.3716 1.8796)
			(layers "F.Cu" "F.Mask" "F.Paste")
			(net "P5VC_12VIN")
		)
	)
	(footprint ""
		(layer "F.Cu")
		(at 57.4675 -274.955 90)
		(property "Reference" "R384"
			(at 0 0 90)
			(layer "F.SilkS")
			(hide yes)
			(effects
				(font
					(size 1.27 1.27)
				)
			)
		)
		(property "Value" "0R2J-2-GP"
			(at 0.064008 -3.993896 90)
			(unlocked yes)
			(layer "F.Fab")
			(hide yes)
			(effects
				(font
					(size 1.016 1.016)
					(thickness 0.1524)
				)
			)
		)
		(property "Device Type" "R402H16"
			(at 0.064008 -5.517896 90)
			(unlocked yes)
			(layer "F.Fab")
			(hide yes)
			(effects
				(font
					(size 1.016 1.016)
					(thickness 0.1524)
				)
			)
		)
		(duplicate_pad_numbers_are_jumpers no)
		(fp_line
			(start 0.508 -0.9398)
			(end -0.508 -0.9398)
			(stroke
				(width 0.1524)
				(type default)
			)
			(layer "F.SilkS")
		)
		(fp_line
			(start -0.508 -0.9398)
			(end -0.508 0.9398)
			(stroke
				(width 0.1524)
				(type default)
			)
			(layer "F.SilkS")
		)
		(fp_rect
			(start -0.508 0.9398)
			(end 0.508 -0.9398)
			(stroke
				(width 0)
				(type default)
			)
			(fill no)
			(layer "F.CrtYd")
		)
		(fp_rect
			(start -0.508 0.9398)
			(end 0.508 -0.9398)
			(stroke
				(width 0)
				(type default)
			)
			(fill no)
			(layer "F.Fab")
		)
		(pad "1" smd custom
			(at 0 -0.4445 90)
			(size 0.1397 0.1397)
			(layers "F.Cu" "F.Mask" "F.Paste")
			(net "HDD_PRSNT_NET7")
			(options
				(clearance outline)
				(anchor circle)
			)
			(primitives
				(gr_poly
					(pts
						(arc
							(start -0.1778 -0.2794)
							(mid -0.249642 -0.249642)
							(end -0.2794 -0.1778)
						)
						(arc
							(start -0.2794 0.1778)
							(mid -0.249642 0.249642)
							(end -0.1778 0.2794)
						)
						(arc
							(start 0.1778 0.2794)
							(mid 0.249642 0.249642)
							(end 0.2794 0.1778)
						)
						(arc
							(start 0.2794 -0.1778)
							(mid 0.249642 -0.249642)
							(end 0.1778 -0.2794)
						)
					)
					(width 0)
					(fill yes)
				)
			)
		)
		(pad "2" smd custom
			(at 0 0.4445 90)
			(size 0.1397 0.1397)
			(layers "F.Cu" "F.Mask" "F.Paste")
			(net "HDD7_LED_B")
			(options
				(clearance outline)
				(anchor circle)
			)
			(primitives
				(gr_poly
					(pts
						(arc
							(start -0.1778 -0.2794)
							(mid -0.249642 -0.249642)
							(end -0.2794 -0.1778)
						)
						(arc
							(start -0.2794 0.1778)
							(mid -0.249642 0.249642)
							(end -0.1778 0.2794)
						)
						(arc
							(start 0.1778 0.2794)
							(mid 0.249642 0.249642)
							(end 0.2794 0.1778)
						)
						(arc
							(start 0.2794 -0.1778)
							(mid 0.249642 -0.249642)
							(end 0.1778 -0.2794)
						)
					)
					(width 0)
					(fill yes)
				)
			)
		)
	)
	(footprint ""
		(layer "F.Cu")
		(at 230.335582 -246.479568 90)
		(property "Reference" "R130"
			(at 0 0 90)
			(layer "F.SilkS")
			(hide yes)
			(effects
				(font
					(size 1.27 1.27)
				)
			)
		)
		(property "Value" "0R2J-2-GP"
			(at 0.064008 -3.993896 90)
			(unlocked yes)
			(layer "F.Fab")
			(hide yes)
			(effects
				(font
					(size 1.016 1.016)
					(thickness 0.1524)
				)
			)
		)
		(property "Device Type" "R402H16"
			(at 0.064008 -5.517896 90)
			(unlocked yes)
			(layer "F.Fab")
			(hide yes)
			(effects
				(font
					(size 1.016 1.016)
					(thickness 0.1524)
				)
			)
		)
		(duplicate_pad_numbers_are_jumpers no)
		(fp_line
			(start 0.508 -0.9398)
			(end -0.508 -0.9398)
			(stroke
				(width 0.1524)
				(type default)
			)
			(layer "F.SilkS")
		)
		(fp_line
			(start -0.508 -0.9398)
			(end -0.508 0.9398)
			(stroke
				(width 0.1524)
				(type default)
			)
			(layer "F.SilkS")
		)
		(fp_rect
			(start -0.508 0.9398)
			(end 0.508 -0.9398)
			(stroke
				(width 0)
				(type default)
			)
			(fill no)
			(layer "F.CrtYd")
		)
		(fp_rect
			(start -0.508 0.9398)
			(end 0.508 -0.9398)
			(stroke
				(width 0)
				(type default)
			)
			(fill no)
			(layer "F.Fab")
		)
		(pad "1" smd custom
			(at 0 -0.4445 90)
			(size 0.1397 0.1397)
			(layers "F.Cu" "F.Mask" "F.Paste")
			(net "DRV_ACT_NET2")
			(options
				(clearance outline)
				(anchor circle)
			)
			(primitives
				(gr_poly
					(pts
						(arc
							(start -0.1778 -0.2794)
							(mid -0.249642 -0.249642)
							(end -0.2794 -0.1778)
						)
						(arc
							(start -0.2794 0.1778)
							(mid -0.249642 0.249642)
							(end -0.1778 0.2794)
						)
						(arc
							(start 0.1778 0.2794)
							(mid 0.249642 0.249642)
							(end 0.2794 0.1778)
						)
						(arc
							(start 0.2794 -0.1778)
							(mid 0.249642 -0.249642)
							(end 0.1778 -0.2794)
						)
					)
					(width 0)
					(fill yes)
				)
			)
		)
		(pad "2" smd custom
			(at 0 0.4445 90)
			(size 0.1397 0.1397)
			(layers "F.Cu" "F.Mask" "F.Paste")
			(net "DRIVE_ACT_2")
			(options
				(clearance outline)
				(anchor circle)
			)
			(primitives
				(gr_poly
					(pts
						(arc
							(start -0.1778 -0.2794)
							(mid -0.249642 -0.249642)
							(end -0.2794 -0.1778)
						)
						(arc
							(start -0.2794 0.1778)
							(mid -0.249642 0.249642)
							(end -0.1778 0.2794)
						)
						(arc
							(start 0.1778 0.2794)
							(mid 0.249642 0.249642)
							(end 0.2794 0.1778)
						)
						(arc
							(start 0.2794 -0.1778)
							(mid 0.249642 -0.249642)
							(end 0.1778 -0.2794)
						)
					)
					(width 0)
					(fill yes)
				)
			)
		)
	)
	(footprint ""
		(layer "F.Cu")
		(at 81.152746 -193.8147)
		(property "Reference" "Q18"
			(at 0 0 0)
			(layer "F.SilkS")
			(hide yes)
			(effects
				(font
					(size 1.27 1.27)
				)
			)
		)
		(property "Value" "2N7002DW-7F-GP"
			(at -2.3622 -8.2042 0)
			(unlocked yes)
			(layer "F.Fab")
			(hide yes)
			(effects
				(font
					(size 1.016 1.016)
					(thickness 0.1524)
				)
			)
		)
		(property "Device Type" "SOT-363H44"
			(at -2.3622 -10.1092 0)
			(unlocked yes)
			(layer "F.Fab")
			(hide yes)
			(effects
				(font
					(size 1.016 1.016)
					(thickness 0.1524)
				)
			)
		)
		(duplicate_pad_numbers_are_jumpers no)
		(fp_line
			(start -1.4478 -1.7018)
			(end -1.4478 1.7018)
			(stroke
				(width 0.1524)
				(type default)
			)
			(layer "F.SilkS")
		)
		(fp_line
			(start -1.4478 1.7018)
			(end 1.4478 1.7018)
			(stroke
				(width 0.1524)
				(type default)
			)
			(layer "F.SilkS")
		)
		(fp_line
			(start -1.27 1.524)
			(end -1.27 0.6604)
			(stroke
				(width 0.4826)
				(type default)
			)
			(layer "F.SilkS")
		)
		(fp_line
			(start 1.4478 -1.7018)
			(end -1.4478 -1.7018)
			(stroke
				(width 0.1524)
				(type default)
			)
			(layer "F.SilkS")
		)
		(fp_line
			(start 1.4478 1.7018)
			(end 1.4478 -1.7018)
			(stroke
				(width 0.1524)
				(type default)
			)
			(layer "F.SilkS")
		)
		(fp_poly
			(pts
				(xy -1.524 -1.778) (xy 1.524 -1.778) (xy 1.524 1.778) (xy -1.524 1.778)
			)
			(stroke
				(width 0)
				(type default)
			)
			(fill no)
			(layer "F.CrtYd")
		)
		(fp_poly
			(pts
				(xy -1.524 -1.778) (xy 1.524 -1.778) (xy 1.524 1.778) (xy -1.524 1.778)
			)
			(stroke
				(width 0)
				(type default)
			)
			(fill no)
			(layer "F.Fab")
		)
		(pad "1" smd rect
			(at -0.65024 0.9398)
			(size 0.4064 1.016)
			(layers "F.Cu" "F.Mask" "F.Paste")
			(net "GND")
		)
		(pad "2" smd rect
			(at 0 0.9398)
			(size 0.4064 1.016)
			(layers "F.Cu" "F.Mask" "F.Paste")
			(net "SW_PWR_R_HDD8")
		)
		(pad "3" smd rect
			(at 0.65024 0.9398)
			(size 0.4064 1.016)
			(layers "F.Cu" "F.Mask" "F.Paste")
			(net "SW_HDD8_P")
		)
		(pad "4" smd rect
			(at 0.65024 -0.9398)
			(size 0.4064 1.016)
			(layers "F.Cu" "F.Mask" "F.Paste")
			(net "GND")
		)
		(pad "5" smd rect
			(at 0 -0.9398)
			(size 0.4064 1.016)
			(layers "F.Cu" "F.Mask" "F.Paste")
			(net "SW_HDD8_G")
		)
		(pad "6" smd rect
			(at -0.65024 -0.9398)
			(size 0.4064 1.016)
			(layers "F.Cu" "F.Mask" "F.Paste")
			(net "SW_HDD8_R")
		)
	)
	(footprint ""
		(layer "F.Cu")
		(at 215.645746 -286.9057 -90)
		(property "Reference" "R138"
			(at 0 0 270)
			(layer "F.SilkS")
			(hide yes)
			(effects
				(font
					(size 1.27 1.27)
				)
			)
		)
		(property "Value" "2R2010J-1-GP"
			(at 0.254 -8.0772 270)
			(unlocked yes)
			(layer "F.Fab")
			(hide yes)
			(effects
				(font
					(size 1.016 1.016)
					(thickness 0.1524)
				)
			)
		)
		(property "Device Type" "R2010H28"
			(at 0.254 -9.6774 270)
			(unlocked yes)
			(layer "F.Fab")
			(hide yes)
			(effects
				(font
					(size 1.016 1.016)
					(thickness 0.1524)
				)
			)
		)
		(duplicate_pad_numbers_are_jumpers no)
		(fp_line
			(start -1.651 3.302)
			(end 1.651 3.302)
			(stroke
				(width 0.1524)
				(type default)
			)
			(layer "F.SilkS")
		)
		(fp_line
			(start 1.651 3.302)
			(end 1.651 -3.302)
			(stroke
				(width 0.1524)
				(type default)
			)
			(layer "F.SilkS")
		)
		(fp_line
			(start -1.651 -3.302)
			(end -1.651 3.302)
			(stroke
				(width 0.1524)
				(type default)
			)
			(layer "F.SilkS")
		)
		(fp_line
			(start 1.651 -3.302)
			(end -1.651 -3.302)
			(stroke
				(width 0.1524)
				(type default)
			)
			(layer "F.SilkS")
		)
		(fp_rect
			(start -1.7272 -3.3782)
			(end 1.7272 3.3782)
			(stroke
				(width 0)
				(type default)
			)
			(fill no)
			(layer "F.CrtYd")
		)
		(fp_poly
			(pts
				(xy 1.7272 3.3782) (xy 1.7272 -3.3782) (xy -1.7272 -3.3782) (xy -1.7272 3.3782)
			)
			(stroke
				(width 0)
				(type default)
			)
			(fill no)
			(layer "F.Fab")
		)
		(pad "1" smd rect
			(at 0 -2.3495 270)
			(size 2.794 1.143)
			(layers "F.Cu" "F.Mask" "F.Paste")
			(net "12V_PRE_2")
		)
		(pad "2" smd rect
			(at 0 2.3495 270)
			(size 2.794 1.143)
			(layers "F.Cu" "F.Mask" "F.Paste")
			(net "P12V_HDD2")
		)
	)
	(footprint ""
		(layer "F.Cu")
		(at 190.754 -495.046 180)
		(property "Reference" "R112"
			(at 0 0 180)
			(layer "F.SilkS")
			(hide yes)
			(effects
				(font
					(size 1.27 1.27)
				)
			)
		)
		(property "Value" "0R2J-2-GP"
			(at 0.064008 -3.993896 180)
			(unlocked yes)
			(layer "F.Fab")
			(hide yes)
			(effects
				(font
					(size 1.016 1.016)
					(thickness 0.1524)
				)
			)
		)
		(property "Device Type" "R402H16"
			(at 0.064008 -5.517896 180)
			(unlocked yes)
			(layer "F.Fab")
			(hide yes)
			(effects
				(font
					(size 1.016 1.016)
					(thickness 0.1524)
				)
			)
		)
		(duplicate_pad_numbers_are_jumpers no)
		(fp_line
			(start 0.508 -0.9398)
			(end -0.508 -0.9398)
			(stroke
				(width 0.1524)
				(type default)
			)
			(layer "F.SilkS")
		)
		(fp_line
			(start -0.508 -0.9398)
			(end -0.508 0.9398)
			(stroke
				(width 0.1524)
				(type default)
			)
			(layer "F.SilkS")
		)
		(fp_rect
			(start -0.508 0.9398)
			(end 0.508 -0.9398)
			(stroke
				(width 0)
				(type default)
			)
			(fill no)
			(layer "F.CrtYd")
		)
		(fp_rect
			(start -0.508 0.9398)
			(end 0.508 -0.9398)
			(stroke
				(width 0)
				(type default)
			)
			(fill no)
			(layer "F.Fab")
		)
		(pad "1" smd custom
			(at 0 -0.4445 180)
			(size 0.1397 0.1397)
			(layers "F.Cu" "F.Mask" "F.Paste")
			(net "SW_PWR_HDD0")
			(options
				(clearance outline)
				(anchor circle)
			)
			(primitives
				(gr_poly
					(pts
						(arc
							(start -0.1778 -0.2794)
							(mid -0.249642 -0.249642)
							(end -0.2794 -0.1778)
						)
						(arc
							(start -0.2794 0.1778)
							(mid -0.249642 0.249642)
							(end -0.1778 0.2794)
						)
						(arc
							(start 0.1778 0.2794)
							(mid 0.249642 0.249642)
							(end 0.2794 0.1778)
						)
						(arc
							(start 0.2794 -0.1778)
							(mid 0.249642 -0.249642)
							(end 0.1778 -0.2794)
						)
					)
					(width 0)
					(fill yes)
				)
			)
		)
		(pad "2" smd custom
			(at 0 0.4445 180)
			(size 0.1397 0.1397)
			(layers "F.Cu" "F.Mask" "F.Paste")
			(net "SW_PWR_R_HDD0")
			(options
				(clearance outline)
				(anchor circle)
			)
			(primitives
				(gr_poly
					(pts
						(arc
							(start -0.1778 -0.2794)
							(mid -0.249642 -0.249642)
							(end -0.2794 -0.1778)
						)
						(arc
							(start -0.2794 0.1778)
							(mid -0.249642 0.249642)
							(end -0.1778 0.2794)
						)
						(arc
							(start 0.1778 0.2794)
							(mid 0.249642 0.249642)
							(end 0.2794 0.1778)
						)
						(arc
							(start 0.2794 -0.1778)
							(mid 0.249642 -0.249642)
							(end 0.1778 -0.2794)
						)
					)
					(width 0)
					(fill yes)
				)
			)
		)
	)
	(footprint ""
		(layer "F.Cu")
		(at 5.969 -29.083 -90)
		(property "Reference" "C132"
			(at 0 0 270)
			(layer "F.SilkS")
			(hide yes)
			(effects
				(font
					(size 1.27 1.27)
				)
			)
		)
		(property "Value" "SC1U25V3KX-1-GP"
			(at 0 -2.8194 270)
			(unlocked yes)
			(layer "F.Fab")
			(hide yes)
			(effects
				(font
					(size 1.016 1.016)
					(thickness 0.1524)
				)
			)
		)
		(property "Device Type" "C603H36"
			(at 0 -4.3434 270)
			(unlocked yes)
			(layer "F.Fab")
			(hide yes)
			(effects
				(font
					(size 1.016 1.016)
					(thickness 0.1524)
				)
			)
		)
		(duplicate_pad_numbers_are_jumpers no)
		(fp_line
			(start 0.508 0)
			(end -0.508 0)
			(stroke
				(width 0.2032)
				(type default)
			)
			(layer "F.SilkS")
		)
		(fp_rect
			(start -0.5842 1.3335)
			(end 0.5842 -1.3335)
			(stroke
				(width 0)
				(type default)
			)
			(fill no)
			(layer "F.CrtYd")
		)
		(fp_rect
			(start -0.5842 1.3335)
			(end 0.5842 -1.3335)
			(stroke
				(width 0)
				(type default)
			)
			(fill no)
			(layer "F.Fab")
		)
		(pad "1" smd custom
			(at 0 -0.762 270)
			(size 0.2159 0.2159)
			(layers "F.Cu" "F.Mask" "F.Paste")
			(net "P12V")
			(options
				(clearance outline)
				(anchor circle)
			)
			(primitives
				(gr_poly
					(pts
						(arc
							(start -0.3302 -0.4318)
							(mid -0.402042 -0.402042)
							(end -0.4318 -0.3302)
						)
						(arc
							(start -0.4318 0.3302)
							(mid -0.402042 0.402042)
							(end -0.3302 0.4318)
						)
						(arc
							(start 0.3302 0.4318)
							(mid 0.402042 0.402042)
							(end 0.4318 0.3302)
						)
						(arc
							(start 0.4318 -0.3302)
							(mid 0.402042 -0.402042)
							(end 0.3302 -0.4318)
						)
					)
					(width 0)
					(fill yes)
				)
			)
		)
		(pad "2" smd custom
			(at 0 0.762 270)
			(size 0.2159 0.2159)
			(layers "F.Cu" "F.Mask" "F.Paste")
			(net "GND")
			(options
				(clearance outline)
				(anchor circle)
			)
			(primitives
				(gr_poly
					(pts
						(arc
							(start -0.3302 -0.4318)
							(mid -0.402042 -0.402042)
							(end -0.4318 -0.3302)
						)
						(arc
							(start -0.4318 0.3302)
							(mid -0.402042 0.402042)
							(end -0.3302 0.4318)
						)
						(arc
							(start 0.3302 0.4318)
							(mid 0.402042 0.402042)
							(end 0.4318 0.3302)
						)
						(arc
							(start 0.4318 -0.3302)
							(mid 0.402042 -0.402042)
							(end 0.3302 -0.4318)
						)
					)
					(width 0)
					(fill yes)
				)
			)
		)
	)
	(footprint ""
		(layer "F.Cu")
		(at 62.563756 -492.661702)
		(property "Reference" "C191"
			(at 0 0 0)
			(layer "F.SilkS")
			(hide yes)
			(effects
				(font
					(size 1.27 1.27)
				)
			)
		)
		(property "Value" "SC10U25V6KX-1GP"
			(at -0.0762 -5.1308 0)
			(unlocked yes)
			(layer "F.Fab")
			(hide yes)
			(effects
				(font
					(size 1.016 1.016)
					(thickness 0.1524)
				)
			)
		)
		(property "Device Type" "C1206H71"
			(at -0.127 -6.6548 0)
			(unlocked yes)
			(layer "F.Fab")
			(hide yes)
			(effects
				(font
					(size 1.016 1.016)
					(thickness 0.1524)
				)
			)
		)
		(duplicate_pad_numbers_are_jumpers no)
		(fp_line
			(start -1.016 -2.2352)
			(end 1.016 -2.2352)
			(stroke
				(width 0.1524)
				(type default)
			)
			(layer "F.SilkS")
		)
		(fp_line
			(start -1.016 -0.8382)
			(end -1.016 -2.2352)
			(stroke
				(width 0.1524)
				(type default)
			)
			(layer "F.SilkS")
		)
		(fp_line
			(start -1.016 2.2352)
			(end -1.016 0.8382)
			(stroke
				(width 0.1524)
				(type default)
			)
			(layer "F.SilkS")
		)
		(fp_line
			(start 1.016 -2.2352)
			(end 1.016 -0.8382)
			(stroke
				(width 0.1524)
				(type default)
			)
			(layer "F.SilkS")
		)
		(fp_line
			(start 1.016 0.8382)
			(end 1.016 2.2352)
			(stroke
				(width 0.1524)
				(type default)
			)
			(layer "F.SilkS")
		)
		(fp_line
			(start 1.016 2.2352)
			(end -1.016 2.2352)
			(stroke
				(width 0.1524)
				(type default)
			)
			(layer "F.SilkS")
		)
		(fp_rect
			(start -1.0922 2.3114)
			(end 1.0922 -2.3114)
			(stroke
				(width 0)
				(type default)
			)
			(fill no)
			(layer "F.CrtYd")
		)
		(fp_poly
			(pts
				(xy 1.0922 -2.3114) (xy 1.0922 2.3114) (xy -1.0922 2.3114) (xy -1.0922 -2.3114)
			)
			(stroke
				(width 0)
				(type default)
			)
			(fill no)
			(layer "F.Fab")
		)
		(pad "1" smd rect
			(at 0 -1.397)
			(size 1.651 1.27)
			(layers "F.Cu" "F.Mask" "F.Paste")
			(net "P12V_HDD5")
		)
		(pad "2" smd rect
			(at 0 1.397)
			(size 1.651 1.27)
			(layers "F.Cu" "F.Mask" "F.Paste")
			(net "GND")
		)
	)
	(footprint ""
		(layer "F.Cu")
		(at 193.802 -293.878 180)
		(property "Reference" "R565"
			(at 0 0 180)
			(layer "F.SilkS")
			(hide yes)
			(effects
				(font
					(size 1.27 1.27)
				)
			)
		)
		(property "Value" "300KR2F-GP"
			(at 0.064008 -3.993896 180)
			(unlocked yes)
			(layer "F.Fab")
			(hide yes)
			(effects
				(font
					(size 1.016 1.016)
					(thickness 0.1524)
				)
			)
		)
		(property "Device Type" "R402H16"
			(at 0.064008 -5.517896 180)
			(unlocked yes)
			(layer "F.Fab")
			(hide yes)
			(effects
				(font
					(size 1.016 1.016)
					(thickness 0.1524)
				)
			)
		)
		(duplicate_pad_numbers_are_jumpers no)
		(fp_line
			(start 0.508 -0.9398)
			(end -0.508 -0.9398)
			(stroke
				(width 0.1524)
				(type default)
			)
			(layer "F.SilkS")
		)
		(fp_line
			(start -0.508 -0.9398)
			(end -0.508 0.9398)
			(stroke
				(width 0.1524)
				(type default)
			)
			(layer "F.SilkS")
		)
		(fp_rect
			(start -0.508 0.9398)
			(end 0.508 -0.9398)
			(stroke
				(width 0)
				(type default)
			)
			(fill no)
			(layer "F.CrtYd")
		)
		(fp_rect
			(start -0.508 0.9398)
			(end 0.508 -0.9398)
			(stroke
				(width 0)
				(type default)
			)
			(fill no)
			(layer "F.Fab")
		)
		(pad "1" smd custom
			(at 0 -0.4445 180)
			(size 0.1397 0.1397)
			(layers "F.Cu" "F.Mask" "F.Paste")
			(net "SW_HDD2_N")
			(options
				(clearance outline)
				(anchor circle)
			)
			(primitives
				(gr_poly
					(pts
						(arc
							(start -0.1778 -0.2794)
							(mid -0.249642 -0.249642)
							(end -0.2794 -0.1778)
						)
						(arc
							(start -0.2794 0.1778)
							(mid -0.249642 0.249642)
							(end -0.1778 0.2794)
						)
						(arc
							(start 0.1778 0.2794)
							(mid 0.249642 0.249642)
							(end 0.2794 0.1778)
						)
						(arc
							(start 0.2794 -0.1778)
							(mid 0.249642 -0.249642)
							(end 0.1778 -0.2794)
						)
					)
					(width 0)
					(fill yes)
				)
			)
		)
		(pad "2" smd custom
			(at 0 0.4445 180)
			(size 0.1397 0.1397)
			(layers "F.Cu" "F.Mask" "F.Paste")
			(net "P12V")
			(options
				(clearance outline)
				(anchor circle)
			)
			(primitives
				(gr_poly
					(pts
						(arc
							(start -0.1778 -0.2794)
							(mid -0.249642 -0.249642)
							(end -0.2794 -0.1778)
						)
						(arc
							(start -0.2794 0.1778)
							(mid -0.249642 0.249642)
							(end -0.1778 0.2794)
						)
						(arc
							(start 0.1778 0.2794)
							(mid 0.249642 0.249642)
							(end 0.2794 0.1778)
						)
						(arc
							(start 0.2794 -0.1778)
							(mid 0.249642 -0.249642)
							(end 0.1778 -0.2794)
						)
					)
					(width 0)
					(fill yes)
				)
			)
		)
	)
	(footprint ""
		(layer "F.Cu")
		(at 190.930784 -184.120028 -90)
		(property "Reference" "R147"
			(at 0 0 270)
			(layer "F.SilkS")
			(hide yes)
			(effects
				(font
					(size 1.27 1.27)
				)
			)
		)
		(property "Value" "1KR2F-3-GP"
			(at 0.064008 -3.993896 270)
			(unlocked yes)
			(layer "F.Fab")
			(hide yes)
			(effects
				(font
					(size 1.016 1.016)
					(thickness 0.1524)
				)
			)
		)
		(property "Device Type" "R402H16"
			(at 0.064008 -5.517896 270)
			(unlocked yes)
			(layer "F.Fab")
			(hide yes)
			(effects
				(font
					(size 1.016 1.016)
					(thickness 0.1524)
				)
			)
		)
		(duplicate_pad_numbers_are_jumpers no)
		(fp_line
			(start -0.508 -0.9398)
			(end -0.508 0.9398)
			(stroke
				(width 0.1524)
				(type default)
			)
			(layer "F.SilkS")
		)
		(fp_line
			(start 0.508 -0.9398)
			(end -0.508 -0.9398)
			(stroke
				(width 0.1524)
				(type default)
			)
			(layer "F.SilkS")
		)
		(fp_rect
			(start -0.508 0.9398)
			(end 0.508 -0.9398)
			(stroke
				(width 0)
				(type default)
			)
			(fill no)
			(layer "F.CrtYd")
		)
		(fp_rect
			(start -0.508 0.9398)
			(end 0.508 -0.9398)
			(stroke
				(width 0)
				(type default)
			)
			(fill no)
			(layer "F.Fab")
		)
		(pad "1" smd custom
			(at 0 -0.4445 270)
			(size 0.1397 0.1397)
			(layers "F.Cu" "F.Mask" "F.Paste")
			(net "P3V3")
			(options
				(clearance outline)
				(anchor circle)
			)
			(primitives
				(gr_poly
					(pts
						(arc
							(start -0.1778 -0.2794)
							(mid -0.249642 -0.249642)
							(end -0.2794 -0.1778)
						)
						(arc
							(start -0.2794 0.1778)
							(mid -0.249642 0.249642)
							(end -0.1778 0.2794)
						)
						(arc
							(start 0.1778 0.2794)
							(mid 0.249642 0.249642)
							(end 0.2794 0.1778)
						)
						(arc
							(start 0.2794 -0.1778)
							(mid 0.249642 -0.249642)
							(end 0.1778 -0.2794)
						)
					)
					(width 0)
					(fill yes)
				)
			)
		)
		(pad "2" smd custom
			(at 0 0.4445 270)
			(size 0.1397 0.1397)
			(layers "F.Cu" "F.Mask" "F.Paste")
			(net "SW_PWR_HDD3")
			(options
				(clearance outline)
				(anchor circle)
			)
			(primitives
				(gr_poly
					(pts
						(arc
							(start -0.1778 -0.2794)
							(mid -0.249642 -0.249642)
							(end -0.2794 -0.1778)
						)
						(arc
							(start -0.2794 0.1778)
							(mid -0.249642 0.249642)
							(end -0.1778 0.2794)
						)
						(arc
							(start 0.1778 0.2794)
							(mid 0.249642 0.249642)
							(end 0.2794 0.1778)
						)
						(arc
							(start 0.2794 -0.1778)
							(mid 0.249642 -0.249642)
							(end 0.1778 -0.2794)
						)
					)
					(width 0)
					(fill yes)
				)
			)
		)
	)
	(footprint ""
		(layer "F.Cu")
		(at 14.731746 -258.3307 -90)
		(property "Reference" "R268"
			(at 0 0 270)
			(layer "F.SilkS")
			(hide yes)
			(effects
				(font
					(size 1.27 1.27)
				)
			)
		)
		(property "Value" "10KR2F-2-GP"
			(at 0.064008 -3.993896 270)
			(unlocked yes)
			(layer "F.Fab")
			(hide yes)
			(effects
				(font
					(size 1.016 1.016)
					(thickness 0.1524)
				)
			)
		)
		(property "Device Type" "R402H16"
			(at 0.064008 -5.517896 270)
			(unlocked yes)
			(layer "F.Fab")
			(hide yes)
			(effects
				(font
					(size 1.016 1.016)
					(thickness 0.1524)
				)
			)
		)
		(duplicate_pad_numbers_are_jumpers no)
		(fp_line
			(start -0.508 -0.9398)
			(end -0.508 0.9398)
			(stroke
				(width 0.1524)
				(type default)
			)
			(layer "F.SilkS")
		)
		(fp_line
			(start 0.508 -0.9398)
			(end -0.508 -0.9398)
			(stroke
				(width 0.1524)
				(type default)
			)
			(layer "F.SilkS")
		)
		(fp_rect
			(start -0.508 0.9398)
			(end 0.508 -0.9398)
			(stroke
				(width 0)
				(type default)
			)
			(fill no)
			(layer "F.CrtYd")
		)
		(fp_rect
			(start -0.508 0.9398)
			(end 0.508 -0.9398)
			(stroke
				(width 0)
				(type default)
			)
			(fill no)
			(layer "F.Fab")
		)
		(pad "1" smd custom
			(at 0 -0.4445 270)
			(size 0.1397 0.1397)
			(layers "F.Cu" "F.Mask" "F.Paste")
			(net "P5VC")
			(options
				(clearance outline)
				(anchor circle)
			)
			(primitives
				(gr_poly
					(pts
						(arc
							(start -0.1778 -0.2794)
							(mid -0.249642 -0.249642)
							(end -0.2794 -0.1778)
						)
						(arc
							(start -0.2794 0.1778)
							(mid -0.249642 0.249642)
							(end -0.1778 0.2794)
						)
						(arc
							(start 0.1778 0.2794)
							(mid 0.249642 0.249642)
							(end 0.2794 0.1778)
						)
						(arc
							(start 0.2794 -0.1778)
							(mid 0.249642 -0.249642)
							(end 0.1778 -0.2794)
						)
					)
					(width 0)
					(fill yes)
				)
			)
		)
		(pad "2" smd custom
			(at 0 0.4445 270)
			(size 0.1397 0.1397)
			(layers "F.Cu" "F.Mask" "F.Paste")
			(net "DRIVE_ACT_12")
			(options
				(clearance outline)
				(anchor circle)
			)
			(primitives
				(gr_poly
					(pts
						(arc
							(start -0.1778 -0.2794)
							(mid -0.249642 -0.249642)
							(end -0.2794 -0.1778)
						)
						(arc
							(start -0.2794 0.1778)
							(mid -0.249642 0.249642)
							(end -0.1778 0.2794)
						)
						(arc
							(start 0.1778 0.2794)
							(mid 0.249642 0.249642)
							(end 0.2794 0.1778)
						)
						(arc
							(start 0.2794 -0.1778)
							(mid 0.249642 -0.249642)
							(end 0.1778 -0.2794)
						)
					)
					(width 0)
					(fill yes)
				)
			)
		)
	)
	(footprint ""
		(layer "F.Cu")
		(at 52.705 -208.534)
		(property "Reference" "C391"
			(at 0 0 0)
			(layer "F.SilkS")
			(hide yes)
			(effects
				(font
					(size 1.27 1.27)
				)
			)
		)
		(property "Value" "SCD033U25V2KX-GP"
			(at 1.1811 -2.7051 0)
			(unlocked yes)
			(layer "F.Fab")
			(hide yes)
			(effects
				(font
					(size 1.016 1.016)
					(thickness 0.1524)
				)
			)
		)
		(property "Device Type" "C402H22"
			(at 1.1811 -4.2291 0)
			(unlocked yes)
			(layer "F.Fab")
			(hide yes)
			(effects
				(font
					(size 1.016 1.016)
					(thickness 0.1524)
				)
			)
		)
		(duplicate_pad_numbers_are_jumpers no)
		(fp_rect
			(start -0.4318 0.9525)
			(end 0.4318 -0.9525)
			(stroke
				(width 0)
				(type default)
			)
			(fill no)
			(layer "F.CrtYd")
		)
		(fp_rect
			(start -0.4318 0.9525)
			(end 0.4318 -0.9525)
			(stroke
				(width 0)
				(type default)
			)
			(fill no)
			(layer "F.Fab")
		)
		(pad "1" smd custom
			(at 0 -0.4445)
			(size 0.1524 0.1524)
			(layers "F.Cu" "F.Mask" "F.Paste")
			(net "P12V")
			(options
				(clearance outline)
				(anchor circle)
			)
			(primitives
				(gr_poly
					(pts
						(arc
							(start 0.3048 -0.2032)
							(mid 0.275042 -0.275042)
							(end 0.2032 -0.3048)
						)
						(arc
							(start -0.2032 -0.3048)
							(mid -0.275042 -0.275042)
							(end -0.3048 -0.2032)
						)
						(arc
							(start -0.3048 0.2032)
							(mid -0.275042 0.275042)
							(end -0.2032 0.3048)
						)
						(arc
							(start 0.2032 0.3048)
							(mid 0.275042 0.275042)
							(end 0.3048 0.2032)
						)
					)
					(width 0)
					(fill yes)
				)
			)
		)
		(pad "2" smd custom
			(at 0 0.4445)
			(size 0.1524 0.1524)
			(layers "F.Cu" "F.Mask" "F.Paste")
			(net "SW_HDD12_N")
			(options
				(clearance outline)
				(anchor circle)
			)
			(primitives
				(gr_poly
					(pts
						(arc
							(start 0.3048 -0.2032)
							(mid 0.275042 -0.275042)
							(end 0.2032 -0.3048)
						)
						(arc
							(start -0.2032 -0.3048)
							(mid -0.275042 -0.275042)
							(end -0.3048 -0.2032)
						)
						(arc
							(start -0.3048 0.2032)
							(mid -0.275042 0.275042)
							(end -0.2032 0.3048)
						)
						(arc
							(start 0.2032 0.3048)
							(mid 0.275042 0.275042)
							(end 0.3048 0.2032)
						)
					)
					(width 0)
					(fill yes)
				)
			)
		)
	)
	(footprint ""
		(layer "F.Cu")
		(at 5.079746 -491.7567 90)
		(property "Reference" "PR39"
			(at 0 0 90)
			(layer "F.SilkS")
			(hide yes)
			(effects
				(font
					(size 1.27 1.27)
				)
			)
		)
		(property "Value" "10KR2F-2-GP"
			(at 0.064008 -3.993896 90)
			(unlocked yes)
			(layer "F.Fab")
			(hide yes)
			(effects
				(font
					(size 1.016 1.016)
					(thickness 0.1524)
				)
			)
		)
		(property "Device Type" "R402H16"
			(at 0.064008 -5.517896 90)
			(unlocked yes)
			(layer "F.Fab")
			(hide yes)
			(effects
				(font
					(size 1.016 1.016)
					(thickness 0.1524)
				)
			)
		)
		(duplicate_pad_numbers_are_jumpers no)
		(fp_line
			(start 0.508 -0.9398)
			(end -0.508 -0.9398)
			(stroke
				(width 0.1524)
				(type default)
			)
			(layer "F.SilkS")
		)
		(fp_line
			(start -0.508 -0.9398)
			(end -0.508 0.9398)
			(stroke
				(width 0.1524)
				(type default)
			)
			(layer "F.SilkS")
		)
		(fp_rect
			(start -0.508 0.9398)
			(end 0.508 -0.9398)
			(stroke
				(width 0)
				(type default)
			)
			(fill no)
			(layer "F.CrtYd")
		)
		(fp_rect
			(start -0.508 0.9398)
			(end 0.508 -0.9398)
			(stroke
				(width 0)
				(type default)
			)
			(fill no)
			(layer "F.Fab")
		)
		(pad "1" smd custom
			(at 0 -0.4445 90)
			(size 0.1397 0.1397)
			(layers "F.Cu" "F.Mask" "F.Paste")
			(net "P5VC_VREG")
			(options
				(clearance outline)
				(anchor circle)
			)
			(primitives
				(gr_poly
					(pts
						(arc
							(start -0.1778 -0.2794)
							(mid -0.249642 -0.249642)
							(end -0.2794 -0.1778)
						)
						(arc
							(start -0.2794 0.1778)
							(mid -0.249642 0.249642)
							(end -0.1778 0.2794)
						)
						(arc
							(start 0.1778 0.2794)
							(mid 0.249642 0.249642)
							(end 0.2794 0.1778)
						)
						(arc
							(start 0.2794 -0.1778)
							(mid 0.249642 -0.249642)
							(end 0.1778 -0.2794)
						)
					)
					(width 0)
					(fill yes)
				)
			)
		)
		(pad "2" smd custom
			(at 0 0.4445 90)
			(size 0.1397 0.1397)
			(layers "F.Cu" "F.Mask" "F.Paste")
			(net "P5VC_PGD")
			(options
				(clearance outline)
				(anchor circle)
			)
			(primitives
				(gr_poly
					(pts
						(arc
							(start -0.1778 -0.2794)
							(mid -0.249642 -0.249642)
							(end -0.2794 -0.1778)
						)
						(arc
							(start -0.2794 0.1778)
							(mid -0.249642 0.249642)
							(end -0.1778 0.2794)
						)
						(arc
							(start 0.1778 0.2794)
							(mid 0.249642 0.249642)
							(end 0.2794 0.1778)
						)
						(arc
							(start 0.2794 -0.1778)
							(mid 0.249642 -0.249642)
							(end 0.1778 -0.2794)
						)
					)
					(width 0)
					(fill yes)
				)
			)
		)
	)
	(footprint ""
		(layer "F.Cu")
		(at 221.799912 -41.636696 90)
		(property "Reference" "R157"
			(at 0 0 90)
			(layer "F.SilkS")
			(hide yes)
			(effects
				(font
					(size 1.27 1.27)
				)
			)
		)
		(property "Value" "402R2F-GP"
			(at 0.064008 -3.993896 90)
			(unlocked yes)
			(layer "F.Fab")
			(hide yes)
			(effects
				(font
					(size 1.016 1.016)
					(thickness 0.1524)
				)
			)
		)
		(property "Device Type" "R402H16"
			(at 0.064008 -5.517896 90)
			(unlocked yes)
			(layer "F.Fab")
			(hide yes)
			(effects
				(font
					(size 1.016 1.016)
					(thickness 0.1524)
				)
			)
		)
		(duplicate_pad_numbers_are_jumpers no)
		(fp_line
			(start 0.508 -0.9398)
			(end -0.508 -0.9398)
			(stroke
				(width 0.1524)
				(type default)
			)
			(layer "F.SilkS")
		)
		(fp_line
			(start -0.508 -0.9398)
			(end -0.508 0.9398)
			(stroke
				(width 0.1524)
				(type default)
			)
			(layer "F.SilkS")
		)
		(fp_rect
			(start -0.508 0.9398)
			(end 0.508 -0.9398)
			(stroke
				(width 0)
				(type default)
			)
			(fill no)
			(layer "F.CrtYd")
		)
		(fp_rect
			(start -0.508 0.9398)
			(end 0.508 -0.9398)
			(stroke
				(width 0)
				(type default)
			)
			(fill no)
			(layer "F.Fab")
		)
		(pad "1" smd custom
			(at 0 -0.4445 90)
			(size 0.1397 0.1397)
			(layers "F.Cu" "F.Mask" "F.Paste")
			(net "P5VA_HDD4_LED")
			(options
				(clearance outline)
				(anchor circle)
			)
			(primitives
				(gr_poly
					(pts
						(arc
							(start -0.1778 -0.2794)
							(mid -0.249642 -0.249642)
							(end -0.2794 -0.1778)
						)
						(arc
							(start -0.2794 0.1778)
							(mid -0.249642 0.249642)
							(end -0.1778 0.2794)
						)
						(arc
							(start 0.1778 0.2794)
							(mid 0.249642 0.249642)
							(end 0.2794 0.1778)
						)
						(arc
							(start 0.2794 -0.1778)
							(mid 0.249642 -0.249642)
							(end 0.1778 -0.2794)
						)
					)
					(width 0)
					(fill yes)
				)
			)
		)
		(pad "2" smd custom
			(at 0 0.4445 90)
			(size 0.1397 0.1397)
			(layers "F.Cu" "F.Mask" "F.Paste")
			(net "DRV_ACT_4")
			(options
				(clearance outline)
				(anchor circle)
			)
			(primitives
				(gr_poly
					(pts
						(arc
							(start -0.1778 -0.2794)
							(mid -0.249642 -0.249642)
							(end -0.2794 -0.1778)
						)
						(arc
							(start -0.2794 0.1778)
							(mid -0.249642 0.249642)
							(end -0.1778 0.2794)
						)
						(arc
							(start 0.1778 0.2794)
							(mid 0.249642 0.249642)
							(end 0.2794 0.1778)
						)
						(arc
							(start 0.2794 -0.1778)
							(mid 0.249642 -0.249642)
							(end 0.1778 -0.2794)
						)
					)
					(width 0)
					(fill yes)
				)
			)
		)
	)
	(footprint ""
		(layer "F.Cu")
		(at 50.164746 -25.2857)
		(property "Reference" "PR23"
			(at 0 0 0)
			(layer "F.SilkS")
			(hide yes)
			(effects
				(font
					(size 1.27 1.27)
				)
			)
		)
		(property "Value" "10KR2F-2-GP"
			(at 0.064008 -3.993896 0)
			(unlocked yes)
			(layer "F.Fab")
			(hide yes)
			(effects
				(font
					(size 1.016 1.016)
					(thickness 0.1524)
				)
			)
		)
		(property "Device Type" "R402H16"
			(at 0.064008 -5.517896 0)
			(unlocked yes)
			(layer "F.Fab")
			(hide yes)
			(effects
				(font
					(size 1.016 1.016)
					(thickness 0.1524)
				)
			)
		)
		(duplicate_pad_numbers_are_jumpers no)
		(fp_line
			(start -0.508 -0.9398)
			(end -0.508 0.9398)
			(stroke
				(width 0.1524)
				(type default)
			)
			(layer "F.SilkS")
		)
		(fp_line
			(start 0.508 -0.9398)
			(end -0.508 -0.9398)
			(stroke
				(width 0.1524)
				(type default)
			)
			(layer "F.SilkS")
		)
		(fp_rect
			(start -0.508 0.9398)
			(end 0.508 -0.9398)
			(stroke
				(width 0)
				(type default)
			)
			(fill no)
			(layer "F.CrtYd")
		)
		(fp_rect
			(start -0.508 0.9398)
			(end 0.508 -0.9398)
			(stroke
				(width 0)
				(type default)
			)
			(fill no)
			(layer "F.Fab")
		)
		(pad "1" smd custom
			(at 0 -0.4445)
			(size 0.1397 0.1397)
			(layers "F.Cu" "F.Mask" "F.Paste")
			(net "P5VB_VREG")
			(options
				(clearance outline)
				(anchor circle)
			)
			(primitives
				(gr_poly
					(pts
						(arc
							(start -0.1778 -0.2794)
							(mid -0.249642 -0.249642)
							(end -0.2794 -0.1778)
						)
						(arc
							(start -0.2794 0.1778)
							(mid -0.249642 0.249642)
							(end -0.1778 0.2794)
						)
						(arc
							(start 0.1778 0.2794)
							(mid 0.249642 0.249642)
							(end 0.2794 0.1778)
						)
						(arc
							(start 0.2794 -0.1778)
							(mid 0.249642 -0.249642)
							(end 0.1778 -0.2794)
						)
					)
					(width 0)
					(fill yes)
				)
			)
		)
		(pad "2" smd custom
			(at 0 0.4445)
			(size 0.1397 0.1397)
			(layers "F.Cu" "F.Mask" "F.Paste")
			(net "P5VB_PGD")
			(options
				(clearance outline)
				(anchor circle)
			)
			(primitives
				(gr_poly
					(pts
						(arc
							(start -0.1778 -0.2794)
							(mid -0.249642 -0.249642)
							(end -0.2794 -0.1778)
						)
						(arc
							(start -0.2794 0.1778)
							(mid -0.249642 0.249642)
							(end -0.1778 0.2794)
						)
						(arc
							(start 0.1778 0.2794)
							(mid 0.249642 0.249642)
							(end 0.2794 0.1778)
						)
						(arc
							(start 0.2794 -0.1778)
							(mid 0.249642 -0.249642)
							(end 0.1778 -0.2794)
						)
					)
					(width 0)
					(fill yes)
				)
			)
		)
	)
	(footprint ""
		(layer "F.Cu")
		(at 33.019746 -63.2587 -90)
		(property "Reference" "C248"
			(at 0 0 270)
			(layer "F.SilkS")
			(hide yes)
			(effects
				(font
					(size 1.27 1.27)
				)
			)
		)
		(property "Value" "SCD01U50V2KX-1GP"
			(at 1.1811 -2.7051 270)
			(unlocked yes)
			(layer "F.Fab")
			(hide yes)
			(effects
				(font
					(size 1.016 1.016)
					(thickness 0.1524)
				)
			)
		)
		(property "Device Type" "C402H22"
			(at 1.1811 -4.2291 270)
			(unlocked yes)
			(layer "F.Fab")
			(hide yes)
			(effects
				(font
					(size 1.016 1.016)
					(thickness 0.1524)
				)
			)
		)
		(duplicate_pad_numbers_are_jumpers no)
		(fp_rect
			(start -0.4318 0.9525)
			(end 0.4318 -0.9525)
			(stroke
				(width 0)
				(type default)
			)
			(fill no)
			(layer "F.CrtYd")
		)
		(fp_rect
			(start -0.4318 0.9525)
			(end 0.4318 -0.9525)
			(stroke
				(width 0)
				(type default)
			)
			(fill no)
			(layer "F.Fab")
		)
		(pad "1" smd custom
			(at 0 -0.4445 270)
			(size 0.1524 0.1524)
			(layers "F.Cu" "F.Mask" "F.Paste")
			(net "SAS2X28_DRIVE_RX_N_B9")
			(options
				(clearance outline)
				(anchor circle)
			)
			(primitives
				(gr_poly
					(pts
						(arc
							(start 0.3048 -0.2032)
							(mid 0.275042 -0.275042)
							(end 0.2032 -0.3048)
						)
						(arc
							(start -0.2032 -0.3048)
							(mid -0.275042 -0.275042)
							(end -0.3048 -0.2032)
						)
						(arc
							(start -0.3048 0.2032)
							(mid -0.275042 0.275042)
							(end -0.2032 0.3048)
						)
						(arc
							(start 0.2032 0.3048)
							(mid 0.275042 0.275042)
							(end 0.3048 0.2032)
						)
					)
					(width 0)
					(fill yes)
				)
			)
		)
		(pad "2" smd custom
			(at 0 0.4445 270)
			(size 0.1524 0.1524)
			(layers "F.Cu" "F.Mask" "F.Paste")
			(net "SAS2X28_B_HDD9_RX_-")
			(options
				(clearance outline)
				(anchor circle)
			)
			(primitives
				(gr_poly
					(pts
						(arc
							(start 0.3048 -0.2032)
							(mid 0.275042 -0.275042)
							(end 0.2032 -0.3048)
						)
						(arc
							(start -0.2032 -0.3048)
							(mid -0.275042 -0.275042)
							(end -0.3048 -0.2032)
						)
						(arc
							(start -0.3048 0.2032)
							(mid -0.275042 0.275042)
							(end -0.2032 0.3048)
						)
						(arc
							(start 0.2032 0.3048)
							(mid 0.275042 0.275042)
							(end 0.3048 0.2032)
						)
					)
					(width 0)
					(fill yes)
				)
			)
		)
	)
	(footprint ""
		(layer "F.Cu")
		(at 62.610746 -391.4267)
		(property "Reference" "C207"
			(at 0 0 0)
			(layer "F.SilkS")
			(hide yes)
			(effects
				(font
					(size 1.27 1.27)
				)
			)
		)
		(property "Value" "SC10U25V6KX-1GP"
			(at -0.0762 -5.1308 0)
			(unlocked yes)
			(layer "F.Fab")
			(hide yes)
			(effects
				(font
					(size 1.016 1.016)
					(thickness 0.1524)
				)
			)
		)
		(property "Device Type" "C1206H71"
			(at -0.127 -6.6548 0)
			(unlocked yes)
			(layer "F.Fab")
			(hide yes)
			(effects
				(font
					(size 1.016 1.016)
					(thickness 0.1524)
				)
			)
		)
		(duplicate_pad_numbers_are_jumpers no)
		(fp_line
			(start -1.016 -2.2352)
			(end 1.016 -2.2352)
			(stroke
				(width 0.1524)
				(type default)
			)
			(layer "F.SilkS")
		)
		(fp_line
			(start -1.016 -0.8382)
			(end -1.016 -2.2352)
			(stroke
				(width 0.1524)
				(type default)
			)
			(layer "F.SilkS")
		)
		(fp_line
			(start -1.016 2.2352)
			(end -1.016 0.8382)
			(stroke
				(width 0.1524)
				(type default)
			)
			(layer "F.SilkS")
		)
		(fp_line
			(start 1.016 -2.2352)
			(end 1.016 -0.8382)
			(stroke
				(width 0.1524)
				(type default)
			)
			(layer "F.SilkS")
		)
		(fp_line
			(start 1.016 0.8382)
			(end 1.016 2.2352)
			(stroke
				(width 0.1524)
				(type default)
			)
			(layer "F.SilkS")
		)
		(fp_line
			(start 1.016 2.2352)
			(end -1.016 2.2352)
			(stroke
				(width 0.1524)
				(type default)
			)
			(layer "F.SilkS")
		)
		(fp_rect
			(start -1.0922 2.3114)
			(end 1.0922 -2.3114)
			(stroke
				(width 0)
				(type default)
			)
			(fill no)
			(layer "F.CrtYd")
		)
		(fp_poly
			(pts
				(xy 1.0922 -2.3114) (xy 1.0922 2.3114) (xy -1.0922 2.3114) (xy -1.0922 -2.3114)
			)
			(stroke
				(width 0)
				(type default)
			)
			(fill no)
			(layer "F.Fab")
		)
		(pad "1" smd rect
			(at 0 -1.397)
			(size 1.651 1.27)
			(layers "F.Cu" "F.Mask" "F.Paste")
			(net "P12V_HDD6")
		)
		(pad "2" smd rect
			(at 0 1.397)
			(size 1.651 1.27)
			(layers "F.Cu" "F.Mask" "F.Paste")
			(net "GND")
		)
	)
	(footprint ""
		(layer "F.Cu")
		(at 200.151746 -82.4357)
		(property "Reference" "U13"
			(at 0 0 0)
			(layer "F.SilkS")
			(hide yes)
			(effects
				(font
					(size 1.27 1.27)
				)
			)
		)
		(property "Value" "74LVC1G08GW-1-GP"
			(at -2.3368 -8.6868 0)
			(unlocked yes)
			(layer "F.Fab")
			(hide yes)
			(effects
				(font
					(size 1.016 1.016)
					(thickness 0.1524)
				)
			)
		)
		(property "Device Type" "SC70-5H44"
			(at -2.3114 -10.414 0)
			(unlocked yes)
			(layer "F.Fab")
			(hide yes)
			(effects
				(font
					(size 1.016 1.016)
					(thickness 0.1524)
				)
			)
		)
		(duplicate_pad_numbers_are_jumpers no)
		(fp_line
			(start -1.27 -1.7018)
			(end 1.27 -1.7018)
			(stroke
				(width 0.1524)
				(type default)
			)
			(layer "F.SilkS")
		)
		(fp_line
			(start -1.27 1.7018)
			(end -1.27 -1.7018)
			(stroke
				(width 0.1524)
				(type default)
			)
			(layer "F.SilkS")
		)
		(fp_line
			(start 0.6604 -1.8034)
			(end 1.3843 -1.8034)
			(stroke
				(width 0.3302)
				(type default)
			)
			(layer "F.SilkS")
		)
		(fp_line
			(start 1.27 -1.7018)
			(end 1.27 1.7018)
			(stroke
				(width 0.1524)
				(type default)
			)
			(layer "F.SilkS")
		)
		(fp_line
			(start 1.27 1.7018)
			(end -1.27 1.7018)
			(stroke
				(width 0.1524)
				(type default)
			)
			(layer "F.SilkS")
		)
		(fp_line
			(start 1.3843 -1.8034)
			(end 1.3843 -1.1176)
			(stroke
				(width 0.3302)
				(type default)
			)
			(layer "F.SilkS")
		)
		(fp_rect
			(start -1.524 1.9558)
			(end 1.524 -1.9558)
			(stroke
				(width 0)
				(type default)
			)
			(fill no)
			(layer "F.CrtYd")
		)
		(fp_poly
			(pts
				(xy -1.524 -1.9558) (xy 1.524 -1.9558) (xy 1.524 1.9558) (xy -1.524 1.9558)
			)
			(stroke
				(width 0)
				(type default)
			)
			(fill no)
			(layer "F.Fab")
		)
		(pad "1" smd rect
			(at 0.65024 -0.8255)
			(size 0.4064 1.2192)
			(layers "F.Cu" "F.Mask" "F.Paste")
			(net "SAS2X28_B_HDD4_FLT")
		)
		(pad "2" smd rect
			(at 0 -0.8255)
			(size 0.4064 1.2192)
			(layers "F.Cu" "F.Mask" "F.Paste")
			(net "SAS2X28_A_HDD4_FLT")
		)
		(pad "3" smd rect
			(at -0.65024 -0.8255)
			(size 0.4064 1.2192)
			(layers "F.Cu" "F.Mask" "F.Paste")
			(net "GND")
		)
		(pad "4" smd rect
			(at -0.65024 0.8255)
			(size 0.4064 1.2192)
			(layers "F.Cu" "F.Mask" "F.Paste")
			(net "FLT_HDD4_DRIVE")
		)
		(pad "5" smd rect
			(at 0.65024 0.8255)
			(size 0.4064 1.2192)
			(layers "F.Cu" "F.Mask" "F.Paste")
			(net "P3V3")
		)
	)
	(footprint ""
		(layer "F.Cu")
		(at 218.646756 -469.928702 -90)
		(property "Reference" "C103"
			(at 0 0 270)
			(layer "F.SilkS")
			(hide yes)
			(effects
				(font
					(size 1.27 1.27)
				)
			)
		)
		(property "Value" "SCD01U50V2KX-1GP"
			(at 1.1811 -2.7051 270)
			(unlocked yes)
			(layer "F.Fab")
			(hide yes)
			(effects
				(font
					(size 1.016 1.016)
					(thickness 0.1524)
				)
			)
		)
		(property "Device Type" "C402H22"
			(at 1.1811 -4.2291 270)
			(unlocked yes)
			(layer "F.Fab")
			(hide yes)
			(effects
				(font
					(size 1.016 1.016)
					(thickness 0.1524)
				)
			)
		)
		(duplicate_pad_numbers_are_jumpers no)
		(fp_rect
			(start -0.4318 0.9525)
			(end 0.4318 -0.9525)
			(stroke
				(width 0)
				(type default)
			)
			(fill no)
			(layer "F.CrtYd")
		)
		(fp_rect
			(start -0.4318 0.9525)
			(end 0.4318 -0.9525)
			(stroke
				(width 0)
				(type default)
			)
			(fill no)
			(layer "F.Fab")
		)
		(pad "1" smd custom
			(at 0 -0.4445 270)
			(size 0.1524 0.1524)
			(layers "F.Cu" "F.Mask" "F.Paste")
			(net "SAS2X28_DRIVE_RX_P_A0")
			(options
				(clearance outline)
				(anchor circle)
			)
			(primitives
				(gr_poly
					(pts
						(arc
							(start 0.3048 -0.2032)
							(mid 0.275042 -0.275042)
							(end 0.2032 -0.3048)
						)
						(arc
							(start -0.2032 -0.3048)
							(mid -0.275042 -0.275042)
							(end -0.3048 -0.2032)
						)
						(arc
							(start -0.3048 0.2032)
							(mid -0.275042 0.275042)
							(end -0.2032 0.3048)
						)
						(arc
							(start 0.2032 0.3048)
							(mid 0.275042 0.275042)
							(end 0.3048 0.2032)
						)
					)
					(width 0)
					(fill yes)
				)
			)
		)
		(pad "2" smd custom
			(at 0 0.4445 270)
			(size 0.1524 0.1524)
			(layers "F.Cu" "F.Mask" "F.Paste")
			(net "SAS2X28_A_HDD0_RX_+")
			(options
				(clearance outline)
				(anchor circle)
			)
			(primitives
				(gr_poly
					(pts
						(arc
							(start 0.3048 -0.2032)
							(mid 0.275042 -0.275042)
							(end 0.2032 -0.3048)
						)
						(arc
							(start -0.2032 -0.3048)
							(mid -0.275042 -0.275042)
							(end -0.3048 -0.2032)
						)
						(arc
							(start -0.3048 0.2032)
							(mid -0.275042 0.275042)
							(end -0.2032 0.3048)
						)
						(arc
							(start 0.2032 0.3048)
							(mid 0.275042 0.275042)
							(end 0.3048 0.2032)
						)
					)
					(width 0)
					(fill yes)
				)
			)
		)
	)
	(footprint ""
		(layer "F.Cu")
		(at 48.9712 -419.8112 180)
		(property "Reference" "R418"
			(at 0 0 180)
			(layer "F.SilkS")
			(hide yes)
			(effects
				(font
					(size 1.27 1.27)
				)
			)
		)
		(property "Value" "0R2J-2-GP"
			(at 0.064008 -3.993896 180)
			(unlocked yes)
			(layer "F.Fab")
			(hide yes)
			(effects
				(font
					(size 1.016 1.016)
					(thickness 0.1524)
				)
			)
		)
		(property "Device Type" "R402H16"
			(at 0.064008 -5.517896 180)
			(unlocked yes)
			(layer "F.Fab")
			(hide yes)
			(effects
				(font
					(size 1.016 1.016)
					(thickness 0.1524)
				)
			)
		)
		(duplicate_pad_numbers_are_jumpers no)
		(fp_line
			(start 0.508 -0.9398)
			(end -0.508 -0.9398)
			(stroke
				(width 0.1524)
				(type default)
			)
			(layer "F.SilkS")
		)
		(fp_line
			(start -0.508 -0.9398)
			(end -0.508 0.9398)
			(stroke
				(width 0.1524)
				(type default)
			)
			(layer "F.SilkS")
		)
		(fp_rect
			(start -0.508 0.9398)
			(end 0.508 -0.9398)
			(stroke
				(width 0)
				(type default)
			)
			(fill no)
			(layer "F.CrtYd")
		)
		(fp_rect
			(start -0.508 0.9398)
			(end 0.508 -0.9398)
			(stroke
				(width 0)
				(type default)
			)
			(fill no)
			(layer "F.Fab")
		)
		(pad "1" smd custom
			(at 0 -0.4445 180)
			(size 0.1397 0.1397)
			(layers "F.Cu" "F.Mask" "F.Paste")
			(net "SW_HDD10_G")
			(options
				(clearance outline)
				(anchor circle)
			)
			(primitives
				(gr_poly
					(pts
						(arc
							(start -0.1778 -0.2794)
							(mid -0.249642 -0.249642)
							(end -0.2794 -0.1778)
						)
						(arc
							(start -0.2794 0.1778)
							(mid -0.249642 0.249642)
							(end -0.1778 0.2794)
						)
						(arc
							(start 0.1778 0.2794)
							(mid 0.249642 0.249642)
							(end 0.2794 0.1778)
						)
						(arc
							(start 0.2794 -0.1778)
							(mid 0.249642 -0.249642)
							(end 0.1778 -0.2794)
						)
					)
					(width 0)
					(fill yes)
				)
			)
		)
		(pad "2" smd custom
			(at 0 0.4445 180)
			(size 0.1397 0.1397)
			(layers "F.Cu" "F.Mask" "F.Paste")
			(net "SW_HDD10_R")
			(options
				(clearance outline)
				(anchor circle)
			)
			(primitives
				(gr_poly
					(pts
						(arc
							(start -0.1778 -0.2794)
							(mid -0.249642 -0.249642)
							(end -0.2794 -0.1778)
						)
						(arc
							(start -0.2794 0.1778)
							(mid -0.249642 0.249642)
							(end -0.1778 0.2794)
						)
						(arc
							(start 0.1778 0.2794)
							(mid 0.249642 0.249642)
							(end 0.2794 0.1778)
						)
						(arc
							(start 0.2794 -0.1778)
							(mid 0.249642 -0.249642)
							(end 0.1778 -0.2794)
						)
					)
					(width 0)
					(fill yes)
				)
			)
		)
	)
	(footprint ""
		(layer "F.Cu")
		(at 94.615 -11.811 -90)
		(property "Reference" "R562"
			(at 0 0 270)
			(layer "F.SilkS")
			(hide yes)
			(effects
				(font
					(size 1.27 1.27)
				)
			)
		)
		(property "Value" "200KR2F-L-GP"
			(at 0.064008 -3.993896 270)
			(unlocked yes)
			(layer "F.Fab")
			(hide yes)
			(effects
				(font
					(size 1.016 1.016)
					(thickness 0.1524)
				)
			)
		)
		(property "Device Type" "R402H16"
			(at 0.064008 -5.517896 270)
			(unlocked yes)
			(layer "F.Fab")
			(hide yes)
			(effects
				(font
					(size 1.016 1.016)
					(thickness 0.1524)
				)
			)
		)
		(duplicate_pad_numbers_are_jumpers no)
		(fp_line
			(start -0.508 -0.9398)
			(end -0.508 0.9398)
			(stroke
				(width 0.1524)
				(type default)
			)
			(layer "F.SilkS")
		)
		(fp_line
			(start 0.508 -0.9398)
			(end -0.508 -0.9398)
			(stroke
				(width 0.1524)
				(type default)
			)
			(layer "F.SilkS")
		)
		(fp_rect
			(start -0.508 0.9398)
			(end 0.508 -0.9398)
			(stroke
				(width 0)
				(type default)
			)
			(fill no)
			(layer "F.CrtYd")
		)
		(fp_rect
			(start -0.508 0.9398)
			(end 0.508 -0.9398)
			(stroke
				(width 0)
				(type default)
			)
			(fill no)
			(layer "F.Fab")
		)
		(pad "1" smd custom
			(at 0 -0.4445 270)
			(size 0.1397 0.1397)
			(layers "F.Cu" "F.Mask" "F.Paste")
			(net "SW_HDD14_R")
			(options
				(clearance outline)
				(anchor circle)
			)
			(primitives
				(gr_poly
					(pts
						(arc
							(start -0.1778 -0.2794)
							(mid -0.249642 -0.249642)
							(end -0.2794 -0.1778)
						)
						(arc
							(start -0.2794 0.1778)
							(mid -0.249642 0.249642)
							(end -0.1778 0.2794)
						)
						(arc
							(start 0.1778 0.2794)
							(mid 0.249642 0.249642)
							(end 0.2794 0.1778)
						)
						(arc
							(start 0.2794 -0.1778)
							(mid 0.249642 -0.249642)
							(end 0.1778 -0.2794)
						)
					)
					(width 0)
					(fill yes)
				)
			)
		)
		(pad "2" smd custom
			(at 0 0.4445 270)
			(size 0.1397 0.1397)
			(layers "F.Cu" "F.Mask" "F.Paste")
			(net "SW_HDD14_N")
			(options
				(clearance outline)
				(anchor circle)
			)
			(primitives
				(gr_poly
					(pts
						(arc
							(start -0.1778 -0.2794)
							(mid -0.249642 -0.249642)
							(end -0.2794 -0.1778)
						)
						(arc
							(start -0.2794 0.1778)
							(mid -0.249642 0.249642)
							(end -0.1778 0.2794)
						)
						(arc
							(start 0.1778 0.2794)
							(mid 0.249642 0.249642)
							(end 0.2794 0.1778)
						)
						(arc
							(start 0.2794 -0.1778)
							(mid 0.249642 -0.249642)
							(end 0.1778 -0.2794)
						)
					)
					(width 0)
					(fill yes)
				)
			)
		)
	)
	(footprint ""
		(layer "F.Cu")
		(at 192.278 -395.351 90)
		(property "Reference" "R120"
			(at 0 0 90)
			(layer "F.SilkS")
			(hide yes)
			(effects
				(font
					(size 1.27 1.27)
				)
			)
		)
		(property "Value" "4K7R2J-2-GP"
			(at 0.064008 -3.993896 90)
			(unlocked yes)
			(layer "F.Fab")
			(hide yes)
			(effects
				(font
					(size 1.016 1.016)
					(thickness 0.1524)
				)
			)
		)
		(property "Device Type" "R402H16"
			(at 0.064008 -5.517896 90)
			(unlocked yes)
			(layer "F.Fab")
			(hide yes)
			(effects
				(font
					(size 1.016 1.016)
					(thickness 0.1524)
				)
			)
		)
		(duplicate_pad_numbers_are_jumpers no)
		(fp_line
			(start 0.508 -0.9398)
			(end -0.508 -0.9398)
			(stroke
				(width 0.1524)
				(type default)
			)
			(layer "F.SilkS")
		)
		(fp_line
			(start -0.508 -0.9398)
			(end -0.508 0.9398)
			(stroke
				(width 0.1524)
				(type default)
			)
			(layer "F.SilkS")
		)
		(fp_rect
			(start -0.508 0.9398)
			(end 0.508 -0.9398)
			(stroke
				(width 0)
				(type default)
			)
			(fill no)
			(layer "F.CrtYd")
		)
		(fp_rect
			(start -0.508 0.9398)
			(end 0.508 -0.9398)
			(stroke
				(width 0)
				(type default)
			)
			(fill no)
			(layer "F.Fab")
		)
		(pad "1" smd custom
			(at 0 -0.4445 90)
			(size 0.1397 0.1397)
			(layers "F.Cu" "F.Mask" "F.Paste")
			(net "P12V")
			(options
				(clearance outline)
				(anchor circle)
			)
			(primitives
				(gr_poly
					(pts
						(arc
							(start -0.1778 -0.2794)
							(mid -0.249642 -0.249642)
							(end -0.2794 -0.1778)
						)
						(arc
							(start -0.2794 0.1778)
							(mid -0.249642 0.249642)
							(end -0.1778 0.2794)
						)
						(arc
							(start 0.1778 0.2794)
							(mid 0.249642 0.249642)
							(end 0.2794 0.1778)
						)
						(arc
							(start 0.2794 -0.1778)
							(mid 0.249642 -0.249642)
							(end 0.1778 -0.2794)
						)
					)
					(width 0)
					(fill yes)
				)
			)
		)
		(pad "2" smd custom
			(at 0 0.4445 90)
			(size 0.1397 0.1397)
			(layers "F.Cu" "F.Mask" "F.Paste")
			(net "SW_HDD1_R")
			(options
				(clearance outline)
				(anchor circle)
			)
			(primitives
				(gr_poly
					(pts
						(arc
							(start -0.1778 -0.2794)
							(mid -0.249642 -0.249642)
							(end -0.2794 -0.1778)
						)
						(arc
							(start -0.2794 0.1778)
							(mid -0.249642 0.249642)
							(end -0.1778 0.2794)
						)
						(arc
							(start 0.1778 0.2794)
							(mid 0.249642 0.249642)
							(end 0.2794 0.1778)
						)
						(arc
							(start 0.2794 -0.1778)
							(mid 0.249642 -0.249642)
							(end 0.1778 -0.2794)
						)
					)
					(width 0)
					(fill yes)
				)
			)
		)
	)
	(footprint ""
		(layer "F.Cu")
		(at 39.750746 -246.7737 90)
		(property "Reference" "R201"
			(at 0 0 90)
			(layer "F.SilkS")
			(hide yes)
			(effects
				(font
					(size 1.27 1.27)
				)
			)
		)
		(property "Value" "330R2F-GP"
			(at 0.064008 -3.993896 90)
			(unlocked yes)
			(layer "F.Fab")
			(hide yes)
			(effects
				(font
					(size 1.016 1.016)
					(thickness 0.1524)
				)
			)
		)
		(property "Device Type" "R402H16"
			(at 0.064008 -5.517896 90)
			(unlocked yes)
			(layer "F.Fab")
			(hide yes)
			(effects
				(font
					(size 1.016 1.016)
					(thickness 0.1524)
				)
			)
		)
		(duplicate_pad_numbers_are_jumpers no)
		(fp_line
			(start 0.508 -0.9398)
			(end -0.508 -0.9398)
			(stroke
				(width 0.1524)
				(type default)
			)
			(layer "F.SilkS")
		)
		(fp_line
			(start -0.508 -0.9398)
			(end -0.508 0.9398)
			(stroke
				(width 0.1524)
				(type default)
			)
			(layer "F.SilkS")
		)
		(fp_rect
			(start -0.508 0.9398)
			(end 0.508 -0.9398)
			(stroke
				(width 0)
				(type default)
			)
			(fill no)
			(layer "F.CrtYd")
		)
		(fp_rect
			(start -0.508 0.9398)
			(end 0.508 -0.9398)
			(stroke
				(width 0)
				(type default)
			)
			(fill no)
			(layer "F.Fab")
		)
		(pad "1" smd custom
			(at 0 -0.4445 90)
			(size 0.1397 0.1397)
			(layers "F.Cu" "F.Mask" "F.Paste")
			(net "P3V3_HDD7_LED")
			(options
				(clearance outline)
				(anchor circle)
			)
			(primitives
				(gr_poly
					(pts
						(arc
							(start -0.1778 -0.2794)
							(mid -0.249642 -0.249642)
							(end -0.2794 -0.1778)
						)
						(arc
							(start -0.2794 0.1778)
							(mid -0.249642 0.249642)
							(end -0.1778 0.2794)
						)
						(arc
							(start 0.1778 0.2794)
							(mid 0.249642 0.249642)
							(end 0.2794 0.1778)
						)
						(arc
							(start 0.2794 -0.1778)
							(mid 0.249642 -0.249642)
							(end 0.1778 -0.2794)
						)
					)
					(width 0)
					(fill yes)
				)
			)
		)
		(pad "2" smd custom
			(at 0 0.4445 90)
			(size 0.1397 0.1397)
			(layers "F.Cu" "F.Mask" "F.Paste")
			(net "FLT_HDD7")
			(options
				(clearance outline)
				(anchor circle)
			)
			(primitives
				(gr_poly
					(pts
						(arc
							(start -0.1778 -0.2794)
							(mid -0.249642 -0.249642)
							(end -0.2794 -0.1778)
						)
						(arc
							(start -0.2794 0.1778)
							(mid -0.249642 0.249642)
							(end -0.1778 0.2794)
						)
						(arc
							(start 0.1778 0.2794)
							(mid 0.249642 0.249642)
							(end 0.2794 0.1778)
						)
						(arc
							(start 0.2794 -0.1778)
							(mid 0.249642 -0.249642)
							(end 0.1778 -0.2794)
						)
					)
					(width 0)
					(fill yes)
				)
			)
		)
	)
	(footprint ""
		(layer "F.Cu")
		(at 35.305746 -131.854702 180)
		(property "Reference" "C323"
			(at 0 0 180)
			(layer "F.SilkS")
			(hide yes)
			(effects
				(font
					(size 1.27 1.27)
				)
			)
		)
		(property "Value" "SCD01U50V2KX-1GP"
			(at 1.1811 -2.7051 180)
			(unlocked yes)
			(layer "F.Fab")
			(hide yes)
			(effects
				(font
					(size 1.016 1.016)
					(thickness 0.1524)
				)
			)
		)
		(property "Device Type" "C402H22"
			(at 1.1811 -4.2291 180)
			(unlocked yes)
			(layer "F.Fab")
			(hide yes)
			(effects
				(font
					(size 1.016 1.016)
					(thickness 0.1524)
				)
			)
		)
		(duplicate_pad_numbers_are_jumpers no)
		(fp_rect
			(start -0.4318 0.9525)
			(end 0.4318 -0.9525)
			(stroke
				(width 0)
				(type default)
			)
			(fill no)
			(layer "F.CrtYd")
		)
		(fp_rect
			(start -0.4318 0.9525)
			(end 0.4318 -0.9525)
			(stroke
				(width 0)
				(type default)
			)
			(fill no)
			(layer "F.Fab")
		)
		(pad "1" smd custom
			(at 0 -0.4445 180)
			(size 0.1524 0.1524)
			(layers "F.Cu" "F.Mask" "F.Paste")
			(net "HDD_PRSNT_NET13")
			(options
				(clearance outline)
				(anchor circle)
			)
			(primitives
				(gr_poly
					(pts
						(arc
							(start 0.3048 -0.2032)
							(mid 0.275042 -0.275042)
							(end 0.2032 -0.3048)
						)
						(arc
							(start -0.2032 -0.3048)
							(mid -0.275042 -0.275042)
							(end -0.3048 -0.2032)
						)
						(arc
							(start -0.3048 0.2032)
							(mid -0.275042 0.275042)
							(end -0.2032 0.3048)
						)
						(arc
							(start 0.2032 0.3048)
							(mid 0.275042 0.275042)
							(end 0.3048 0.2032)
						)
					)
					(width 0)
					(fill yes)
				)
			)
		)
		(pad "2" smd custom
			(at 0 0.4445 180)
			(size 0.1524 0.1524)
			(layers "F.Cu" "F.Mask" "F.Paste")
			(net "GND")
			(options
				(clearance outline)
				(anchor circle)
			)
			(primitives
				(gr_poly
					(pts
						(arc
							(start 0.3048 -0.2032)
							(mid 0.275042 -0.275042)
							(end 0.2032 -0.3048)
						)
						(arc
							(start -0.2032 -0.3048)
							(mid -0.275042 -0.275042)
							(end -0.3048 -0.2032)
						)
						(arc
							(start -0.3048 0.2032)
							(mid -0.275042 0.275042)
							(end -0.2032 0.3048)
						)
						(arc
							(start 0.2032 0.3048)
							(mid 0.275042 0.275042)
							(end 0.3048 0.2032)
						)
					)
					(width 0)
					(fill yes)
				)
			)
		)
	)
	(footprint ""
		(layer "F.Cu")
		(at 47.751746 -217.706702)
		(property "Reference" "C304"
			(at 0 0 0)
			(layer "F.SilkS")
			(hide yes)
			(effects
				(font
					(size 1.27 1.27)
				)
			)
		)
		(property "Value" "SC10U25V6KX-1GP"
			(at -0.0762 -5.1308 0)
			(unlocked yes)
			(layer "F.Fab")
			(hide yes)
			(effects
				(font
					(size 1.016 1.016)
					(thickness 0.1524)
				)
			)
		)
		(property "Device Type" "C1206H71"
			(at -0.127 -6.6548 0)
			(unlocked yes)
			(layer "F.Fab")
			(hide yes)
			(effects
				(font
					(size 1.016 1.016)
					(thickness 0.1524)
				)
			)
		)
		(duplicate_pad_numbers_are_jumpers no)
		(fp_line
			(start -1.016 -2.2352)
			(end 1.016 -2.2352)
			(stroke
				(width 0.1524)
				(type default)
			)
			(layer "F.SilkS")
		)
		(fp_line
			(start -1.016 -0.8382)
			(end -1.016 -2.2352)
			(stroke
				(width 0.1524)
				(type default)
			)
			(layer "F.SilkS")
		)
		(fp_line
			(start -1.016 2.2352)
			(end -1.016 0.8382)
			(stroke
				(width 0.1524)
				(type default)
			)
			(layer "F.SilkS")
		)
		(fp_line
			(start 1.016 -2.2352)
			(end 1.016 -0.8382)
			(stroke
				(width 0.1524)
				(type default)
			)
			(layer "F.SilkS")
		)
		(fp_line
			(start 1.016 0.8382)
			(end 1.016 2.2352)
			(stroke
				(width 0.1524)
				(type default)
			)
			(layer "F.SilkS")
		)
		(fp_line
			(start 1.016 2.2352)
			(end -1.016 2.2352)
			(stroke
				(width 0.1524)
				(type default)
			)
			(layer "F.SilkS")
		)
		(fp_rect
			(start -1.0922 2.3114)
			(end 1.0922 -2.3114)
			(stroke
				(width 0)
				(type default)
			)
			(fill no)
			(layer "F.CrtYd")
		)
		(fp_poly
			(pts
				(xy 1.0922 -2.3114) (xy 1.0922 2.3114) (xy -1.0922 2.3114) (xy -1.0922 -2.3114)
			)
			(stroke
				(width 0)
				(type default)
			)
			(fill no)
			(layer "F.Fab")
		)
		(pad "1" smd rect
			(at 0 -1.397)
			(size 1.651 1.27)
			(layers "F.Cu" "F.Mask" "F.Paste")
			(net "P12V_HDD12")
		)
		(pad "2" smd rect
			(at 0 1.397)
			(size 1.651 1.27)
			(layers "F.Cu" "F.Mask" "F.Paste")
			(net "GND")
		)
	)
	(footprint ""
		(layer "F.Cu")
		(at 207.4164 -272.5166 -90)
		(property "Reference" "Q33"
			(at 0 0 270)
			(layer "F.SilkS")
			(hide yes)
			(effects
				(font
					(size 1.27 1.27)
				)
			)
		)
		(property "Value" "2N7002DW-7F-GP"
			(at -2.3622 -8.2042 270)
			(unlocked yes)
			(layer "F.Fab")
			(hide yes)
			(effects
				(font
					(size 1.016 1.016)
					(thickness 0.1524)
				)
			)
		)
		(property "Device Type" "SOT-363H44"
			(at -2.3622 -10.1092 270)
			(unlocked yes)
			(layer "F.Fab")
			(hide yes)
			(effects
				(font
					(size 1.016 1.016)
					(thickness 0.1524)
				)
			)
		)
		(duplicate_pad_numbers_are_jumpers no)
		(fp_line
			(start -1.4478 1.7018)
			(end 1.4478 1.7018)
			(stroke
				(width 0.1524)
				(type default)
			)
			(layer "F.SilkS")
		)
		(fp_line
			(start 1.4478 1.7018)
			(end 1.4478 -1.7018)
			(stroke
				(width 0.1524)
				(type default)
			)
			(layer "F.SilkS")
		)
		(fp_line
			(start -1.27 1.524)
			(end -1.27 0.6604)
			(stroke
				(width 0.4826)
				(type default)
			)
			(layer "F.SilkS")
		)
		(fp_line
			(start -1.4478 -1.7018)
			(end -1.4478 1.7018)
			(stroke
				(width 0.1524)
				(type default)
			)
			(layer "F.SilkS")
		)
		(fp_line
			(start 1.4478 -1.7018)
			(end -1.4478 -1.7018)
			(stroke
				(width 0.1524)
				(type default)
			)
			(layer "F.SilkS")
		)
		(fp_poly
			(pts
				(xy -1.524 -1.778) (xy 1.524 -1.778) (xy 1.524 1.778) (xy -1.524 1.778)
			)
			(stroke
				(width 0)
				(type default)
			)
			(fill no)
			(layer "F.CrtYd")
		)
		(fp_poly
			(pts
				(xy -1.524 -1.778) (xy 1.524 -1.778) (xy 1.524 1.778) (xy -1.524 1.778)
			)
			(stroke
				(width 0)
				(type default)
			)
			(fill no)
			(layer "F.Fab")
		)
		(pad "1" smd rect
			(at -0.65024 0.9398 270)
			(size 0.4064 1.016)
			(layers "F.Cu" "F.Mask" "F.Paste")
			(net "P3V3_HDD2_LED")
		)
		(pad "2" smd rect
			(at 0 0.9398 270)
			(size 0.4064 1.016)
			(layers "F.Cu" "F.Mask" "F.Paste")
			(net "HDD2_LED_G")
		)
		(pad "3" smd rect
			(at 0.65024 0.9398 270)
			(size 0.4064 1.016)
			(layers "F.Cu" "F.Mask" "F.Paste")
			(net "P5VA")
		)
		(pad "4" smd rect
			(at 0.65024 -0.9398 270)
			(size 0.4064 1.016)
			(layers "F.Cu" "F.Mask" "F.Paste")
			(net "P5VA_HDD2_LED")
		)
		(pad "5" smd rect
			(at 0 -0.9398 270)
			(size 0.4064 1.016)
			(layers "F.Cu" "F.Mask" "F.Paste")
			(net "HDD2_LED_G")
		)
		(pad "6" smd rect
			(at -0.65024 -0.9398 270)
			(size 0.4064 1.016)
			(layers "F.Cu" "F.Mask" "F.Paste")
			(net "P3V3")
		)
	)
	(footprint ""
		(layer "F.Cu")
		(at 36.237418 -332.29804 180)
		(property "Reference" "C283"
			(at 0 0 180)
			(layer "F.SilkS")
			(hide yes)
			(effects
				(font
					(size 1.27 1.27)
				)
			)
		)
		(property "Value" "SCD1U10V2KX-5GP"
			(at 1.1811 -2.7051 180)
			(unlocked yes)
			(layer "F.Fab")
			(hide yes)
			(effects
				(font
					(size 1.016 1.016)
					(thickness 0.1524)
				)
			)
		)
		(property "Device Type" "C402H22"
			(at 1.1811 -4.2291 180)
			(unlocked yes)
			(layer "F.Fab")
			(hide yes)
			(effects
				(font
					(size 1.016 1.016)
					(thickness 0.1524)
				)
			)
		)
		(duplicate_pad_numbers_are_jumpers no)
		(fp_rect
			(start -0.4318 0.9525)
			(end 0.4318 -0.9525)
			(stroke
				(width 0)
				(type default)
			)
			(fill no)
			(layer "F.CrtYd")
		)
		(fp_rect
			(start -0.4318 0.9525)
			(end 0.4318 -0.9525)
			(stroke
				(width 0)
				(type default)
			)
			(fill no)
			(layer "F.Fab")
		)
		(pad "1" smd custom
			(at 0 -0.4445 180)
			(size 0.1524 0.1524)
			(layers "F.Cu" "F.Mask" "F.Paste")
			(net "P3V3")
			(options
				(clearance outline)
				(anchor circle)
			)
			(primitives
				(gr_poly
					(pts
						(arc
							(start 0.3048 -0.2032)
							(mid 0.275042 -0.275042)
							(end 0.2032 -0.3048)
						)
						(arc
							(start -0.2032 -0.3048)
							(mid -0.275042 -0.275042)
							(end -0.3048 -0.2032)
						)
						(arc
							(start -0.3048 0.2032)
							(mid -0.275042 0.275042)
							(end -0.2032 0.3048)
						)
						(arc
							(start 0.2032 0.3048)
							(mid 0.275042 0.275042)
							(end 0.3048 0.2032)
						)
					)
					(width 0)
					(fill yes)
				)
			)
		)
		(pad "2" smd custom
			(at 0 0.4445 180)
			(size 0.1524 0.1524)
			(layers "F.Cu" "F.Mask" "F.Paste")
			(net "GND")
			(options
				(clearance outline)
				(anchor circle)
			)
			(primitives
				(gr_poly
					(pts
						(arc
							(start 0.3048 -0.2032)
							(mid 0.275042 -0.275042)
							(end 0.2032 -0.3048)
						)
						(arc
							(start -0.2032 -0.3048)
							(mid -0.275042 -0.275042)
							(end -0.3048 -0.2032)
						)
						(arc
							(start -0.3048 0.2032)
							(mid -0.275042 0.275042)
							(end -0.2032 0.3048)
						)
						(arc
							(start 0.2032 0.3048)
							(mid 0.275042 0.275042)
							(end 0.3048 0.2032)
						)
					)
					(width 0)
					(fill yes)
				)
			)
		)
	)
	(footprint ""
		(layer "F.Cu")
		(at 194.774058 -389.584184 -90)
		(property "Reference" "U6"
			(at 0 0 270)
			(layer "F.SilkS")
			(hide yes)
			(effects
				(font
					(size 1.27 1.27)
				)
			)
		)
		(property "Value" "74LVC1G08GW-1-GP"
			(at -2.3368 -8.6868 270)
			(unlocked yes)
			(layer "F.Fab")
			(hide yes)
			(effects
				(font
					(size 1.016 1.016)
					(thickness 0.1524)
				)
			)
		)
		(property "Device Type" "SC70-5H44"
			(at -2.3114 -10.414 270)
			(unlocked yes)
			(layer "F.Fab")
			(hide yes)
			(effects
				(font
					(size 1.016 1.016)
					(thickness 0.1524)
				)
			)
		)
		(duplicate_pad_numbers_are_jumpers no)
		(fp_line
			(start -1.27 1.7018)
			(end -1.27 -1.7018)
			(stroke
				(width 0.1524)
				(type default)
			)
			(layer "F.SilkS")
		)
		(fp_line
			(start 1.27 1.7018)
			(end -1.27 1.7018)
			(stroke
				(width 0.1524)
				(type default)
			)
			(layer "F.SilkS")
		)
		(fp_line
			(start -1.27 -1.7018)
			(end 1.27 -1.7018)
			(stroke
				(width 0.1524)
				(type default)
			)
			(layer "F.SilkS")
		)
		(fp_line
			(start 1.27 -1.7018)
			(end 1.27 1.7018)
			(stroke
				(width 0.1524)
				(type default)
			)
			(layer "F.SilkS")
		)
		(fp_line
			(start 0.6604 -1.8034)
			(end 1.3843 -1.8034)
			(stroke
				(width 0.3302)
				(type default)
			)
			(layer "F.SilkS")
		)
		(fp_line
			(start 1.3843 -1.8034)
			(end 1.3843 -1.1176)
			(stroke
				(width 0.3302)
				(type default)
			)
			(layer "F.SilkS")
		)
		(fp_rect
			(start -1.524 1.9558)
			(end 1.524 -1.9558)
			(stroke
				(width 0)
				(type default)
			)
			(fill no)
			(layer "F.CrtYd")
		)
		(fp_poly
			(pts
				(xy -1.524 -1.9558) (xy 1.524 -1.9558) (xy 1.524 1.9558) (xy -1.524 1.9558)
			)
			(stroke
				(width 0)
				(type default)
			)
			(fill no)
			(layer "F.Fab")
		)
		(pad "1" smd rect
			(at 0.65024 -0.8255 270)
			(size 0.4064 1.2192)
			(layers "F.Cu" "F.Mask" "F.Paste")
			(net "SAS_EXP_B_PWR1")
		)
		(pad "2" smd rect
			(at 0 -0.8255 270)
			(size 0.4064 1.2192)
			(layers "F.Cu" "F.Mask" "F.Paste")
			(net "SAS_EXP_A_PWR1")
		)
		(pad "3" smd rect
			(at -0.65024 -0.8255 270)
			(size 0.4064 1.2192)
			(layers "F.Cu" "F.Mask" "F.Paste")
			(net "GND")
		)
		(pad "4" smd rect
			(at -0.65024 0.8255 270)
			(size 0.4064 1.2192)
			(layers "F.Cu" "F.Mask" "F.Paste")
			(net "DRIVE_PWR1")
		)
		(pad "5" smd rect
			(at 0.65024 0.8255 270)
			(size 0.4064 1.2192)
			(layers "F.Cu" "F.Mask" "F.Paste")
			(net "P3V3")
		)
	)
	(footprint ""
		(layer "F.Cu")
		(at 45.338746 -39.7637 90)
		(property "Reference" "R230"
			(at 0 0 90)
			(layer "F.SilkS")
			(hide yes)
			(effects
				(font
					(size 1.27 1.27)
				)
			)
		)
		(property "Value" "0R2J-2-GP"
			(at 0.064008 -3.993896 90)
			(unlocked yes)
			(layer "F.Fab")
			(hide yes)
			(effects
				(font
					(size 1.016 1.016)
					(thickness 0.1524)
				)
			)
		)
		(property "Device Type" "R402H16"
			(at 0.064008 -5.517896 90)
			(unlocked yes)
			(layer "F.Fab")
			(hide yes)
			(effects
				(font
					(size 1.016 1.016)
					(thickness 0.1524)
				)
			)
		)
		(duplicate_pad_numbers_are_jumpers no)
		(fp_line
			(start 0.508 -0.9398)
			(end -0.508 -0.9398)
			(stroke
				(width 0.1524)
				(type default)
			)
			(layer "F.SilkS")
		)
		(fp_line
			(start -0.508 -0.9398)
			(end -0.508 0.9398)
			(stroke
				(width 0.1524)
				(type default)
			)
			(layer "F.SilkS")
		)
		(fp_rect
			(start -0.508 0.9398)
			(end 0.508 -0.9398)
			(stroke
				(width 0)
				(type default)
			)
			(fill no)
			(layer "F.CrtYd")
		)
		(fp_rect
			(start -0.508 0.9398)
			(end 0.508 -0.9398)
			(stroke
				(width 0)
				(type default)
			)
			(fill no)
			(layer "F.Fab")
		)
		(pad "1" smd custom
			(at 0 -0.4445 90)
			(size 0.1397 0.1397)
			(layers "F.Cu" "F.Mask" "F.Paste")
			(net "FLT_NET_HDD9")
			(options
				(clearance outline)
				(anchor circle)
			)
			(primitives
				(gr_poly
					(pts
						(arc
							(start -0.1778 -0.2794)
							(mid -0.249642 -0.249642)
							(end -0.2794 -0.1778)
						)
						(arc
							(start -0.2794 0.1778)
							(mid -0.249642 0.249642)
							(end -0.1778 0.2794)
						)
						(arc
							(start 0.1778 0.2794)
							(mid 0.249642 0.249642)
							(end 0.2794 0.1778)
						)
						(arc
							(start 0.2794 -0.1778)
							(mid 0.249642 -0.249642)
							(end 0.1778 -0.2794)
						)
					)
					(width 0)
					(fill yes)
				)
			)
		)
		(pad "2" smd custom
			(at 0 0.4445 90)
			(size 0.1397 0.1397)
			(layers "F.Cu" "F.Mask" "F.Paste")
			(net "FLT_HDD9_DRIVE")
			(options
				(clearance outline)
				(anchor circle)
			)
			(primitives
				(gr_poly
					(pts
						(arc
							(start -0.1778 -0.2794)
							(mid -0.249642 -0.249642)
							(end -0.2794 -0.1778)
						)
						(arc
							(start -0.2794 0.1778)
							(mid -0.249642 0.249642)
							(end -0.1778 0.2794)
						)
						(arc
							(start 0.1778 0.2794)
							(mid 0.249642 0.249642)
							(end 0.2794 0.1778)
						)
						(arc
							(start 0.2794 -0.1778)
							(mid 0.249642 -0.249642)
							(end 0.1778 -0.2794)
						)
					)
					(width 0)
					(fill yes)
				)
			)
		)
	)
	(footprint ""
		(layer "F.Cu")
		(at 58.165746 -178.5747 90)
		(property "Reference" "R218"
			(at 0 0 90)
			(layer "F.SilkS")
			(hide yes)
			(effects
				(font
					(size 1.27 1.27)
				)
			)
		)
		(property "Value" "2R2010J-1-GP"
			(at 0.254 -8.0772 90)
			(unlocked yes)
			(layer "F.Fab")
			(hide yes)
			(effects
				(font
					(size 1.016 1.016)
					(thickness 0.1524)
				)
			)
		)
		(property "Device Type" "R2010H28"
			(at 0.254 -9.6774 90)
			(unlocked yes)
			(layer "F.Fab")
			(hide yes)
			(effects
				(font
					(size 1.016 1.016)
					(thickness 0.1524)
				)
			)
		)
		(duplicate_pad_numbers_are_jumpers no)
		(fp_line
			(start 1.651 -3.302)
			(end -1.651 -3.302)
			(stroke
				(width 0.1524)
				(type default)
			)
			(layer "F.SilkS")
		)
		(fp_line
			(start -1.651 -3.302)
			(end -1.651 3.302)
			(stroke
				(width 0.1524)
				(type default)
			)
			(layer "F.SilkS")
		)
		(fp_line
			(start 1.651 3.302)
			(end 1.651 -3.302)
			(stroke
				(width 0.1524)
				(type default)
			)
			(layer "F.SilkS")
		)
		(fp_line
			(start -1.651 3.302)
			(end 1.651 3.302)
			(stroke
				(width 0.1524)
				(type default)
			)
			(layer "F.SilkS")
		)
		(fp_rect
			(start -1.7272 -3.3782)
			(end 1.7272 3.3782)
			(stroke
				(width 0)
				(type default)
			)
			(fill no)
			(layer "F.CrtYd")
		)
		(fp_poly
			(pts
				(xy 1.7272 3.3782) (xy 1.7272 -3.3782) (xy -1.7272 -3.3782) (xy -1.7272 3.3782)
			)
			(stroke
				(width 0)
				(type default)
			)
			(fill no)
			(layer "F.Fab")
		)
		(pad "1" smd rect
			(at 0 -2.3495 90)
			(size 2.794 1.143)
			(layers "F.Cu" "F.Mask" "F.Paste")
			(net "5V_PRE_8")
		)
		(pad "2" smd rect
			(at 0 2.3495 90)
			(size 2.794 1.143)
			(layers "F.Cu" "F.Mask" "F.Paste")
			(net "P5V_HDD8")
		)
	)
	(footprint ""
		(layer "F.Cu")
		(at 45.482256 -453.799702 90)
		(property "Reference" "R170"
			(at 0 0 90)
			(layer "F.SilkS")
			(hide yes)
			(effects
				(font
					(size 1.27 1.27)
				)
			)
		)
		(property "Value" "10KR2F-2-GP"
			(at 0.064008 -3.993896 90)
			(unlocked yes)
			(layer "F.Fab")
			(hide yes)
			(effects
				(font
					(size 1.016 1.016)
					(thickness 0.1524)
				)
			)
		)
		(property "Device Type" "R402H16"
			(at 0.064008 -5.517896 90)
			(unlocked yes)
			(layer "F.Fab")
			(hide yes)
			(effects
				(font
					(size 1.016 1.016)
					(thickness 0.1524)
				)
			)
		)
		(duplicate_pad_numbers_are_jumpers no)
		(fp_line
			(start 0.508 -0.9398)
			(end -0.508 -0.9398)
			(stroke
				(width 0.1524)
				(type default)
			)
			(layer "F.SilkS")
		)
		(fp_line
			(start -0.508 -0.9398)
			(end -0.508 0.9398)
			(stroke
				(width 0.1524)
				(type default)
			)
			(layer "F.SilkS")
		)
		(fp_rect
			(start -0.508 0.9398)
			(end 0.508 -0.9398)
			(stroke
				(width 0)
				(type default)
			)
			(fill no)
			(layer "F.CrtYd")
		)
		(fp_rect
			(start -0.508 0.9398)
			(end 0.508 -0.9398)
			(stroke
				(width 0)
				(type default)
			)
			(fill no)
			(layer "F.Fab")
		)
		(pad "1" smd custom
			(at 0 -0.4445 90)
			(size 0.1397 0.1397)
			(layers "F.Cu" "F.Mask" "F.Paste")
			(net "P5VB")
			(options
				(clearance outline)
				(anchor circle)
			)
			(primitives
				(gr_poly
					(pts
						(arc
							(start -0.1778 -0.2794)
							(mid -0.249642 -0.249642)
							(end -0.2794 -0.1778)
						)
						(arc
							(start -0.2794 0.1778)
							(mid -0.249642 0.249642)
							(end -0.1778 0.2794)
						)
						(arc
							(start 0.1778 0.2794)
							(mid 0.249642 0.249642)
							(end 0.2794 0.1778)
						)
						(arc
							(start 0.2794 -0.1778)
							(mid 0.249642 -0.249642)
							(end 0.1778 -0.2794)
						)
					)
					(width 0)
					(fill yes)
				)
			)
		)
		(pad "2" smd custom
			(at 0 0.4445 90)
			(size 0.1397 0.1397)
			(layers "F.Cu" "F.Mask" "F.Paste")
			(net "DRIVE_ACT_5")
			(options
				(clearance outline)
				(anchor circle)
			)
			(primitives
				(gr_poly
					(pts
						(arc
							(start -0.1778 -0.2794)
							(mid -0.249642 -0.249642)
							(end -0.2794 -0.1778)
						)
						(arc
							(start -0.2794 0.1778)
							(mid -0.249642 0.249642)
							(end -0.1778 0.2794)
						)
						(arc
							(start 0.1778 0.2794)
							(mid 0.249642 0.249642)
							(end 0.2794 0.1778)
						)
						(arc
							(start 0.2794 -0.1778)
							(mid 0.249642 -0.249642)
							(end 0.1778 -0.2794)
						)
					)
					(width 0)
					(fill yes)
				)
			)
		)
	)
	(footprint ""
		(layer "F.Cu")
		(at 27.228546 -245.8339 -90)
		(property "Reference" "R368"
			(at 0 0 270)
			(layer "F.SilkS")
			(hide yes)
			(effects
				(font
					(size 1.27 1.27)
				)
			)
		)
		(property "Value" "4K7R2J-2-GP"
			(at 0.064008 -3.993896 270)
			(unlocked yes)
			(layer "F.Fab")
			(hide yes)
			(effects
				(font
					(size 1.016 1.016)
					(thickness 0.1524)
				)
			)
		)
		(property "Device Type" "R402H16"
			(at 0.064008 -5.517896 270)
			(unlocked yes)
			(layer "F.Fab")
			(hide yes)
			(effects
				(font
					(size 1.016 1.016)
					(thickness 0.1524)
				)
			)
		)
		(duplicate_pad_numbers_are_jumpers no)
		(fp_line
			(start -0.508 -0.9398)
			(end -0.508 0.9398)
			(stroke
				(width 0.1524)
				(type default)
			)
			(layer "F.SilkS")
		)
		(fp_line
			(start 0.508 -0.9398)
			(end -0.508 -0.9398)
			(stroke
				(width 0.1524)
				(type default)
			)
			(layer "F.SilkS")
		)
		(fp_rect
			(start -0.508 0.9398)
			(end 0.508 -0.9398)
			(stroke
				(width 0)
				(type default)
			)
			(fill no)
			(layer "F.CrtYd")
		)
		(fp_rect
			(start -0.508 0.9398)
			(end 0.508 -0.9398)
			(stroke
				(width 0)
				(type default)
			)
			(fill no)
			(layer "F.Fab")
		)
		(pad "1" smd custom
			(at 0 -0.4445 270)
			(size 0.1397 0.1397)
			(layers "F.Cu" "F.Mask" "F.Paste")
			(net "P3V3")
			(options
				(clearance outline)
				(anchor circle)
			)
			(primitives
				(gr_poly
					(pts
						(arc
							(start -0.1778 -0.2794)
							(mid -0.249642 -0.249642)
							(end -0.2794 -0.1778)
						)
						(arc
							(start -0.2794 0.1778)
							(mid -0.249642 0.249642)
							(end -0.1778 0.2794)
						)
						(arc
							(start 0.1778 0.2794)
							(mid 0.249642 0.249642)
							(end 0.2794 0.1778)
						)
						(arc
							(start 0.2794 -0.1778)
							(mid 0.249642 -0.249642)
							(end 0.1778 -0.2794)
						)
					)
					(width 0)
					(fill yes)
				)
			)
		)
		(pad "2" smd custom
			(at 0 0.4445 270)
			(size 0.1397 0.1397)
			(layers "F.Cu" "F.Mask" "F.Paste")
			(net "I2C_B_SDA")
			(options
				(clearance outline)
				(anchor circle)
			)
			(primitives
				(gr_poly
					(pts
						(arc
							(start -0.1778 -0.2794)
							(mid -0.249642 -0.249642)
							(end -0.2794 -0.1778)
						)
						(arc
							(start -0.2794 0.1778)
							(mid -0.249642 0.249642)
							(end -0.1778 0.2794)
						)
						(arc
							(start 0.1778 0.2794)
							(mid 0.249642 0.249642)
							(end 0.2794 0.1778)
						)
						(arc
							(start 0.2794 -0.1778)
							(mid 0.249642 -0.249642)
							(end 0.1778 -0.2794)
						)
					)
					(width 0)
					(fill yes)
				)
			)
		)
	)
	(footprint ""
		(layer "F.Cu")
		(at 77.851 -402.463 180)
		(property "Reference" "C385"
			(at 0 0 180)
			(layer "F.SilkS")
			(hide yes)
			(effects
				(font
					(size 1.27 1.27)
				)
			)
		)
		(property "Value" "SCD033U25V2KX-GP"
			(at 1.1811 -2.7051 180)
			(unlocked yes)
			(layer "F.Fab")
			(hide yes)
			(effects
				(font
					(size 1.016 1.016)
					(thickness 0.1524)
				)
			)
		)
		(property "Device Type" "C402H22"
			(at 1.1811 -4.2291 180)
			(unlocked yes)
			(layer "F.Fab")
			(hide yes)
			(effects
				(font
					(size 1.016 1.016)
					(thickness 0.1524)
				)
			)
		)
		(duplicate_pad_numbers_are_jumpers no)
		(fp_rect
			(start -0.4318 0.9525)
			(end 0.4318 -0.9525)
			(stroke
				(width 0)
				(type default)
			)
			(fill no)
			(layer "F.CrtYd")
		)
		(fp_rect
			(start -0.4318 0.9525)
			(end 0.4318 -0.9525)
			(stroke
				(width 0)
				(type default)
			)
			(fill no)
			(layer "F.Fab")
		)
		(pad "1" smd custom
			(at 0 -0.4445 180)
			(size 0.1524 0.1524)
			(layers "F.Cu" "F.Mask" "F.Paste")
			(net "P12V")
			(options
				(clearance outline)
				(anchor circle)
			)
			(primitives
				(gr_poly
					(pts
						(arc
							(start 0.3048 -0.2032)
							(mid 0.275042 -0.275042)
							(end 0.2032 -0.3048)
						)
						(arc
							(start -0.2032 -0.3048)
							(mid -0.275042 -0.275042)
							(end -0.3048 -0.2032)
						)
						(arc
							(start -0.3048 0.2032)
							(mid -0.275042 0.275042)
							(end -0.2032 0.3048)
						)
						(arc
							(start 0.2032 0.3048)
							(mid 0.275042 0.275042)
							(end 0.3048 0.2032)
						)
					)
					(width 0)
					(fill yes)
				)
			)
		)
		(pad "2" smd custom
			(at 0 0.4445 180)
			(size 0.1524 0.1524)
			(layers "F.Cu" "F.Mask" "F.Paste")
			(net "SW_HDD6_N")
			(options
				(clearance outline)
				(anchor circle)
			)
			(primitives
				(gr_poly
					(pts
						(arc
							(start 0.3048 -0.2032)
							(mid 0.275042 -0.275042)
							(end 0.2032 -0.3048)
						)
						(arc
							(start -0.2032 -0.3048)
							(mid -0.275042 -0.275042)
							(end -0.3048 -0.2032)
						)
						(arc
							(start -0.3048 0.2032)
							(mid -0.275042 0.275042)
							(end -0.2032 0.3048)
						)
						(arc
							(start 0.2032 0.3048)
							(mid 0.275042 0.275042)
							(end 0.3048 0.2032)
						)
					)
					(width 0)
					(fill yes)
				)
			)
		)
	)
	(footprint ""
		(layer "F.Cu")
		(at 224.6884 -453.7202 90)
		(property "Reference" "R102"
			(at 0 0 90)
			(layer "F.SilkS")
			(hide yes)
			(effects
				(font
					(size 1.27 1.27)
				)
			)
		)
		(property "Value" "402R2F-GP"
			(at 0.064008 -3.993896 90)
			(unlocked yes)
			(layer "F.Fab")
			(hide yes)
			(effects
				(font
					(size 1.016 1.016)
					(thickness 0.1524)
				)
			)
		)
		(property "Device Type" "R402H16"
			(at 0.064008 -5.517896 90)
			(unlocked yes)
			(layer "F.Fab")
			(hide yes)
			(effects
				(font
					(size 1.016 1.016)
					(thickness 0.1524)
				)
			)
		)
		(duplicate_pad_numbers_are_jumpers no)
		(fp_line
			(start 0.508 -0.9398)
			(end -0.508 -0.9398)
			(stroke
				(width 0.1524)
				(type default)
			)
			(layer "F.SilkS")
		)
		(fp_line
			(start -0.508 -0.9398)
			(end -0.508 0.9398)
			(stroke
				(width 0.1524)
				(type default)
			)
			(layer "F.SilkS")
		)
		(fp_rect
			(start -0.508 0.9398)
			(end 0.508 -0.9398)
			(stroke
				(width 0)
				(type default)
			)
			(fill no)
			(layer "F.CrtYd")
		)
		(fp_rect
			(start -0.508 0.9398)
			(end 0.508 -0.9398)
			(stroke
				(width 0)
				(type default)
			)
			(fill no)
			(layer "F.Fab")
		)
		(pad "1" smd custom
			(at 0 -0.4445 90)
			(size 0.1397 0.1397)
			(layers "F.Cu" "F.Mask" "F.Paste")
			(net "P5VA_HDD0_LED")
			(options
				(clearance outline)
				(anchor circle)
			)
			(primitives
				(gr_poly
					(pts
						(arc
							(start -0.1778 -0.2794)
							(mid -0.249642 -0.249642)
							(end -0.2794 -0.1778)
						)
						(arc
							(start -0.2794 0.1778)
							(mid -0.249642 0.249642)
							(end -0.1778 0.2794)
						)
						(arc
							(start 0.1778 0.2794)
							(mid 0.249642 0.249642)
							(end 0.2794 0.1778)
						)
						(arc
							(start 0.2794 -0.1778)
							(mid 0.249642 -0.249642)
							(end 0.1778 -0.2794)
						)
					)
					(width 0)
					(fill yes)
				)
			)
		)
		(pad "2" smd custom
			(at 0 0.4445 90)
			(size 0.1397 0.1397)
			(layers "F.Cu" "F.Mask" "F.Paste")
			(net "DRV_ACT_0")
			(options
				(clearance outline)
				(anchor circle)
			)
			(primitives
				(gr_poly
					(pts
						(arc
							(start -0.1778 -0.2794)
							(mid -0.249642 -0.249642)
							(end -0.2794 -0.1778)
						)
						(arc
							(start -0.2794 0.1778)
							(mid -0.249642 0.249642)
							(end -0.1778 0.2794)
						)
						(arc
							(start 0.1778 0.2794)
							(mid 0.249642 0.249642)
							(end 0.2794 0.1778)
						)
						(arc
							(start 0.2794 -0.1778)
							(mid 0.249642 -0.249642)
							(end 0.1778 -0.2794)
						)
					)
					(width 0)
					(fill yes)
				)
			)
		)
	)
	(footprint ""
		(layer "F.Cu")
		(at 217.762582 -270.355568 -90)
		(property "Reference" "C137"
			(at 0 0 270)
			(layer "F.SilkS")
			(hide yes)
			(effects
				(font
					(size 1.27 1.27)
				)
			)
		)
		(property "Value" "SCD01U50V2KX-1GP"
			(at 1.1811 -2.7051 270)
			(unlocked yes)
			(layer "F.Fab")
			(hide yes)
			(effects
				(font
					(size 1.016 1.016)
					(thickness 0.1524)
				)
			)
		)
		(property "Device Type" "C402H22"
			(at 1.1811 -4.2291 270)
			(unlocked yes)
			(layer "F.Fab")
			(hide yes)
			(effects
				(font
					(size 1.016 1.016)
					(thickness 0.1524)
				)
			)
		)
		(duplicate_pad_numbers_are_jumpers no)
		(fp_rect
			(start -0.4318 0.9525)
			(end 0.4318 -0.9525)
			(stroke
				(width 0)
				(type default)
			)
			(fill no)
			(layer "F.CrtYd")
		)
		(fp_rect
			(start -0.4318 0.9525)
			(end 0.4318 -0.9525)
			(stroke
				(width 0)
				(type default)
			)
			(fill no)
			(layer "F.Fab")
		)
		(pad "1" smd custom
			(at 0 -0.4445 270)
			(size 0.1524 0.1524)
			(layers "F.Cu" "F.Mask" "F.Paste")
			(net "SAS2X28_DRIVE_RX_P_B2")
			(options
				(clearance outline)
				(anchor circle)
			)
			(primitives
				(gr_poly
					(pts
						(arc
							(start 0.3048 -0.2032)
							(mid 0.275042 -0.275042)
							(end 0.2032 -0.3048)
						)
						(arc
							(start -0.2032 -0.3048)
							(mid -0.275042 -0.275042)
							(end -0.3048 -0.2032)
						)
						(arc
							(start -0.3048 0.2032)
							(mid -0.275042 0.275042)
							(end -0.2032 0.3048)
						)
						(arc
							(start 0.2032 0.3048)
							(mid 0.275042 0.275042)
							(end 0.3048 0.2032)
						)
					)
					(width 0)
					(fill yes)
				)
			)
		)
		(pad "2" smd custom
			(at 0 0.4445 270)
			(size 0.1524 0.1524)
			(layers "F.Cu" "F.Mask" "F.Paste")
			(net "SAS2X28_B_HDD2_RX_+")
			(options
				(clearance outline)
				(anchor circle)
			)
			(primitives
				(gr_poly
					(pts
						(arc
							(start 0.3048 -0.2032)
							(mid 0.275042 -0.275042)
							(end 0.2032 -0.3048)
						)
						(arc
							(start -0.2032 -0.3048)
							(mid -0.275042 -0.275042)
							(end -0.3048 -0.2032)
						)
						(arc
							(start -0.3048 0.2032)
							(mid -0.275042 0.275042)
							(end -0.2032 0.3048)
						)
						(arc
							(start 0.2032 0.3048)
							(mid 0.275042 0.275042)
							(end 0.3048 0.2032)
						)
					)
					(width 0)
					(fill yes)
				)
			)
		)
	)
	(footprint ""
		(layer "F.Cu")
		(at 229.615746 -26.1747 -90)
		(property "Reference" "PR9"
			(at 0 0 270)
			(layer "F.SilkS")
			(hide yes)
			(effects
				(font
					(size 1.27 1.27)
				)
			)
		)
		(property "Value" "76K8R2F-GP"
			(at 0.064008 -3.993896 270)
			(unlocked yes)
			(layer "F.Fab")
			(hide yes)
			(effects
				(font
					(size 1.016 1.016)
					(thickness 0.1524)
				)
			)
		)
		(property "Device Type" "R402H16"
			(at 0.064008 -5.517896 270)
			(unlocked yes)
			(layer "F.Fab")
			(hide yes)
			(effects
				(font
					(size 1.016 1.016)
					(thickness 0.1524)
				)
			)
		)
		(duplicate_pad_numbers_are_jumpers no)
		(fp_line
			(start -0.508 -0.9398)
			(end -0.508 0.9398)
			(stroke
				(width 0.1524)
				(type default)
			)
			(layer "F.SilkS")
		)
		(fp_line
			(start 0.508 -0.9398)
			(end -0.508 -0.9398)
			(stroke
				(width 0.1524)
				(type default)
			)
			(layer "F.SilkS")
		)
		(fp_rect
			(start -0.508 0.9398)
			(end 0.508 -0.9398)
			(stroke
				(width 0)
				(type default)
			)
			(fill no)
			(layer "F.CrtYd")
		)
		(fp_rect
			(start -0.508 0.9398)
			(end 0.508 -0.9398)
			(stroke
				(width 0)
				(type default)
			)
			(fill no)
			(layer "F.Fab")
		)
		(pad "1" smd custom
			(at 0 -0.4445 270)
			(size 0.1397 0.1397)
			(layers "F.Cu" "F.Mask" "F.Paste")
			(net "P5VA_ROVP")
			(options
				(clearance outline)
				(anchor circle)
			)
			(primitives
				(gr_poly
					(pts
						(arc
							(start -0.1778 -0.2794)
							(mid -0.249642 -0.249642)
							(end -0.2794 -0.1778)
						)
						(arc
							(start -0.2794 0.1778)
							(mid -0.249642 0.249642)
							(end -0.1778 0.2794)
						)
						(arc
							(start 0.1778 0.2794)
							(mid 0.249642 0.249642)
							(end 0.2794 0.1778)
						)
						(arc
							(start 0.2794 -0.1778)
							(mid 0.249642 -0.249642)
							(end 0.1778 -0.2794)
						)
					)
					(width 0)
					(fill yes)
				)
			)
		)
		(pad "2" smd custom
			(at 0 0.4445 270)
			(size 0.1397 0.1397)
			(layers "F.Cu" "F.Mask" "F.Paste")
			(net "P5VA")
			(options
				(clearance outline)
				(anchor circle)
			)
			(primitives
				(gr_poly
					(pts
						(arc
							(start -0.1778 -0.2794)
							(mid -0.249642 -0.249642)
							(end -0.2794 -0.1778)
						)
						(arc
							(start -0.2794 0.1778)
							(mid -0.249642 0.249642)
							(end -0.1778 0.2794)
						)
						(arc
							(start 0.1778 0.2794)
							(mid 0.249642 0.249642)
							(end 0.2794 0.1778)
						)
						(arc
							(start 0.2794 -0.1778)
							(mid 0.249642 -0.249642)
							(end 0.1778 -0.2794)
						)
					)
					(width 0)
					(fill yes)
				)
			)
		)
	)
	(footprint ""
		(layer "F.Cu")
		(at 77.495146 -7.013702)
		(property "Reference" "C335"
			(at 0 0 0)
			(layer "F.SilkS")
			(hide yes)
			(effects
				(font
					(size 1.27 1.27)
				)
			)
		)
		(property "Value" "SC10U25V6KX-1GP"
			(at -0.0762 -5.1308 0)
			(unlocked yes)
			(layer "F.Fab")
			(hide yes)
			(effects
				(font
					(size 1.016 1.016)
					(thickness 0.1524)
				)
			)
		)
		(property "Device Type" "C1206H71"
			(at -0.127 -6.6548 0)
			(unlocked yes)
			(layer "F.Fab")
			(hide yes)
			(effects
				(font
					(size 1.016 1.016)
					(thickness 0.1524)
				)
			)
		)
		(duplicate_pad_numbers_are_jumpers no)
		(fp_line
			(start -1.016 -2.2352)
			(end 1.016 -2.2352)
			(stroke
				(width 0.1524)
				(type default)
			)
			(layer "F.SilkS")
		)
		(fp_line
			(start -1.016 -0.8382)
			(end -1.016 -2.2352)
			(stroke
				(width 0.1524)
				(type default)
			)
			(layer "F.SilkS")
		)
		(fp_line
			(start -1.016 2.2352)
			(end -1.016 0.8382)
			(stroke
				(width 0.1524)
				(type default)
			)
			(layer "F.SilkS")
		)
		(fp_line
			(start 1.016 -2.2352)
			(end 1.016 -0.8382)
			(stroke
				(width 0.1524)
				(type default)
			)
			(layer "F.SilkS")
		)
		(fp_line
			(start 1.016 0.8382)
			(end 1.016 2.2352)
			(stroke
				(width 0.1524)
				(type default)
			)
			(layer "F.SilkS")
		)
		(fp_line
			(start 1.016 2.2352)
			(end -1.016 2.2352)
			(stroke
				(width 0.1524)
				(type default)
			)
			(layer "F.SilkS")
		)
		(fp_rect
			(start -1.0922 2.3114)
			(end 1.0922 -2.3114)
			(stroke
				(width 0)
				(type default)
			)
			(fill no)
			(layer "F.CrtYd")
		)
		(fp_poly
			(pts
				(xy 1.0922 -2.3114) (xy 1.0922 2.3114) (xy -1.0922 2.3114) (xy -1.0922 -2.3114)
			)
			(stroke
				(width 0)
				(type default)
			)
			(fill no)
			(layer "F.Fab")
		)
		(pad "1" smd rect
			(at 0 -1.397)
			(size 1.651 1.27)
			(layers "F.Cu" "F.Mask" "F.Paste")
			(net "P12V_HDD14")
		)
		(pad "2" smd rect
			(at 0 1.397)
			(size 1.651 1.27)
			(layers "F.Cu" "F.Mask" "F.Paste")
			(net "GND")
		)
	)
	(footprint ""
		(layer "F.Cu")
		(at 197.485 -179.832)
		(property "Reference" "C149"
			(at 0 0 0)
			(layer "F.SilkS")
			(hide yes)
			(effects
				(font
					(size 1.27 1.27)
				)
			)
		)
		(property "Value" "SCD1U10V2KX-5GP"
			(at 1.1811 -2.7051 0)
			(unlocked yes)
			(layer "F.Fab")
			(hide yes)
			(effects
				(font
					(size 1.016 1.016)
					(thickness 0.1524)
				)
			)
		)
		(property "Device Type" "C402H22"
			(at 1.1811 -4.2291 0)
			(unlocked yes)
			(layer "F.Fab")
			(hide yes)
			(effects
				(font
					(size 1.016 1.016)
					(thickness 0.1524)
				)
			)
		)
		(duplicate_pad_numbers_are_jumpers no)
		(fp_rect
			(start -0.4318 0.9525)
			(end 0.4318 -0.9525)
			(stroke
				(width 0)
				(type default)
			)
			(fill no)
			(layer "F.CrtYd")
		)
		(fp_rect
			(start -0.4318 0.9525)
			(end 0.4318 -0.9525)
			(stroke
				(width 0)
				(type default)
			)
			(fill no)
			(layer "F.Fab")
		)
		(pad "1" smd custom
			(at 0 -0.4445)
			(size 0.1524 0.1524)
			(layers "F.Cu" "F.Mask" "F.Paste")
			(net "P3V3")
			(options
				(clearance outline)
				(anchor circle)
			)
			(primitives
				(gr_poly
					(pts
						(arc
							(start 0.3048 -0.2032)
							(mid 0.275042 -0.275042)
							(end 0.2032 -0.3048)
						)
						(arc
							(start -0.2032 -0.3048)
							(mid -0.275042 -0.275042)
							(end -0.3048 -0.2032)
						)
						(arc
							(start -0.3048 0.2032)
							(mid -0.275042 0.275042)
							(end -0.2032 0.3048)
						)
						(arc
							(start 0.2032 0.3048)
							(mid 0.275042 0.275042)
							(end 0.3048 0.2032)
						)
					)
					(width 0)
					(fill yes)
				)
			)
		)
		(pad "2" smd custom
			(at 0 0.4445)
			(size 0.1524 0.1524)
			(layers "F.Cu" "F.Mask" "F.Paste")
			(net "GND")
			(options
				(clearance outline)
				(anchor circle)
			)
			(primitives
				(gr_poly
					(pts
						(arc
							(start 0.3048 -0.2032)
							(mid 0.275042 -0.275042)
							(end 0.2032 -0.3048)
						)
						(arc
							(start -0.2032 -0.3048)
							(mid -0.275042 -0.275042)
							(end -0.3048 -0.2032)
						)
						(arc
							(start -0.3048 0.2032)
							(mid -0.275042 0.275042)
							(end -0.2032 0.3048)
						)
						(arc
							(start 0.2032 0.3048)
							(mid 0.275042 0.275042)
							(end 0.3048 0.2032)
						)
					)
					(width 0)
					(fill yes)
				)
			)
		)
	)
	(footprint ""
		(layer "F.Cu")
		(at 59.1058 -378.3838 180)
		(property "Reference" "Q59"
			(at 0 0 180)
			(layer "F.SilkS")
			(hide yes)
			(effects
				(font
					(size 1.27 1.27)
				)
			)
		)
		(property "Value" "2N7002-11-GP"
			(at 0.127 -8.9662 180)
			(unlocked yes)
			(layer "F.Fab")
			(hide yes)
			(effects
				(font
					(size 1.016 1.016)
					(thickness 0.1524)
				)
			)
		)
		(property "Device Type" "SOT23DGS2D4H44"
			(at 0.127 -10.4902 180)
			(unlocked yes)
			(layer "F.Fab")
			(hide yes)
			(effects
				(font
					(size 1.016 1.016)
					(thickness 0.1524)
				)
			)
		)
		(duplicate_pad_numbers_are_jumpers no)
		(fp_line
			(start 1.651 1.778)
			(end 1.651 -1.778)
			(stroke
				(width 0.1524)
				(type default)
			)
			(layer "F.SilkS")
		)
		(fp_line
			(start 1.651 -1.778)
			(end -1.651 -1.778)
			(stroke
				(width 0.1524)
				(type default)
			)
			(layer "F.SilkS")
		)
		(fp_line
			(start -1.651 1.778)
			(end 1.651 1.778)
			(stroke
				(width 0.1524)
				(type default)
			)
			(layer "F.SilkS")
		)
		(fp_line
			(start -1.651 -1.778)
			(end -1.651 1.778)
			(stroke
				(width 0.1524)
				(type default)
			)
			(layer "F.SilkS")
		)
		(fp_poly
			(pts
				(xy -1.778 1.8796) (xy -1.778 -1.8796) (xy 1.778 -1.8796) (xy 1.778 1.8796)
			)
			(stroke
				(width 0)
				(type default)
			)
			(fill no)
			(layer "F.CrtYd")
		)
		(fp_poly
			(pts
				(xy -1.778 1.8796) (xy -1.778 -1.8796) (xy 1.778 -1.8796) (xy 1.778 1.8796)
			)
			(stroke
				(width 0)
				(type default)
			)
			(fill no)
			(layer "F.Fab")
		)
		(pad "D" smd custom
			(at 0 -0.9525 180)
			(size 0.1905 0.1905)
			(layers "F.Cu" "F.Mask" "F.Paste")
			(net "HDD6_LED_G")
			(options
				(clearance outline)
				(anchor circle)
			)
			(primitives
				(gr_poly
					(pts
						(arc
							(start -0.1778 0.5715)
							(mid -0.321484 0.511984)
							(end -0.381 0.3683)
						)
						(arc
							(start -0.381 -0.3683)
							(mid -0.321484 -0.511984)
							(end -0.1778 -0.5715)
						)
						(arc
							(start 0.1778 -0.5715)
							(mid 0.321484 -0.511984)
							(end 0.381 -0.3683)
						)
						(arc
							(start 0.381 0.3683)
							(mid 0.321484 0.511984)
							(end 0.1778 0.5715)
						)
					)
					(width 0)
					(fill yes)
				)
			)
		)
		(pad "G" smd custom
			(at -0.98425 0.9525 180)
			(size 0.1905 0.1905)
			(layers "F.Cu" "F.Mask" "F.Paste")
			(net "HDD6_LED_B")
			(options
				(clearance outline)
				(anchor circle)
			)
			(primitives
				(gr_poly
					(pts
						(arc
							(start -0.1778 0.5715)
							(mid -0.321484 0.511984)
							(end -0.381 0.3683)
						)
						(arc
							(start -0.381 -0.3683)
							(mid -0.321484 -0.511984)
							(end -0.1778 -0.5715)
						)
						(arc
							(start 0.1778 -0.5715)
							(mid 0.321484 -0.511984)
							(end 0.381 -0.3683)
						)
						(arc
							(start 0.381 0.3683)
							(mid 0.321484 0.511984)
							(end 0.1778 0.5715)
						)
					)
					(width 0)
					(fill yes)
				)
			)
		)
		(pad "S" smd custom
			(at 0.98425 0.9525 180)
			(size 0.1905 0.1905)
			(layers "F.Cu" "F.Mask" "F.Paste")
			(net "GND")
			(options
				(clearance outline)
				(anchor circle)
			)
			(primitives
				(gr_poly
					(pts
						(arc
							(start -0.1778 0.5715)
							(mid -0.321484 0.511984)
							(end -0.381 0.3683)
						)
						(arc
							(start -0.381 -0.3683)
							(mid -0.321484 -0.511984)
							(end -0.1778 -0.5715)
						)
						(arc
							(start 0.1778 -0.5715)
							(mid 0.321484 -0.511984)
							(end 0.381 -0.3683)
						)
						(arc
							(start 0.381 0.3683)
							(mid 0.321484 0.511984)
							(end 0.1778 0.5715)
						)
					)
					(width 0)
					(fill yes)
				)
			)
		)
	)
	(footprint ""
		(layer "F.Cu")
		(at 17.500092 -129.329942 -90)
		(property "Reference" "SKT14"
			(at 0 0 270)
			(layer "F.SilkS")
			(hide yes)
			(effects
				(font
					(size 1.27 1.27)
				)
			)
		)
		(property "Value" "SKT-SATA14P-15P-12-GP"
			(at -22.6187 8.1788 270)
			(unlocked yes)
			(layer "F.Fab")
			(hide yes)
			(effects
				(font
					(size 1.016 1.016)
					(thickness 0.1524)
				)
			)
		)
		(property "Device Type" "87945-1001"
			(at -22.6187 6.6548 270)
			(unlocked yes)
			(layer "F.Fab")
			(hide yes)
			(effects
				(font
					(size 1.016 1.016)
					(thickness 0.1524)
				)
			)
		)
		(duplicate_pad_numbers_are_jumpers no)
		(fp_line
			(start -20.4724 9.652)
			(end -20.4724 2.3114)
			(stroke
				(width 0.1524)
				(type default)
			)
			(layer "F.SilkS")
		)
		(fp_line
			(start -17.8435 9.652)
			(end -20.4724 9.652)
			(stroke
				(width 0.1524)
				(type default)
			)
			(layer "F.SilkS")
		)
		(fp_line
			(start 17.8435 9.652)
			(end 17.8435 7.9502)
			(stroke
				(width 0.1524)
				(type default)
			)
			(layer "F.SilkS")
		)
		(fp_line
			(start 20.4724 9.652)
			(end 17.8435 9.652)
			(stroke
				(width 0.1524)
				(type default)
			)
			(layer "F.SilkS")
		)
		(fp_line
			(start -17.8435 7.9502)
			(end -17.8435 9.652)
			(stroke
				(width 0.1524)
				(type default)
			)
			(layer "F.SilkS")
		)
		(fp_line
			(start 17.8435 7.9502)
			(end -17.8435 7.9502)
			(stroke
				(width 0.1524)
				(type default)
			)
			(layer "F.SilkS")
		)
		(fp_line
			(start -23.7617 2.3114)
			(end -23.7617 -2.3114)
			(stroke
				(width 0.1524)
				(type default)
			)
			(layer "F.SilkS")
		)
		(fp_line
			(start -20.4724 2.3114)
			(end -23.7617 2.3114)
			(stroke
				(width 0.1524)
				(type default)
			)
			(layer "F.SilkS")
		)
		(fp_line
			(start 20.4724 2.3114)
			(end 20.4724 9.652)
			(stroke
				(width 0.1524)
				(type default)
			)
			(layer "F.SilkS")
		)
		(fp_line
			(start 23.7617 2.3114)
			(end 20.4724 2.3114)
			(stroke
				(width 0.1524)
				(type default)
			)
			(layer "F.SilkS")
		)
		(fp_line
			(start -23.117556 0.5461)
			(end -23.117556 -0.5461)
			(stroke
				(width 0.3048)
				(type default)
			)
			(layer "F.SilkS")
		)
		(fp_line
			(start 20.882356 0.5461)
			(end 20.882356 -0.5461)
			(stroke
				(width 0.3048)
				(type default)
			)
			(layer "F.SilkS")
		)
		(fp_line
			(start -20.882356 -0.5461)
			(end -20.882356 0.5461)
			(stroke
				(width 0.3048)
				(type default)
			)
			(layer "F.SilkS")
		)
		(fp_line
			(start 23.117556 -0.5461)
			(end 23.117556 0.5461)
			(stroke
				(width 0.3048)
				(type default)
			)
			(layer "F.SilkS")
		)
		(fp_line
			(start -23.7617 -2.3114)
			(end -20.4724 -2.3114)
			(stroke
				(width 0.1524)
				(type default)
			)
			(layer "F.SilkS")
		)
		(fp_line
			(start -20.4724 -2.3114)
			(end -20.4724 -5.7658)
			(stroke
				(width 0.1524)
				(type default)
			)
			(layer "F.SilkS")
		)
		(fp_line
			(start 20.4724 -2.3114)
			(end 23.7617 -2.3114)
			(stroke
				(width 0.1524)
				(type default)
			)
			(layer "F.SilkS")
		)
		(fp_line
			(start 23.7617 -2.3114)
			(end 23.7617 2.3114)
			(stroke
				(width 0.1524)
				(type default)
			)
			(layer "F.SilkS")
		)
		(fp_line
			(start -20.4724 -5.7658)
			(end 20.4724 -5.7658)
			(stroke
				(width 0.1524)
				(type default)
			)
			(layer "F.SilkS")
		)
		(fp_line
			(start 20.4724 -5.7658)
			(end 20.4724 -2.3114)
			(stroke
				(width 0.1524)
				(type default)
			)
			(layer "F.SilkS")
		)
		(fp_line
			(start -15.3924 -5.8547)
			(end -16.3576 -5.8547)
			(stroke
				(width 0.3302)
				(type default)
			)
			(layer "F.SilkS")
		)
		(fp_arc
			(start -20.882356 0.5461)
			(mid -21.999956 1.6637)
			(end -23.117556 0.5461)
			(stroke
				(width 0.3048)
				(type default)
			)
			(layer "F.SilkS")
		)
		(fp_arc
			(start 23.117556 0.5461)
			(mid 21.999956 1.6637)
			(end 20.882356 0.5461)
			(stroke
				(width 0.3048)
				(type default)
			)
			(layer "F.SilkS")
		)
		(fp_arc
			(start -23.117556 -0.5461)
			(mid -21.999956 -1.6637)
			(end -20.882356 -0.5461)
			(stroke
				(width 0.3048)
				(type default)
			)
			(layer "F.SilkS")
		)
		(fp_arc
			(start 20.882356 -0.5461)
			(mid 21.999956 -1.6637)
			(end 23.117556 -0.5461)
			(stroke
				(width 0.3048)
				(type default)
			)
			(layer "F.SilkS")
		)
		(fp_poly
			(pts
				(xy -15.87119 -5.838698) (xy -15.23619 -6.473698) (xy -16.50619 -6.473698)
			)
			(stroke
				(width 0)
				(type default)
			)
			(fill yes)
			(layer "F.SilkS")
		)
		(fp_poly
			(pts
				(xy -20.2184 -5.5118) (xy 20.2184 -5.5118) (xy 20.2184 -2.0574) (xy 23.5077 -2.0574) (xy 23.5077 2.0574)
				(xy 20.2184 2.0574) (xy 20.2184 9.398) (xy 18.0975 9.398) (xy 18.0975 7.6962) (xy -18.0975 7.6962)
				(xy -18.0975 9.398) (xy -20.2184 9.398) (xy -20.2184 2.0574) (xy -23.5077 2.0574) (xy -23.5077 -2.0574)
				(xy -20.2184 -2.0574)
			)
			(stroke
				(width 0)
				(type default)
			)
			(fill no)
			(layer "F.CrtYd")
		)
		(fp_poly
			(pts
				(xy -20.2184 -5.5118) (xy -20.2184 -6.0198) (xy -20.7264 -6.0198) (xy -20.7264 -2.5654) (xy -24.0157 -2.5654)
				(xy -24.0157 2.5654) (xy -20.7264 2.5654) (xy -20.7264 9.906) (xy -17.5895 9.906) (xy -17.5895 8.2042)
				(xy 17.5895 8.2042) (xy 17.5895 9.906) (xy 20.7264 9.906) (xy 20.7264 2.5654) (xy 24.0157 2.5654)
				(xy 24.0157 -2.5654) (xy 20.7264 -2.5654) (xy 20.7264 -6.0198) (xy -20.21586 -6.0198) (xy -20.21586 -5.5118)
				(xy 20.2184 -5.5118) (xy 20.2184 -2.0574) (xy 23.5077 -2.0574) (xy 23.5077 2.0574) (xy 20.2184 2.0574)
				(xy 20.2184 9.398) (xy 18.0975 9.398) (xy 18.0975 7.6962) (xy -18.0975 7.6962) (xy -18.0975 9.398)
				(xy -20.2184 9.398) (xy -20.2184 2.0574) (xy -23.5077 2.0574) (xy -23.5077 -2.0574) (xy -20.2184 -2.0574)
			)
			(stroke
				(width 0)
				(type default)
			)
			(fill no)
			(layer "F.CrtYd")
		)
		(fp_poly
			(pts
				(xy -20.7264 -6.0198) (xy -20.7264 -2.5654) (xy -24.0157 -2.5654) (xy -24.0157 2.5654) (xy -20.7264 2.5654)
				(xy -20.7264 9.906) (xy -17.5895 9.906) (xy -17.5895 8.2042) (xy 17.5895 8.2042) (xy 17.5895 9.906)
				(xy 20.7264 9.906) (xy 20.7264 2.5654) (xy 24.0157 2.5654) (xy 24.0157 -2.5654) (xy 20.7264 -2.5654)
				(xy 20.7264 -6.0198)
			)
			(stroke
				(width 0)
				(type default)
			)
			(fill no)
			(layer "F.Fab")
		)
		(pad "" np_thru_hole circle
			(at -18.999962 -2.350008 270)
			(size 0.254 0.254)
			(drill 1.8542)
			(layers "*.Cu" "*.Mask")
			(clearance 1.1557)
			(thermal_gap 1.1557)
		)
		(pad "" np_thru_hole circle
			(at 18.999962 -2.350008 270)
			(size 0.254 0.254)
			(drill 1.8542)
			(layers "*.Cu" "*.Mask")
			(clearance 1.1557)
			(thermal_gap 1.1557)
		)
		(pad "H1" thru_hole oval
			(at -21.999956 0 270)
			(size 1.524 2.6162)
			(drill oval 0.8128 1.905)
			(layers "*.Cu" "*.Mask")
			(remove_unused_layers no)
			(net "GND")
			(clearance 0.1524)
			(thermal_gap 0.1524)
		)
		(pad "H2" thru_hole oval
			(at 21.999956 0 270)
			(size 1.524 2.6162)
			(drill oval 0.8128 1.905)
			(layers "*.Cu" "*.Mask")
			(remove_unused_layers no)
			(net "GND")
			(clearance 0.1524)
			(thermal_gap 0.1524)
		)
		(pad "P1" smd rect
			(at -1.89992 -4.249928 270)
			(size 0.6604 2.3876)
			(layers "F.Cu" "F.Mask" "F.Paste")
			(net "Net_50")
		)
		(pad "P2" smd rect
			(at -0.62992 -4.249928 270)
			(size 0.6604 2.3876)
			(layers "F.Cu" "F.Mask" "F.Paste")
			(net "Net_49")
		)
		(pad "P3" smd rect
			(at 0.64008 -4.249928 270)
			(size 0.6604 2.3876)
			(layers "F.Cu" "F.Mask" "F.Paste")
			(net "Net_48")
		)
		(pad "P4" smd rect
			(at 1.91008 -4.249928 270)
			(size 0.6604 2.3876)
			(layers "F.Cu" "F.Mask" "F.Paste")
			(net "GND")
		)
		(pad "P5" smd rect
			(at 3.18008 -4.249928 270)
			(size 0.6604 2.3876)
			(layers "F.Cu" "F.Mask" "F.Paste")
			(net "HDD_PRSNT_NET13")
		)
		(pad "P6" smd rect
			(at 4.45008 -4.249928 270)
			(size 0.6604 2.3876)
			(layers "F.Cu" "F.Mask" "F.Paste")
			(net "GND")
		)
		(pad "P7" smd rect
			(at 5.72008 -4.249928 270)
			(size 0.6604 2.3876)
			(layers "F.Cu" "F.Mask" "F.Paste")
			(net "5V_PRE_13")
		)
		(pad "P8" smd rect
			(at 6.99008 -4.249928 270)
			(size 0.6604 2.3876)
			(layers "F.Cu" "F.Mask" "F.Paste")
			(net "P5V_HDD13")
		)
		(pad "P9" smd rect
			(at 8.26008 -4.249928 270)
			(size 0.6604 2.3876)
			(layers "F.Cu" "F.Mask" "F.Paste")
			(net "P5V_HDD13")
		)
		(pad "P10" smd rect
			(at 9.53008 -4.249928 270)
			(size 0.6604 2.3876)
			(layers "F.Cu" "F.Mask" "F.Paste")
			(net "GND")
		)
		(pad "P11" smd rect
			(at 10.80008 -4.249928 270)
			(size 0.6604 2.3876)
			(layers "F.Cu" "F.Mask" "F.Paste")
			(net "ACT_HDD13")
		)
		(pad "P12" smd rect
			(at 12.07008 -4.249928 270)
			(size 0.6604 2.3876)
			(layers "F.Cu" "F.Mask" "F.Paste")
			(net "GND")
		)
		(pad "P13" smd rect
			(at 13.34008 -4.249928 270)
			(size 0.6604 2.3876)
			(layers "F.Cu" "F.Mask" "F.Paste")
			(net "12V_PRE_13")
		)
		(pad "P14" smd rect
			(at 14.61008 -4.249928 270)
			(size 0.6604 2.3876)
			(layers "F.Cu" "F.Mask" "F.Paste")
			(net "P12V_HDD13")
		)
		(pad "P15" smd rect
			(at 15.88008 -4.249928 270)
			(size 0.6604 2.3876)
			(layers "F.Cu" "F.Mask" "F.Paste")
			(net "P12V_HDD13")
		)
		(pad "S1" smd rect
			(at -15.86992 -4.249928 270)
			(size 0.6604 2.3876)
			(layers "F.Cu" "F.Mask" "F.Paste")
			(net "GND")
		)
		(pad "S2" smd rect
			(at -14.59992 -4.249928 270)
			(size 0.6604 2.3876)
			(layers "F.Cu" "F.Mask" "F.Paste")
			(net "SAS2X28_A_HDD13_TX_+")
		)
		(pad "S3" smd rect
			(at -13.32992 -4.249928 270)
			(size 0.6604 2.3876)
			(layers "F.Cu" "F.Mask" "F.Paste")
			(net "SAS2X28_A_HDD13_TX_-")
		)
		(pad "S4" smd rect
			(at -12.05992 -4.249928 270)
			(size 0.6604 2.3876)
			(layers "F.Cu" "F.Mask" "F.Paste")
			(net "GND")
		)
		(pad "S5" smd rect
			(at -10.78992 -4.249928 270)
			(size 0.6604 2.3876)
			(layers "F.Cu" "F.Mask" "F.Paste")
			(net "SAS2X28_DRIVE_RX_N_A13")
		)
		(pad "S6" smd rect
			(at -9.51992 -4.249928 270)
			(size 0.6604 2.3876)
			(layers "F.Cu" "F.Mask" "F.Paste")
			(net "SAS2X28_DRIVE_RX_P_A13")
		)
		(pad "S7" smd rect
			(at -8.24992 -4.249928 270)
			(size 0.6604 2.3876)
			(layers "F.Cu" "F.Mask" "F.Paste")
			(net "GND")
		)
		(pad "S8" smd rect
			(at -7.480046 -2.100072 270)
			(size 0.508 1.905)
			(layers "F.Cu" "F.Mask" "F.Paste")
			(net "GND")
		)
		(pad "S9" smd rect
			(at -6.679946 -2.100072 270)
			(size 0.508 1.905)
			(layers "F.Cu" "F.Mask" "F.Paste")
			(net "SAS2X28_B_HDD13_TX_+")
		)
		(pad "S10" smd rect
			(at -5.8801 -2.100072 270)
			(size 0.508 1.905)
			(layers "F.Cu" "F.Mask" "F.Paste")
			(net "SAS2X28_B_HDD13_TX_-")
		)
		(pad "S11" smd rect
			(at -5.08 -2.100072 270)
			(size 0.508 1.905)
			(layers "F.Cu" "F.Mask" "F.Paste")
			(net "GND")
		)
		(pad "S12" smd rect
			(at -4.2799 -2.100072 270)
			(size 0.508 1.905)
			(layers "F.Cu" "F.Mask" "F.Paste")
			(net "SAS2X28_DRIVE_RX_N_B13")
		)
		(pad "S13" smd rect
			(at -3.480054 -2.100072 270)
			(size 0.508 1.905)
			(layers "F.Cu" "F.Mask" "F.Paste")
			(net "SAS2X28_DRIVE_RX_P_B13")
		)
		(pad "S14" smd rect
			(at -2.679954 -2.100072 270)
			(size 0.508 1.905)
			(layers "F.Cu" "F.Mask" "F.Paste")
			(net "GND")
		)
		(zone
			(layers "F.Cu" "B.Cu" "In1.Cu" "In2.Cu" "In3.Cu" "In4.Cu" "In5.Cu" "In6.Cu")
			(hatch none 0.5)
			(connect_pads
				(clearance 0)
			)
			(min_thickness 0.25)
			(keepout
				(tracks not_allowed)
				(vias allowed)
				(pads allowed)
				(copperpour not_allowed)
				(footprints allowed)
			)
			(placement
				(enabled no)
				(sheetname "")
			)
			(fill
				(thermal_gap 0.5)
				(thermal_bridge_width 0.5)
				(island_removal_mode 0)
			)
			(polygon
				(pts
					(arc
						(start 21.082 -148.329904)
						(mid 18.6182 -148.329904)
						(end 21.082 -148.329904)
					)
				)
			)
		)
		(zone
			(layers "F.Cu" "B.Cu" "In1.Cu" "In2.Cu" "In3.Cu" "In4.Cu" "In5.Cu" "In6.Cu")
			(hatch none 0.5)
			(connect_pads
				(clearance 0)
			)
			(min_thickness 0.25)
			(keepout
				(tracks not_allowed)
				(vias allowed)
				(pads allowed)
				(copperpour not_allowed)
				(footprints allowed)
			)
			(placement
				(enabled no)
				(sheetname "")
			)
			(fill
				(thermal_gap 0.5)
				(thermal_bridge_width 0.5)
				(island_removal_mode 0)
			)
			(polygon
				(pts
					(arc
						(start 21.082 -110.32998)
						(mid 18.6182 -110.32998)
						(end 21.082 -110.32998)
					)
				)
			)
		)
	)
	(footprint ""
		(layer "F.Cu")
		(at 4.445 -283.718 90)
		(property "Reference" "PC68"
			(at 0 0 90)
			(layer "F.SilkS")
			(hide yes)
			(effects
				(font
					(size 1.27 1.27)
				)
			)
		)
		(property "Value" "SC22U25V5MX-GP"
			(at -0.0762 -6.1214 90)
			(unlocked yes)
			(layer "F.Fab")
			(hide yes)
			(effects
				(font
					(size 1.016 1.016)
					(thickness 0.1524)
				)
			)
		)
		(property "Device Type" "C805H58"
			(at -0.0762 -8.1534 90)
			(unlocked yes)
			(layer "F.Fab")
			(hide yes)
			(effects
				(font
					(size 1.016 1.016)
					(thickness 0.1524)
				)
			)
		)
		(duplicate_pad_numbers_are_jumpers no)
		(fp_line
			(start 0.635 0)
			(end -0.635 0)
			(stroke
				(width 0.508)
				(type default)
			)
			(layer "F.SilkS")
		)
		(fp_rect
			(start -0.9652 1.778)
			(end 0.9652 -1.778)
			(stroke
				(width 0)
				(type default)
			)
			(fill no)
			(layer "F.CrtYd")
		)
		(fp_poly
			(pts
				(xy -0.9652 -1.778) (xy 0.9652 -1.778) (xy 0.9652 1.778) (xy -0.9652 1.778)
			)
			(stroke
				(width 0)
				(type default)
			)
			(fill no)
			(layer "F.Fab")
		)
		(pad "1" smd rect
			(at 0 -0.9652 90)
			(size 1.397 1.143)
			(layers "F.Cu" "F.Mask" "F.Paste")
			(net "P12V")
		)
		(pad "2" smd rect
			(at 0 0.9652 90)
			(size 1.397 1.143)
			(layers "F.Cu" "F.Mask" "F.Paste")
			(net "GND")
		)
	)
	(footprint ""
		(layer "F.Cu")
		(at 224.747582 -247.876568 90)
		(property "Reference" "R129"
			(at 0 0 90)
			(layer "F.SilkS")
			(hide yes)
			(effects
				(font
					(size 1.27 1.27)
				)
			)
		)
		(property "Value" "402R2F-GP"
			(at 0.064008 -3.993896 90)
			(unlocked yes)
			(layer "F.Fab")
			(hide yes)
			(effects
				(font
					(size 1.016 1.016)
					(thickness 0.1524)
				)
			)
		)
		(property "Device Type" "R402H16"
			(at 0.064008 -5.517896 90)
			(unlocked yes)
			(layer "F.Fab")
			(hide yes)
			(effects
				(font
					(size 1.016 1.016)
					(thickness 0.1524)
				)
			)
		)
		(duplicate_pad_numbers_are_jumpers no)
		(fp_line
			(start 0.508 -0.9398)
			(end -0.508 -0.9398)
			(stroke
				(width 0.1524)
				(type default)
			)
			(layer "F.SilkS")
		)
		(fp_line
			(start -0.508 -0.9398)
			(end -0.508 0.9398)
			(stroke
				(width 0.1524)
				(type default)
			)
			(layer "F.SilkS")
		)
		(fp_rect
			(start -0.508 0.9398)
			(end 0.508 -0.9398)
			(stroke
				(width 0)
				(type default)
			)
			(fill no)
			(layer "F.CrtYd")
		)
		(fp_rect
			(start -0.508 0.9398)
			(end 0.508 -0.9398)
			(stroke
				(width 0)
				(type default)
			)
			(fill no)
			(layer "F.Fab")
		)
		(pad "1" smd custom
			(at 0 -0.4445 90)
			(size 0.1397 0.1397)
			(layers "F.Cu" "F.Mask" "F.Paste")
			(net "P5VA_HDD2_LED")
			(options
				(clearance outline)
				(anchor circle)
			)
			(primitives
				(gr_poly
					(pts
						(arc
							(start -0.1778 -0.2794)
							(mid -0.249642 -0.249642)
							(end -0.2794 -0.1778)
						)
						(arc
							(start -0.2794 0.1778)
							(mid -0.249642 0.249642)
							(end -0.1778 0.2794)
						)
						(arc
							(start 0.1778 0.2794)
							(mid 0.249642 0.249642)
							(end 0.2794 0.1778)
						)
						(arc
							(start 0.2794 -0.1778)
							(mid 0.249642 -0.249642)
							(end 0.1778 -0.2794)
						)
					)
					(width 0)
					(fill yes)
				)
			)
		)
		(pad "2" smd custom
			(at 0 0.4445 90)
			(size 0.1397 0.1397)
			(layers "F.Cu" "F.Mask" "F.Paste")
			(net "DRV_ACT_2")
			(options
				(clearance outline)
				(anchor circle)
			)
			(primitives
				(gr_poly
					(pts
						(arc
							(start -0.1778 -0.2794)
							(mid -0.249642 -0.249642)
							(end -0.2794 -0.1778)
						)
						(arc
							(start -0.2794 0.1778)
							(mid -0.249642 0.249642)
							(end -0.1778 0.2794)
						)
						(arc
							(start 0.1778 0.2794)
							(mid 0.249642 0.249642)
							(end 0.2794 0.1778)
						)
						(arc
							(start 0.2794 -0.1778)
							(mid 0.249642 -0.249642)
							(end 0.1778 -0.2794)
						)
					)
					(width 0)
					(fill yes)
				)
			)
		)
	)
	(footprint ""
		(layer "F.Cu")
		(at 20.193254 -156.3243 -90)
		(property "Reference" "R285"
			(at 0 0 270)
			(layer "F.SilkS")
			(hide yes)
			(effects
				(font
					(size 1.27 1.27)
				)
			)
		)
		(property "Value" "330R2F-GP"
			(at 0.064008 -3.993896 270)
			(unlocked yes)
			(layer "F.Fab")
			(hide yes)
			(effects
				(font
					(size 1.016 1.016)
					(thickness 0.1524)
				)
			)
		)
		(property "Device Type" "R402H16"
			(at 0.064008 -5.517896 270)
			(unlocked yes)
			(layer "F.Fab")
			(hide yes)
			(effects
				(font
					(size 1.016 1.016)
					(thickness 0.1524)
				)
			)
		)
		(duplicate_pad_numbers_are_jumpers no)
		(fp_line
			(start -0.508 -0.9398)
			(end -0.508 0.9398)
			(stroke
				(width 0.1524)
				(type default)
			)
			(layer "F.SilkS")
		)
		(fp_line
			(start 0.508 -0.9398)
			(end -0.508 -0.9398)
			(stroke
				(width 0.1524)
				(type default)
			)
			(layer "F.SilkS")
		)
		(fp_rect
			(start -0.508 0.9398)
			(end 0.508 -0.9398)
			(stroke
				(width 0)
				(type default)
			)
			(fill no)
			(layer "F.CrtYd")
		)
		(fp_rect
			(start -0.508 0.9398)
			(end 0.508 -0.9398)
			(stroke
				(width 0)
				(type default)
			)
			(fill no)
			(layer "F.Fab")
		)
		(pad "1" smd custom
			(at 0 -0.4445 270)
			(size 0.1397 0.1397)
			(layers "F.Cu" "F.Mask" "F.Paste")
			(net "P3V3_HDD13_LED")
			(options
				(clearance outline)
				(anchor circle)
			)
			(primitives
				(gr_poly
					(pts
						(arc
							(start -0.1778 -0.2794)
							(mid -0.249642 -0.249642)
							(end -0.2794 -0.1778)
						)
						(arc
							(start -0.2794 0.1778)
							(mid -0.249642 0.249642)
							(end -0.1778 0.2794)
						)
						(arc
							(start 0.1778 0.2794)
							(mid 0.249642 0.249642)
							(end 0.2794 0.1778)
						)
						(arc
							(start 0.2794 -0.1778)
							(mid 0.249642 -0.249642)
							(end 0.1778 -0.2794)
						)
					)
					(width 0)
					(fill yes)
				)
			)
		)
		(pad "2" smd custom
			(at 0 0.4445 270)
			(size 0.1397 0.1397)
			(layers "F.Cu" "F.Mask" "F.Paste")
			(net "FLT_HDD13")
			(options
				(clearance outline)
				(anchor circle)
			)
			(primitives
				(gr_poly
					(pts
						(arc
							(start -0.1778 -0.2794)
							(mid -0.249642 -0.249642)
							(end -0.2794 -0.1778)
						)
						(arc
							(start -0.2794 0.1778)
							(mid -0.249642 0.249642)
							(end -0.1778 0.2794)
						)
						(arc
							(start 0.1778 0.2794)
							(mid 0.249642 0.249642)
							(end 0.2794 0.1778)
						)
						(arc
							(start 0.2794 -0.1778)
							(mid 0.249642 -0.249642)
							(end 0.1778 -0.2794)
						)
					)
					(width 0)
					(fill yes)
				)
			)
		)
	)
	(footprint ""
		(layer "F.Cu")
		(at 14.604746 -51.7017 -90)
		(property "Reference" "R296"
			(at 0 0 270)
			(layer "F.SilkS")
			(hide yes)
			(effects
				(font
					(size 1.27 1.27)
				)
			)
		)
		(property "Value" "10KR2F-2-GP"
			(at 0.064008 -3.993896 270)
			(unlocked yes)
			(layer "F.Fab")
			(hide yes)
			(effects
				(font
					(size 1.016 1.016)
					(thickness 0.1524)
				)
			)
		)
		(property "Device Type" "R402H16"
			(at 0.064008 -5.517896 270)
			(unlocked yes)
			(layer "F.Fab")
			(hide yes)
			(effects
				(font
					(size 1.016 1.016)
					(thickness 0.1524)
				)
			)
		)
		(duplicate_pad_numbers_are_jumpers no)
		(fp_line
			(start -0.508 -0.9398)
			(end -0.508 0.9398)
			(stroke
				(width 0.1524)
				(type default)
			)
			(layer "F.SilkS")
		)
		(fp_line
			(start 0.508 -0.9398)
			(end -0.508 -0.9398)
			(stroke
				(width 0.1524)
				(type default)
			)
			(layer "F.SilkS")
		)
		(fp_rect
			(start -0.508 0.9398)
			(end 0.508 -0.9398)
			(stroke
				(width 0)
				(type default)
			)
			(fill no)
			(layer "F.CrtYd")
		)
		(fp_rect
			(start -0.508 0.9398)
			(end 0.508 -0.9398)
			(stroke
				(width 0)
				(type default)
			)
			(fill no)
			(layer "F.Fab")
		)
		(pad "1" smd custom
			(at 0 -0.4445 270)
			(size 0.1397 0.1397)
			(layers "F.Cu" "F.Mask" "F.Paste")
			(net "P5VC")
			(options
				(clearance outline)
				(anchor circle)
			)
			(primitives
				(gr_poly
					(pts
						(arc
							(start -0.1778 -0.2794)
							(mid -0.249642 -0.249642)
							(end -0.2794 -0.1778)
						)
						(arc
							(start -0.2794 0.1778)
							(mid -0.249642 0.249642)
							(end -0.1778 0.2794)
						)
						(arc
							(start 0.1778 0.2794)
							(mid 0.249642 0.249642)
							(end 0.2794 0.1778)
						)
						(arc
							(start 0.2794 -0.1778)
							(mid 0.249642 -0.249642)
							(end 0.1778 -0.2794)
						)
					)
					(width 0)
					(fill yes)
				)
			)
		)
		(pad "2" smd custom
			(at 0 0.4445 270)
			(size 0.1397 0.1397)
			(layers "F.Cu" "F.Mask" "F.Paste")
			(net "DRIVE_ACT_14")
			(options
				(clearance outline)
				(anchor circle)
			)
			(primitives
				(gr_poly
					(pts
						(arc
							(start -0.1778 -0.2794)
							(mid -0.249642 -0.249642)
							(end -0.2794 -0.1778)
						)
						(arc
							(start -0.2794 0.1778)
							(mid -0.249642 0.249642)
							(end -0.1778 0.2794)
						)
						(arc
							(start 0.1778 0.2794)
							(mid 0.249642 0.249642)
							(end 0.2794 0.1778)
						)
						(arc
							(start 0.2794 -0.1778)
							(mid 0.249642 -0.249642)
							(end 0.1778 -0.2794)
						)
					)
					(width 0)
					(fill yes)
				)
			)
		)
	)
	(footprint ""
		(layer "F.Cu")
		(at 78.358746 -190.5127 90)
		(property "Reference" "R224"
			(at 0 0 90)
			(layer "F.SilkS")
			(hide yes)
			(effects
				(font
					(size 1.27 1.27)
				)
			)
		)
		(property "Value" "0R2J-2-GP"
			(at 0.064008 -3.993896 90)
			(unlocked yes)
			(layer "F.Fab")
			(hide yes)
			(effects
				(font
					(size 1.016 1.016)
					(thickness 0.1524)
				)
			)
		)
		(property "Device Type" "R402H16"
			(at 0.064008 -5.517896 90)
			(unlocked yes)
			(layer "F.Fab")
			(hide yes)
			(effects
				(font
					(size 1.016 1.016)
					(thickness 0.1524)
				)
			)
		)
		(duplicate_pad_numbers_are_jumpers no)
		(fp_line
			(start 0.508 -0.9398)
			(end -0.508 -0.9398)
			(stroke
				(width 0.1524)
				(type default)
			)
			(layer "F.SilkS")
		)
		(fp_line
			(start -0.508 -0.9398)
			(end -0.508 0.9398)
			(stroke
				(width 0.1524)
				(type default)
			)
			(layer "F.SilkS")
		)
		(fp_rect
			(start -0.508 0.9398)
			(end 0.508 -0.9398)
			(stroke
				(width 0)
				(type default)
			)
			(fill no)
			(layer "F.CrtYd")
		)
		(fp_rect
			(start -0.508 0.9398)
			(end 0.508 -0.9398)
			(stroke
				(width 0)
				(type default)
			)
			(fill no)
			(layer "F.Fab")
		)
		(pad "1" smd custom
			(at 0 -0.4445 90)
			(size 0.1397 0.1397)
			(layers "F.Cu" "F.Mask" "F.Paste")
			(net "SW_PWR_HDD8")
			(options
				(clearance outline)
				(anchor circle)
			)
			(primitives
				(gr_poly
					(pts
						(arc
							(start -0.1778 -0.2794)
							(mid -0.249642 -0.249642)
							(end -0.2794 -0.1778)
						)
						(arc
							(start -0.2794 0.1778)
							(mid -0.249642 0.249642)
							(end -0.1778 0.2794)
						)
						(arc
							(start 0.1778 0.2794)
							(mid 0.249642 0.249642)
							(end 0.2794 0.1778)
						)
						(arc
							(start 0.2794 -0.1778)
							(mid 0.249642 -0.249642)
							(end 0.1778 -0.2794)
						)
					)
					(width 0)
					(fill yes)
				)
			)
		)
		(pad "2" smd custom
			(at 0 0.4445 90)
			(size 0.1397 0.1397)
			(layers "F.Cu" "F.Mask" "F.Paste")
			(net "SW_PWR_R_HDD8")
			(options
				(clearance outline)
				(anchor circle)
			)
			(primitives
				(gr_poly
					(pts
						(arc
							(start -0.1778 -0.2794)
							(mid -0.249642 -0.249642)
							(end -0.2794 -0.1778)
						)
						(arc
							(start -0.2794 0.1778)
							(mid -0.249642 0.249642)
							(end -0.1778 0.2794)
						)
						(arc
							(start 0.1778 0.2794)
							(mid 0.249642 0.249642)
							(end 0.2794 0.1778)
						)
						(arc
							(start 0.2794 -0.1778)
							(mid 0.249642 -0.249642)
							(end 0.1778 -0.2794)
						)
					)
					(width 0)
					(fill yes)
				)
			)
		)
	)
	(footprint ""
		(layer "F.Cu")
		(at 30.733746 -298.9707 180)
		(property "Reference" "C226"
			(at 0 0 180)
			(layer "F.SilkS")
			(hide yes)
			(effects
				(font
					(size 1.27 1.27)
				)
			)
		)
		(property "Value" "SC10U25V6KX-1GP"
			(at -0.0762 -5.1308 180)
			(unlocked yes)
			(layer "F.Fab")
			(hide yes)
			(effects
				(font
					(size 1.016 1.016)
					(thickness 0.1524)
				)
			)
		)
		(property "Device Type" "C1206H71"
			(at -0.127 -6.6548 180)
			(unlocked yes)
			(layer "F.Fab")
			(hide yes)
			(effects
				(font
					(size 1.016 1.016)
					(thickness 0.1524)
				)
			)
		)
		(duplicate_pad_numbers_are_jumpers no)
		(fp_line
			(start 1.016 2.2352)
			(end -1.016 2.2352)
			(stroke
				(width 0.1524)
				(type default)
			)
			(layer "F.SilkS")
		)
		(fp_line
			(start 1.016 0.8382)
			(end 1.016 2.2352)
			(stroke
				(width 0.1524)
				(type default)
			)
			(layer "F.SilkS")
		)
		(fp_line
			(start 1.016 -2.2352)
			(end 1.016 -0.8382)
			(stroke
				(width 0.1524)
				(type default)
			)
			(layer "F.SilkS")
		)
		(fp_line
			(start -1.016 2.2352)
			(end -1.016 0.8382)
			(stroke
				(width 0.1524)
				(type default)
			)
			(layer "F.SilkS")
		)
		(fp_line
			(start -1.016 -0.8382)
			(end -1.016 -2.2352)
			(stroke
				(width 0.1524)
				(type default)
			)
			(layer "F.SilkS")
		)
		(fp_line
			(start -1.016 -2.2352)
			(end 1.016 -2.2352)
			(stroke
				(width 0.1524)
				(type default)
			)
			(layer "F.SilkS")
		)
		(fp_rect
			(start -1.0922 2.3114)
			(end 1.0922 -2.3114)
			(stroke
				(width 0)
				(type default)
			)
			(fill no)
			(layer "F.CrtYd")
		)
		(fp_poly
			(pts
				(xy 1.0922 -2.3114) (xy 1.0922 2.3114) (xy -1.0922 2.3114) (xy -1.0922 -2.3114)
			)
			(stroke
				(width 0)
				(type default)
			)
			(fill no)
			(layer "F.Fab")
		)
		(pad "1" smd rect
			(at 0 -1.397 180)
			(size 1.651 1.27)
			(layers "F.Cu" "F.Mask" "F.Paste")
			(net "P12V_HDD7")
		)
		(pad "2" smd rect
			(at 0 1.397 180)
			(size 1.651 1.27)
			(layers "F.Cu" "F.Mask" "F.Paste")
			(net "GND")
		)
	)
	(footprint ""
		(layer "F.Cu")
		(at 242.696746 -22.7457 90)
		(property "Reference" "PR1"
			(at 0 0 90)
			(layer "F.SilkS")
			(hide yes)
			(effects
				(font
					(size 1.27 1.27)
				)
			)
		)
		(property "Value" "0R3J-0-U-GP"
			(at -0.0254 -2.5146 90)
			(unlocked yes)
			(layer "F.Fab")
			(hide yes)
			(effects
				(font
					(size 1.016 1.016)
					(thickness 0.1524)
				)
			)
		)
		(property "Device Type" "R603H22"
			(at -0.0254 -4.0386 90)
			(unlocked yes)
			(layer "F.Fab")
			(hide yes)
			(effects
				(font
					(size 1.016 1.016)
					(thickness 0.1524)
				)
			)
		)
		(duplicate_pad_numbers_are_jumpers no)
		(fp_line
			(start 0.2032 0)
			(end 0.4826 0)
			(stroke
				(width 0.2032)
				(type default)
			)
			(layer "F.SilkS")
		)
		(fp_line
			(start -0.4826 0)
			(end -0.2032 0)
			(stroke
				(width 0.2032)
				(type default)
			)
			(layer "F.SilkS")
		)
		(fp_rect
			(start -0.5842 1.3335)
			(end 0.5842 -1.3335)
			(stroke
				(width 0)
				(type default)
			)
			(fill no)
			(layer "F.CrtYd")
		)
		(fp_rect
			(start -0.5842 1.3335)
			(end 0.5842 -1.3335)
			(stroke
				(width 0)
				(type default)
			)
			(fill no)
			(layer "F.Fab")
		)
		(pad "1" smd custom
			(at 0 -0.762 90)
			(size 0.2159 0.2159)
			(layers "F.Cu" "F.Mask" "F.Paste")
			(net "P5VA_12VIN")
			(options
				(clearance outline)
				(anchor circle)
			)
			(primitives
				(gr_poly
					(pts
						(arc
							(start -0.3302 -0.4318)
							(mid -0.402042 -0.402042)
							(end -0.4318 -0.3302)
						)
						(arc
							(start -0.4318 0.3302)
							(mid -0.402042 0.402042)
							(end -0.3302 0.4318)
						)
						(arc
							(start 0.3302 0.4318)
							(mid 0.402042 0.402042)
							(end 0.4318 0.3302)
						)
						(arc
							(start 0.4318 -0.3302)
							(mid 0.402042 -0.402042)
							(end 0.3302 -0.4318)
						)
					)
					(width 0)
					(fill yes)
				)
			)
		)
		(pad "2" smd custom
			(at 0 0.762 90)
			(size 0.2159 0.2159)
			(layers "F.Cu" "F.Mask" "F.Paste")
			(net "P5VA_VDD")
			(options
				(clearance outline)
				(anchor circle)
			)
			(primitives
				(gr_poly
					(pts
						(arc
							(start -0.3302 -0.4318)
							(mid -0.402042 -0.402042)
							(end -0.4318 -0.3302)
						)
						(arc
							(start -0.4318 0.3302)
							(mid -0.402042 0.402042)
							(end -0.3302 0.4318)
						)
						(arc
							(start 0.3302 0.4318)
							(mid 0.402042 0.402042)
							(end 0.4318 0.3302)
						)
						(arc
							(start 0.4318 -0.3302)
							(mid 0.402042 -0.402042)
							(end 0.3302 -0.4318)
						)
					)
					(width 0)
					(fill yes)
				)
			)
		)
	)
	(footprint ""
		(layer "F.Cu")
		(at 215.496902 -282.730702 180)
		(property "Reference" "C139"
			(at 0 0 180)
			(layer "F.SilkS")
			(hide yes)
			(effects
				(font
					(size 1.27 1.27)
				)
			)
		)
		(property "Value" "SC10U16V6KX-2GP"
			(at -0.0762 -5.1308 180)
			(unlocked yes)
			(layer "F.Fab")
			(hide yes)
			(effects
				(font
					(size 1.016 1.016)
					(thickness 0.1524)
				)
			)
		)
		(property "Device Type" "C1206H71"
			(at -0.127 -6.6548 180)
			(unlocked yes)
			(layer "F.Fab")
			(hide yes)
			(effects
				(font
					(size 1.016 1.016)
					(thickness 0.1524)
				)
			)
		)
		(duplicate_pad_numbers_are_jumpers no)
		(fp_line
			(start 1.016 2.2352)
			(end -1.016 2.2352)
			(stroke
				(width 0.1524)
				(type default)
			)
			(layer "F.SilkS")
		)
		(fp_line
			(start 1.016 0.8382)
			(end 1.016 2.2352)
			(stroke
				(width 0.1524)
				(type default)
			)
			(layer "F.SilkS")
		)
		(fp_line
			(start 1.016 -2.2352)
			(end 1.016 -0.8382)
			(stroke
				(width 0.1524)
				(type default)
			)
			(layer "F.SilkS")
		)
		(fp_line
			(start -1.016 2.2352)
			(end -1.016 0.8382)
			(stroke
				(width 0.1524)
				(type default)
			)
			(layer "F.SilkS")
		)
		(fp_line
			(start -1.016 -0.8382)
			(end -1.016 -2.2352)
			(stroke
				(width 0.1524)
				(type default)
			)
			(layer "F.SilkS")
		)
		(fp_line
			(start -1.016 -2.2352)
			(end 1.016 -2.2352)
			(stroke
				(width 0.1524)
				(type default)
			)
			(layer "F.SilkS")
		)
		(fp_rect
			(start -1.0922 2.3114)
			(end 1.0922 -2.3114)
			(stroke
				(width 0)
				(type default)
			)
			(fill no)
			(layer "F.CrtYd")
		)
		(fp_poly
			(pts
				(xy 1.0922 -2.3114) (xy 1.0922 2.3114) (xy -1.0922 2.3114) (xy -1.0922 -2.3114)
			)
			(stroke
				(width 0)
				(type default)
			)
			(fill no)
			(layer "F.Fab")
		)
		(pad "1" smd rect
			(at 0 -1.397 180)
			(size 1.651 1.27)
			(layers "F.Cu" "F.Mask" "F.Paste")
			(net "P5V_HDD2")
		)
		(pad "2" smd rect
			(at 0 1.397 180)
			(size 1.651 1.27)
			(layers "F.Cu" "F.Mask" "F.Paste")
			(net "GND")
		)
	)
	(footprint ""
		(layer "F.Cu")
		(at 14.604746 -53.7337 -90)
		(property "Reference" "R300"
			(at 0 0 270)
			(layer "F.SilkS")
			(hide yes)
			(effects
				(font
					(size 1.27 1.27)
				)
			)
		)
		(property "Value" "0R2J-2-GP"
			(at 0.064008 -3.993896 270)
			(unlocked yes)
			(layer "F.Fab")
			(hide yes)
			(effects
				(font
					(size 1.016 1.016)
					(thickness 0.1524)
				)
			)
		)
		(property "Device Type" "R402H16"
			(at 0.064008 -5.517896 270)
			(unlocked yes)
			(layer "F.Fab")
			(hide yes)
			(effects
				(font
					(size 1.016 1.016)
					(thickness 0.1524)
				)
			)
		)
		(duplicate_pad_numbers_are_jumpers no)
		(fp_line
			(start -0.508 -0.9398)
			(end -0.508 0.9398)
			(stroke
				(width 0.1524)
				(type default)
			)
			(layer "F.SilkS")
		)
		(fp_line
			(start 0.508 -0.9398)
			(end -0.508 -0.9398)
			(stroke
				(width 0.1524)
				(type default)
			)
			(layer "F.SilkS")
		)
		(fp_rect
			(start -0.508 0.9398)
			(end 0.508 -0.9398)
			(stroke
				(width 0)
				(type default)
			)
			(fill no)
			(layer "F.CrtYd")
		)
		(fp_rect
			(start -0.508 0.9398)
			(end 0.508 -0.9398)
			(stroke
				(width 0)
				(type default)
			)
			(fill no)
			(layer "F.Fab")
		)
		(pad "1" smd custom
			(at 0 -0.4445 270)
			(size 0.1397 0.1397)
			(layers "F.Cu" "F.Mask" "F.Paste")
			(net "FLT_NET_HDD14")
			(options
				(clearance outline)
				(anchor circle)
			)
			(primitives
				(gr_poly
					(pts
						(arc
							(start -0.1778 -0.2794)
							(mid -0.249642 -0.249642)
							(end -0.2794 -0.1778)
						)
						(arc
							(start -0.2794 0.1778)
							(mid -0.249642 0.249642)
							(end -0.1778 0.2794)
						)
						(arc
							(start 0.1778 0.2794)
							(mid 0.249642 0.249642)
							(end 0.2794 0.1778)
						)
						(arc
							(start 0.2794 -0.1778)
							(mid 0.249642 -0.249642)
							(end 0.1778 -0.2794)
						)
					)
					(width 0)
					(fill yes)
				)
			)
		)
		(pad "2" smd custom
			(at 0 0.4445 270)
			(size 0.1397 0.1397)
			(layers "F.Cu" "F.Mask" "F.Paste")
			(net "FLT_HDD14_DRIVE")
			(options
				(clearance outline)
				(anchor circle)
			)
			(primitives
				(gr_poly
					(pts
						(arc
							(start -0.1778 -0.2794)
							(mid -0.249642 -0.249642)
							(end -0.2794 -0.1778)
						)
						(arc
							(start -0.2794 0.1778)
							(mid -0.249642 0.249642)
							(end -0.1778 0.2794)
						)
						(arc
							(start 0.1778 0.2794)
							(mid 0.249642 0.249642)
							(end 0.2794 0.1778)
						)
						(arc
							(start 0.2794 -0.1778)
							(mid 0.249642 -0.249642)
							(end 0.1778 -0.2794)
						)
					)
					(width 0)
					(fill yes)
				)
			)
		)
	)
	(footprint ""
		(layer "F.Cu")
		(at 252.499622 -170.999912)
		(property "Reference" "H15"
			(at 0 0 0)
			(layer "F.SilkS")
			(hide yes)
			(effects
				(font
					(size 1.27 1.27)
				)
			)
		)
		(property "Value" "HOLE315R140"
			(at 0 -7.5692 0)
			(unlocked yes)
			(layer "F.Fab")
			(hide yes)
			(effects
				(font
					(size 1.016 1.016)
					(thickness 0.1524)
				)
			)
		)
		(property "Device Type" "HOLE315R140"
			(at 0 -9.0932 0)
			(unlocked yes)
			(layer "F.Fab")
			(hide yes)
			(effects
				(font
					(size 1.016 1.016)
					(thickness 0.1524)
				)
			)
		)
		(duplicate_pad_numbers_are_jumpers no)
		(fp_poly
			(pts
				(arc
					(start 4.3053 0)
					(mid -4.3053 0)
					(end 4.3053 0)
				)
			)
			(stroke
				(width 0)
				(type default)
			)
			(fill no)
			(layer "F.CrtYd")
		)
		(fp_poly
			(pts
				(arc
					(start 4.3053 0)
					(mid -4.3053 0)
					(end 4.3053 0)
				)
			)
			(stroke
				(width 0)
				(type default)
			)
			(fill no)
			(layer "F.Fab")
		)
		(pad "1" thru_hole circle
			(at 0.00127 0.00127)
			(size 8.001 8.001)
			(drill 3.556)
			(layers "*.Cu" "*.Mask")
			(remove_unused_layers no)
			(net "GND")
			(clearance -1.7145)
			(thermal_gap 0.3048)
			(padstack
				(mode front_inner_back)
				(layer "Inner"
					(shape circle)
					(size 3.9624 3.9624)
					(clearance 0.3048)
				)
				(layer "B.Cu"
					(shape circle)
					(size 8.001 8.001)
					(clearance -1.7145)
				)
			)
		)
	)
	(footprint ""
		(layer "F.Cu")
		(at 8.5852 -151.7396 90)
		(property "Reference" "R547"
			(at 0 0 90)
			(layer "F.SilkS")
			(hide yes)
			(effects
				(font
					(size 1.27 1.27)
				)
			)
		)
		(property "Value" "0R2J-2-GP"
			(at 0.064008 -3.993896 90)
			(unlocked yes)
			(layer "F.Fab")
			(hide yes)
			(effects
				(font
					(size 1.016 1.016)
					(thickness 0.1524)
				)
			)
		)
		(property "Device Type" "R402H16"
			(at 0.064008 -5.517896 90)
			(unlocked yes)
			(layer "F.Fab")
			(hide yes)
			(effects
				(font
					(size 1.016 1.016)
					(thickness 0.1524)
				)
			)
		)
		(duplicate_pad_numbers_are_jumpers no)
		(fp_line
			(start 0.508 -0.9398)
			(end -0.508 -0.9398)
			(stroke
				(width 0.1524)
				(type default)
			)
			(layer "F.SilkS")
		)
		(fp_line
			(start -0.508 -0.9398)
			(end -0.508 0.9398)
			(stroke
				(width 0.1524)
				(type default)
			)
			(layer "F.SilkS")
		)
		(fp_rect
			(start -0.508 0.9398)
			(end 0.508 -0.9398)
			(stroke
				(width 0)
				(type default)
			)
			(fill no)
			(layer "F.CrtYd")
		)
		(fp_rect
			(start -0.508 0.9398)
			(end 0.508 -0.9398)
			(stroke
				(width 0)
				(type default)
			)
			(fill no)
			(layer "F.Fab")
		)
		(pad "1" smd custom
			(at 0 -0.4445 90)
			(size 0.1397 0.1397)
			(layers "F.Cu" "F.Mask" "F.Paste")
			(net "I2C_C_SDA_DAMP_B")
			(options
				(clearance outline)
				(anchor circle)
			)
			(primitives
				(gr_poly
					(pts
						(arc
							(start -0.1778 -0.2794)
							(mid -0.249642 -0.249642)
							(end -0.2794 -0.1778)
						)
						(arc
							(start -0.2794 0.1778)
							(mid -0.249642 0.249642)
							(end -0.1778 0.2794)
						)
						(arc
							(start 0.1778 0.2794)
							(mid 0.249642 0.249642)
							(end 0.2794 0.1778)
						)
						(arc
							(start 0.2794 -0.1778)
							(mid 0.249642 -0.249642)
							(end 0.1778 -0.2794)
						)
					)
					(width 0)
					(fill yes)
				)
			)
		)
		(pad "2" smd custom
			(at 0 0.4445 90)
			(size 0.1397 0.1397)
			(layers "F.Cu" "F.Mask" "F.Paste")
			(net "I2C_C_SDA")
			(options
				(clearance outline)
				(anchor circle)
			)
			(primitives
				(gr_poly
					(pts
						(arc
							(start -0.1778 -0.2794)
							(mid -0.249642 -0.249642)
							(end -0.2794 -0.1778)
						)
						(arc
							(start -0.2794 0.1778)
							(mid -0.249642 0.249642)
							(end -0.1778 0.2794)
						)
						(arc
							(start 0.1778 0.2794)
							(mid 0.249642 0.249642)
							(end 0.2794 0.1778)
						)
						(arc
							(start 0.2794 -0.1778)
							(mid 0.249642 -0.249642)
							(end 0.1778 -0.2794)
						)
					)
					(width 0)
					(fill yes)
				)
			)
		)
	)
	(footprint ""
		(layer "F.Cu")
		(at 78.994 -94.488 180)
		(property "Reference" "C388"
			(at 0 0 180)
			(layer "F.SilkS")
			(hide yes)
			(effects
				(font
					(size 1.27 1.27)
				)
			)
		)
		(property "Value" "SCD033U25V2KX-GP"
			(at 1.1811 -2.7051 180)
			(unlocked yes)
			(layer "F.Fab")
			(hide yes)
			(effects
				(font
					(size 1.016 1.016)
					(thickness 0.1524)
				)
			)
		)
		(property "Device Type" "C402H22"
			(at 1.1811 -4.2291 180)
			(unlocked yes)
			(layer "F.Fab")
			(hide yes)
			(effects
				(font
					(size 1.016 1.016)
					(thickness 0.1524)
				)
			)
		)
		(duplicate_pad_numbers_are_jumpers no)
		(fp_rect
			(start -0.4318 0.9525)
			(end 0.4318 -0.9525)
			(stroke
				(width 0)
				(type default)
			)
			(fill no)
			(layer "F.CrtYd")
		)
		(fp_rect
			(start -0.4318 0.9525)
			(end 0.4318 -0.9525)
			(stroke
				(width 0)
				(type default)
			)
			(fill no)
			(layer "F.Fab")
		)
		(pad "1" smd custom
			(at 0 -0.4445 180)
			(size 0.1524 0.1524)
			(layers "F.Cu" "F.Mask" "F.Paste")
			(net "P12V")
			(options
				(clearance outline)
				(anchor circle)
			)
			(primitives
				(gr_poly
					(pts
						(arc
							(start 0.3048 -0.2032)
							(mid 0.275042 -0.275042)
							(end 0.2032 -0.3048)
						)
						(arc
							(start -0.2032 -0.3048)
							(mid -0.275042 -0.275042)
							(end -0.3048 -0.2032)
						)
						(arc
							(start -0.3048 0.2032)
							(mid -0.275042 0.275042)
							(end -0.2032 0.3048)
						)
						(arc
							(start 0.2032 0.3048)
							(mid 0.275042 0.275042)
							(end 0.3048 0.2032)
						)
					)
					(width 0)
					(fill yes)
				)
			)
		)
		(pad "2" smd custom
			(at 0 0.4445 180)
			(size 0.1524 0.1524)
			(layers "F.Cu" "F.Mask" "F.Paste")
			(net "SW_HDD9_N")
			(options
				(clearance outline)
				(anchor circle)
			)
			(primitives
				(gr_poly
					(pts
						(arc
							(start 0.3048 -0.2032)
							(mid 0.275042 -0.275042)
							(end 0.2032 -0.3048)
						)
						(arc
							(start -0.2032 -0.3048)
							(mid -0.275042 -0.275042)
							(end -0.3048 -0.2032)
						)
						(arc
							(start -0.3048 0.2032)
							(mid -0.275042 0.275042)
							(end -0.2032 0.3048)
						)
						(arc
							(start 0.2032 0.3048)
							(mid 0.275042 0.275042)
							(end 0.3048 0.2032)
						)
					)
					(width 0)
					(fill yes)
				)
			)
		)
	)
	(footprint ""
		(layer "F.Cu")
		(at 79.211932 -496.145312 90)
		(property "Reference" "R182"
			(at 0 0 90)
			(layer "F.SilkS")
			(hide yes)
			(effects
				(font
					(size 1.27 1.27)
				)
			)
		)
		(property "Value" "0R2J-2-GP"
			(at 0.064008 -3.993896 90)
			(unlocked yes)
			(layer "F.Fab")
			(hide yes)
			(effects
				(font
					(size 1.016 1.016)
					(thickness 0.1524)
				)
			)
		)
		(property "Device Type" "R402H16"
			(at 0.064008 -5.517896 90)
			(unlocked yes)
			(layer "F.Fab")
			(hide yes)
			(effects
				(font
					(size 1.016 1.016)
					(thickness 0.1524)
				)
			)
		)
		(duplicate_pad_numbers_are_jumpers no)
		(fp_line
			(start 0.508 -0.9398)
			(end -0.508 -0.9398)
			(stroke
				(width 0.1524)
				(type default)
			)
			(layer "F.SilkS")
		)
		(fp_line
			(start -0.508 -0.9398)
			(end -0.508 0.9398)
			(stroke
				(width 0.1524)
				(type default)
			)
			(layer "F.SilkS")
		)
		(fp_rect
			(start -0.508 0.9398)
			(end 0.508 -0.9398)
			(stroke
				(width 0)
				(type default)
			)
			(fill no)
			(layer "F.CrtYd")
		)
		(fp_rect
			(start -0.508 0.9398)
			(end 0.508 -0.9398)
			(stroke
				(width 0)
				(type default)
			)
			(fill no)
			(layer "F.Fab")
		)
		(pad "1" smd custom
			(at 0 -0.4445 90)
			(size 0.1397 0.1397)
			(layers "F.Cu" "F.Mask" "F.Paste")
			(net "SW_PWR_HDD5")
			(options
				(clearance outline)
				(anchor circle)
			)
			(primitives
				(gr_poly
					(pts
						(arc
							(start -0.1778 -0.2794)
							(mid -0.249642 -0.249642)
							(end -0.2794 -0.1778)
						)
						(arc
							(start -0.2794 0.1778)
							(mid -0.249642 0.249642)
							(end -0.1778 0.2794)
						)
						(arc
							(start 0.1778 0.2794)
							(mid 0.249642 0.249642)
							(end 0.2794 0.1778)
						)
						(arc
							(start 0.2794 -0.1778)
							(mid 0.249642 -0.249642)
							(end 0.1778 -0.2794)
						)
					)
					(width 0)
					(fill yes)
				)
			)
		)
		(pad "2" smd custom
			(at 0 0.4445 90)
			(size 0.1397 0.1397)
			(layers "F.Cu" "F.Mask" "F.Paste")
			(net "SW_PWR_R_HDD5")
			(options
				(clearance outline)
				(anchor circle)
			)
			(primitives
				(gr_poly
					(pts
						(arc
							(start -0.1778 -0.2794)
							(mid -0.249642 -0.249642)
							(end -0.2794 -0.1778)
						)
						(arc
							(start -0.2794 0.1778)
							(mid -0.249642 0.249642)
							(end -0.1778 0.2794)
						)
						(arc
							(start 0.1778 0.2794)
							(mid 0.249642 0.249642)
							(end 0.2794 0.1778)
						)
						(arc
							(start 0.2794 -0.1778)
							(mid 0.249642 -0.249642)
							(end 0.1778 -0.2794)
						)
					)
					(width 0)
					(fill yes)
				)
			)
		)
	)
	(footprint ""
		(layer "F.Cu")
		(at 177.685446 -460.536036 90)
		(property "Reference" "C363"
			(at 0 0 90)
			(layer "F.SilkS")
			(hide yes)
			(effects
				(font
					(size 1.27 1.27)
				)
			)
		)
		(property "Value" "SC1U10V2KX-1GP"
			(at 1.1811 -2.7051 90)
			(unlocked yes)
			(layer "F.Fab")
			(hide yes)
			(effects
				(font
					(size 1.016 1.016)
					(thickness 0.1524)
				)
			)
		)
		(property "Device Type" "C402H22"
			(at 1.1811 -4.2291 90)
			(unlocked yes)
			(layer "F.Fab")
			(hide yes)
			(effects
				(font
					(size 1.016 1.016)
					(thickness 0.1524)
				)
			)
		)
		(duplicate_pad_numbers_are_jumpers no)
		(fp_rect
			(start -0.4318 0.9525)
			(end 0.4318 -0.9525)
			(stroke
				(width 0)
				(type default)
			)
			(fill no)
			(layer "F.CrtYd")
		)
		(fp_rect
			(start -0.4318 0.9525)
			(end 0.4318 -0.9525)
			(stroke
				(width 0)
				(type default)
			)
			(fill no)
			(layer "F.Fab")
		)
		(pad "1" smd custom
			(at 0 -0.4445 90)
			(size 0.1524 0.1524)
			(layers "F.Cu" "F.Mask" "F.Paste")
			(net "P3V3")
			(options
				(clearance outline)
				(anchor circle)
			)
			(primitives
				(gr_poly
					(pts
						(arc
							(start 0.3048 -0.2032)
							(mid 0.275042 -0.275042)
							(end 0.2032 -0.3048)
						)
						(arc
							(start -0.2032 -0.3048)
							(mid -0.275042 -0.275042)
							(end -0.3048 -0.2032)
						)
						(arc
							(start -0.3048 0.2032)
							(mid -0.275042 0.275042)
							(end -0.2032 0.3048)
						)
						(arc
							(start 0.2032 0.3048)
							(mid 0.275042 0.275042)
							(end 0.3048 0.2032)
						)
					)
					(width 0)
					(fill yes)
				)
			)
		)
		(pad "2" smd custom
			(at 0 0.4445 90)
			(size 0.1524 0.1524)
			(layers "F.Cu" "F.Mask" "F.Paste")
			(net "GND")
			(options
				(clearance outline)
				(anchor circle)
			)
			(primitives
				(gr_poly
					(pts
						(arc
							(start 0.3048 -0.2032)
							(mid 0.275042 -0.275042)
							(end 0.2032 -0.3048)
						)
						(arc
							(start -0.2032 -0.3048)
							(mid -0.275042 -0.275042)
							(end -0.3048 -0.2032)
						)
						(arc
							(start -0.3048 0.2032)
							(mid -0.275042 0.275042)
							(end -0.2032 0.3048)
						)
						(arc
							(start 0.2032 0.3048)
							(mid 0.275042 0.275042)
							(end 0.3048 0.2032)
						)
					)
					(width 0)
					(fill yes)
				)
			)
		)
	)
	(footprint ""
		(layer "F.Cu")
		(at 58.927746 -25.6667 90)
		(property "Reference" "PR18"
			(at 0 0 90)
			(layer "F.SilkS")
			(hide yes)
			(effects
				(font
					(size 1.27 1.27)
				)
			)
		)
		(property "Value" "0R2J-2-GP"
			(at 0.064008 -3.993896 90)
			(unlocked yes)
			(layer "F.Fab")
			(hide yes)
			(effects
				(font
					(size 1.016 1.016)
					(thickness 0.1524)
				)
			)
		)
		(property "Device Type" "R402H16"
			(at 0.064008 -5.517896 90)
			(unlocked yes)
			(layer "F.Fab")
			(hide yes)
			(effects
				(font
					(size 1.016 1.016)
					(thickness 0.1524)
				)
			)
		)
		(duplicate_pad_numbers_are_jumpers no)
		(fp_line
			(start 0.508 -0.9398)
			(end -0.508 -0.9398)
			(stroke
				(width 0.1524)
				(type default)
			)
			(layer "F.SilkS")
		)
		(fp_line
			(start -0.508 -0.9398)
			(end -0.508 0.9398)
			(stroke
				(width 0.1524)
				(type default)
			)
			(layer "F.SilkS")
		)
		(fp_rect
			(start -0.508 0.9398)
			(end 0.508 -0.9398)
			(stroke
				(width 0)
				(type default)
			)
			(fill no)
			(layer "F.CrtYd")
		)
		(fp_rect
			(start -0.508 0.9398)
			(end 0.508 -0.9398)
			(stroke
				(width 0)
				(type default)
			)
			(fill no)
			(layer "F.Fab")
		)
		(pad "1" smd custom
			(at 0 -0.4445 90)
			(size 0.1397 0.1397)
			(layers "F.Cu" "F.Mask" "F.Paste")
			(net "P5VB_RF")
			(options
				(clearance outline)
				(anchor circle)
			)
			(primitives
				(gr_poly
					(pts
						(arc
							(start -0.1778 -0.2794)
							(mid -0.249642 -0.249642)
							(end -0.2794 -0.1778)
						)
						(arc
							(start -0.2794 0.1778)
							(mid -0.249642 0.249642)
							(end -0.1778 0.2794)
						)
						(arc
							(start 0.1778 0.2794)
							(mid 0.249642 0.249642)
							(end 0.2794 0.1778)
						)
						(arc
							(start 0.2794 -0.1778)
							(mid 0.249642 -0.249642)
							(end 0.1778 -0.2794)
						)
					)
					(width 0)
					(fill yes)
				)
			)
		)
		(pad "2" smd custom
			(at 0 0.4445 90)
			(size 0.1397 0.1397)
			(layers "F.Cu" "F.Mask" "F.Paste")
			(net "P5VB_AGND")
			(options
				(clearance outline)
				(anchor circle)
			)
			(primitives
				(gr_poly
					(pts
						(arc
							(start -0.1778 -0.2794)
							(mid -0.249642 -0.249642)
							(end -0.2794 -0.1778)
						)
						(arc
							(start -0.2794 0.1778)
							(mid -0.249642 0.249642)
							(end -0.1778 0.2794)
						)
						(arc
							(start 0.1778 0.2794)
							(mid 0.249642 0.249642)
							(end 0.2794 0.1778)
						)
						(arc
							(start 0.2794 -0.1778)
							(mid 0.249642 -0.249642)
							(end 0.1778 -0.2794)
						)
					)
					(width 0)
					(fill yes)
				)
			)
		)
	)
	(footprint ""
		(layer "F.Cu")
		(at 21.082 -393.7)
		(property "Reference" "R509"
			(at 0 0 0)
			(layer "F.SilkS")
			(hide yes)
			(effects
				(font
					(size 1.27 1.27)
				)
			)
		)
		(property "Value" "0R2J-2-GP"
			(at 0.064008 -3.993896 0)
			(unlocked yes)
			(layer "F.Fab")
			(hide yes)
			(effects
				(font
					(size 1.016 1.016)
					(thickness 0.1524)
				)
			)
		)
		(property "Device Type" "R402H16"
			(at 0.064008 -5.517896 0)
			(unlocked yes)
			(layer "F.Fab")
			(hide yes)
			(effects
				(font
					(size 1.016 1.016)
					(thickness 0.1524)
				)
			)
		)
		(duplicate_pad_numbers_are_jumpers no)
		(fp_line
			(start -0.508 -0.9398)
			(end -0.508 0.9398)
			(stroke
				(width 0.1524)
				(type default)
			)
			(layer "F.SilkS")
		)
		(fp_line
			(start 0.508 -0.9398)
			(end -0.508 -0.9398)
			(stroke
				(width 0.1524)
				(type default)
			)
			(layer "F.SilkS")
		)
		(fp_rect
			(start -0.508 0.9398)
			(end 0.508 -0.9398)
			(stroke
				(width 0)
				(type default)
			)
			(fill no)
			(layer "F.CrtYd")
		)
		(fp_rect
			(start -0.508 0.9398)
			(end 0.508 -0.9398)
			(stroke
				(width 0)
				(type default)
			)
			(fill no)
			(layer "F.Fab")
		)
		(pad "1" smd custom
			(at 0 -0.4445)
			(size 0.1397 0.1397)
			(layers "F.Cu" "F.Mask" "F.Paste")
			(net "I2C_D_SDA_DAMP_A")
			(options
				(clearance outline)
				(anchor circle)
			)
			(primitives
				(gr_poly
					(pts
						(arc
							(start -0.1778 -0.2794)
							(mid -0.249642 -0.249642)
							(end -0.2794 -0.1778)
						)
						(arc
							(start -0.2794 0.1778)
							(mid -0.249642 0.249642)
							(end -0.1778 0.2794)
						)
						(arc
							(start 0.1778 0.2794)
							(mid 0.249642 0.249642)
							(end 0.2794 0.1778)
						)
						(arc
							(start 0.2794 -0.1778)
							(mid 0.249642 -0.249642)
							(end 0.1778 -0.2794)
						)
					)
					(width 0)
					(fill yes)
				)
			)
		)
		(pad "2" smd custom
			(at 0 0.4445)
			(size 0.1397 0.1397)
			(layers "F.Cu" "F.Mask" "F.Paste")
			(net "I2C_D_SDA")
			(options
				(clearance outline)
				(anchor circle)
			)
			(primitives
				(gr_poly
					(pts
						(arc
							(start -0.1778 -0.2794)
							(mid -0.249642 -0.249642)
							(end -0.2794 -0.1778)
						)
						(arc
							(start -0.2794 0.1778)
							(mid -0.249642 0.249642)
							(end -0.1778 0.2794)
						)
						(arc
							(start 0.1778 0.2794)
							(mid 0.249642 0.249642)
							(end 0.2794 0.1778)
						)
						(arc
							(start 0.2794 -0.1778)
							(mid 0.249642 -0.249642)
							(end 0.1778 -0.2794)
						)
					)
					(width 0)
					(fill yes)
				)
			)
		)
	)
	(footprint ""
		(layer "F.Cu")
		(at 45.275246 -248.0437 90)
		(property "Reference" "R198"
			(at 0 0 90)
			(layer "F.SilkS")
			(hide yes)
			(effects
				(font
					(size 1.27 1.27)
				)
			)
		)
		(property "Value" "10KR2F-2-GP"
			(at 0.064008 -3.993896 90)
			(unlocked yes)
			(layer "F.Fab")
			(hide yes)
			(effects
				(font
					(size 1.016 1.016)
					(thickness 0.1524)
				)
			)
		)
		(property "Device Type" "R402H16"
			(at 0.064008 -5.517896 90)
			(unlocked yes)
			(layer "F.Fab")
			(hide yes)
			(effects
				(font
					(size 1.016 1.016)
					(thickness 0.1524)
				)
			)
		)
		(duplicate_pad_numbers_are_jumpers no)
		(fp_line
			(start 0.508 -0.9398)
			(end -0.508 -0.9398)
			(stroke
				(width 0.1524)
				(type default)
			)
			(layer "F.SilkS")
		)
		(fp_line
			(start -0.508 -0.9398)
			(end -0.508 0.9398)
			(stroke
				(width 0.1524)
				(type default)
			)
			(layer "F.SilkS")
		)
		(fp_rect
			(start -0.508 0.9398)
			(end 0.508 -0.9398)
			(stroke
				(width 0)
				(type default)
			)
			(fill no)
			(layer "F.CrtYd")
		)
		(fp_rect
			(start -0.508 0.9398)
			(end 0.508 -0.9398)
			(stroke
				(width 0)
				(type default)
			)
			(fill no)
			(layer "F.Fab")
		)
		(pad "1" smd custom
			(at 0 -0.4445 90)
			(size 0.1397 0.1397)
			(layers "F.Cu" "F.Mask" "F.Paste")
			(net "P5VB")
			(options
				(clearance outline)
				(anchor circle)
			)
			(primitives
				(gr_poly
					(pts
						(arc
							(start -0.1778 -0.2794)
							(mid -0.249642 -0.249642)
							(end -0.2794 -0.1778)
						)
						(arc
							(start -0.2794 0.1778)
							(mid -0.249642 0.249642)
							(end -0.1778 0.2794)
						)
						(arc
							(start 0.1778 0.2794)
							(mid 0.249642 0.249642)
							(end 0.2794 0.1778)
						)
						(arc
							(start 0.2794 -0.1778)
							(mid 0.249642 -0.249642)
							(end 0.1778 -0.2794)
						)
					)
					(width 0)
					(fill yes)
				)
			)
		)
		(pad "2" smd custom
			(at 0 0.4445 90)
			(size 0.1397 0.1397)
			(layers "F.Cu" "F.Mask" "F.Paste")
			(net "DRIVE_ACT_7")
			(options
				(clearance outline)
				(anchor circle)
			)
			(primitives
				(gr_poly
					(pts
						(arc
							(start -0.1778 -0.2794)
							(mid -0.249642 -0.249642)
							(end -0.2794 -0.1778)
						)
						(arc
							(start -0.2794 0.1778)
							(mid -0.249642 0.249642)
							(end -0.1778 0.2794)
						)
						(arc
							(start 0.1778 0.2794)
							(mid 0.249642 0.249642)
							(end 0.2794 0.1778)
						)
						(arc
							(start 0.2794 -0.1778)
							(mid 0.249642 -0.249642)
							(end 0.1778 -0.2794)
						)
					)
					(width 0)
					(fill yes)
				)
			)
		)
	)
	(footprint ""
		(layer "F.Cu")
		(at 5.969 -30.353 -90)
		(property "Reference" "C157"
			(at 0 0 270)
			(layer "F.SilkS")
			(hide yes)
			(effects
				(font
					(size 1.27 1.27)
				)
			)
		)
		(property "Value" "SC1U25V3KX-1-GP"
			(at 0 -2.8194 270)
			(unlocked yes)
			(layer "F.Fab")
			(hide yes)
			(effects
				(font
					(size 1.016 1.016)
					(thickness 0.1524)
				)
			)
		)
		(property "Device Type" "C603H36"
			(at 0 -4.3434 270)
			(unlocked yes)
			(layer "F.Fab")
			(hide yes)
			(effects
				(font
					(size 1.016 1.016)
					(thickness 0.1524)
				)
			)
		)
		(duplicate_pad_numbers_are_jumpers no)
		(fp_line
			(start 0.508 0)
			(end -0.508 0)
			(stroke
				(width 0.2032)
				(type default)
			)
			(layer "F.SilkS")
		)
		(fp_rect
			(start -0.5842 1.3335)
			(end 0.5842 -1.3335)
			(stroke
				(width 0)
				(type default)
			)
			(fill no)
			(layer "F.CrtYd")
		)
		(fp_rect
			(start -0.5842 1.3335)
			(end 0.5842 -1.3335)
			(stroke
				(width 0)
				(type default)
			)
			(fill no)
			(layer "F.Fab")
		)
		(pad "1" smd custom
			(at 0 -0.762 270)
			(size 0.2159 0.2159)
			(layers "F.Cu" "F.Mask" "F.Paste")
			(net "P12V")
			(options
				(clearance outline)
				(anchor circle)
			)
			(primitives
				(gr_poly
					(pts
						(arc
							(start -0.3302 -0.4318)
							(mid -0.402042 -0.402042)
							(end -0.4318 -0.3302)
						)
						(arc
							(start -0.4318 0.3302)
							(mid -0.402042 0.402042)
							(end -0.3302 0.4318)
						)
						(arc
							(start 0.3302 0.4318)
							(mid 0.402042 0.402042)
							(end 0.4318 0.3302)
						)
						(arc
							(start 0.4318 -0.3302)
							(mid 0.402042 -0.402042)
							(end 0.3302 -0.4318)
						)
					)
					(width 0)
					(fill yes)
				)
			)
		)
		(pad "2" smd custom
			(at 0 0.762 270)
			(size 0.2159 0.2159)
			(layers "F.Cu" "F.Mask" "F.Paste")
			(net "GND")
			(options
				(clearance outline)
				(anchor circle)
			)
			(primitives
				(gr_poly
					(pts
						(arc
							(start -0.3302 -0.4318)
							(mid -0.402042 -0.402042)
							(end -0.4318 -0.3302)
						)
						(arc
							(start -0.4318 0.3302)
							(mid -0.402042 0.402042)
							(end -0.3302 0.4318)
						)
						(arc
							(start 0.3302 0.4318)
							(mid 0.402042 0.402042)
							(end 0.4318 0.3302)
						)
						(arc
							(start 0.4318 -0.3302)
							(mid 0.402042 -0.402042)
							(end 0.3302 -0.4318)
						)
					)
					(width 0)
					(fill yes)
				)
			)
		)
	)
	(footprint ""
		(layer "F.Cu")
		(at 77.216 -23.0378 90)
		(property "Reference" "R404"
			(at 0 0 90)
			(layer "F.SilkS")
			(hide yes)
			(effects
				(font
					(size 1.27 1.27)
				)
			)
		)
		(property "Value" "0R2J-2-GP"
			(at 0.064008 -3.993896 90)
			(unlocked yes)
			(layer "F.Fab")
			(hide yes)
			(effects
				(font
					(size 1.016 1.016)
					(thickness 0.1524)
				)
			)
		)
		(property "Device Type" "R402H16"
			(at 0.064008 -5.517896 90)
			(unlocked yes)
			(layer "F.Fab")
			(hide yes)
			(effects
				(font
					(size 1.016 1.016)
					(thickness 0.1524)
				)
			)
		)
		(duplicate_pad_numbers_are_jumpers no)
		(fp_line
			(start 0.508 -0.9398)
			(end -0.508 -0.9398)
			(stroke
				(width 0.1524)
				(type default)
			)
			(layer "F.SilkS")
		)
		(fp_line
			(start -0.508 -0.9398)
			(end -0.508 0.9398)
			(stroke
				(width 0.1524)
				(type default)
			)
			(layer "F.SilkS")
		)
		(fp_rect
			(start -0.508 0.9398)
			(end 0.508 -0.9398)
			(stroke
				(width 0)
				(type default)
			)
			(fill no)
			(layer "F.CrtYd")
		)
		(fp_rect
			(start -0.508 0.9398)
			(end 0.508 -0.9398)
			(stroke
				(width 0)
				(type default)
			)
			(fill no)
			(layer "F.Fab")
		)
		(pad "1" smd custom
			(at 0 -0.4445 90)
			(size 0.1397 0.1397)
			(layers "F.Cu" "F.Mask" "F.Paste")
			(net "HDD_PRSNT_NET14")
			(options
				(clearance outline)
				(anchor circle)
			)
			(primitives
				(gr_poly
					(pts
						(arc
							(start -0.1778 -0.2794)
							(mid -0.249642 -0.249642)
							(end -0.2794 -0.1778)
						)
						(arc
							(start -0.2794 0.1778)
							(mid -0.249642 0.249642)
							(end -0.1778 0.2794)
						)
						(arc
							(start 0.1778 0.2794)
							(mid 0.249642 0.249642)
							(end 0.2794 0.1778)
						)
						(arc
							(start 0.2794 -0.1778)
							(mid 0.249642 -0.249642)
							(end 0.1778 -0.2794)
						)
					)
					(width 0)
					(fill yes)
				)
			)
		)
		(pad "2" smd custom
			(at 0 0.4445 90)
			(size 0.1397 0.1397)
			(layers "F.Cu" "F.Mask" "F.Paste")
			(net "HDD14_LED_B")
			(options
				(clearance outline)
				(anchor circle)
			)
			(primitives
				(gr_poly
					(pts
						(arc
							(start -0.1778 -0.2794)
							(mid -0.249642 -0.249642)
							(end -0.2794 -0.1778)
						)
						(arc
							(start -0.2794 0.1778)
							(mid -0.249642 0.249642)
							(end -0.1778 0.2794)
						)
						(arc
							(start 0.1778 0.2794)
							(mid 0.249642 0.249642)
							(end 0.2794 0.1778)
						)
						(arc
							(start 0.2794 -0.1778)
							(mid 0.249642 -0.249642)
							(end 0.1778 -0.2794)
						)
					)
					(width 0)
					(fill yes)
				)
			)
		)
	)
	(footprint ""
		(layer "F.Cu")
		(at 215.273382 -291.310568 180)
		(property "Reference" "C144"
			(at 0 0 180)
			(layer "F.SilkS")
			(hide yes)
			(effects
				(font
					(size 1.27 1.27)
				)
			)
		)
		(property "Value" "SC10U25V6KX-1GP"
			(at -0.0762 -5.1308 180)
			(unlocked yes)
			(layer "F.Fab")
			(hide yes)
			(effects
				(font
					(size 1.016 1.016)
					(thickness 0.1524)
				)
			)
		)
		(property "Device Type" "C1206H71"
			(at -0.127 -6.6548 180)
			(unlocked yes)
			(layer "F.Fab")
			(hide yes)
			(effects
				(font
					(size 1.016 1.016)
					(thickness 0.1524)
				)
			)
		)
		(duplicate_pad_numbers_are_jumpers no)
		(fp_line
			(start 1.016 2.2352)
			(end -1.016 2.2352)
			(stroke
				(width 0.1524)
				(type default)
			)
			(layer "F.SilkS")
		)
		(fp_line
			(start 1.016 0.8382)
			(end 1.016 2.2352)
			(stroke
				(width 0.1524)
				(type default)
			)
			(layer "F.SilkS")
		)
		(fp_line
			(start 1.016 -2.2352)
			(end 1.016 -0.8382)
			(stroke
				(width 0.1524)
				(type default)
			)
			(layer "F.SilkS")
		)
		(fp_line
			(start -1.016 2.2352)
			(end -1.016 0.8382)
			(stroke
				(width 0.1524)
				(type default)
			)
			(layer "F.SilkS")
		)
		(fp_line
			(start -1.016 -0.8382)
			(end -1.016 -2.2352)
			(stroke
				(width 0.1524)
				(type default)
			)
			(layer "F.SilkS")
		)
		(fp_line
			(start -1.016 -2.2352)
			(end 1.016 -2.2352)
			(stroke
				(width 0.1524)
				(type default)
			)
			(layer "F.SilkS")
		)
		(fp_rect
			(start -1.0922 2.3114)
			(end 1.0922 -2.3114)
			(stroke
				(width 0)
				(type default)
			)
			(fill no)
			(layer "F.CrtYd")
		)
		(fp_poly
			(pts
				(xy 1.0922 -2.3114) (xy 1.0922 2.3114) (xy -1.0922 2.3114) (xy -1.0922 -2.3114)
			)
			(stroke
				(width 0)
				(type default)
			)
			(fill no)
			(layer "F.Fab")
		)
		(pad "1" smd rect
			(at 0 -1.397 180)
			(size 1.651 1.27)
			(layers "F.Cu" "F.Mask" "F.Paste")
			(net "P12V_HDD2")
		)
		(pad "2" smd rect
			(at 0 1.397 180)
			(size 1.651 1.27)
			(layers "F.Cu" "F.Mask" "F.Paste")
			(net "GND")
		)
	)
	(footprint ""
		(layer "F.Cu")
		(at 58.674 -478.0788)
		(property "Reference" "R375"
			(at 0 0 0)
			(layer "F.SilkS")
			(hide yes)
			(effects
				(font
					(size 1.27 1.27)
				)
			)
		)
		(property "Value" "10KR2F-2-GP"
			(at 0.064008 -3.993896 0)
			(unlocked yes)
			(layer "F.Fab")
			(hide yes)
			(effects
				(font
					(size 1.016 1.016)
					(thickness 0.1524)
				)
			)
		)
		(property "Device Type" "R402H16"
			(at 0.064008 -5.517896 0)
			(unlocked yes)
			(layer "F.Fab")
			(hide yes)
			(effects
				(font
					(size 1.016 1.016)
					(thickness 0.1524)
				)
			)
		)
		(duplicate_pad_numbers_are_jumpers no)
		(fp_line
			(start -0.508 -0.9398)
			(end -0.508 0.9398)
			(stroke
				(width 0.1524)
				(type default)
			)
			(layer "F.SilkS")
		)
		(fp_line
			(start 0.508 -0.9398)
			(end -0.508 -0.9398)
			(stroke
				(width 0.1524)
				(type default)
			)
			(layer "F.SilkS")
		)
		(fp_rect
			(start -0.508 0.9398)
			(end 0.508 -0.9398)
			(stroke
				(width 0)
				(type default)
			)
			(fill no)
			(layer "F.CrtYd")
		)
		(fp_rect
			(start -0.508 0.9398)
			(end 0.508 -0.9398)
			(stroke
				(width 0)
				(type default)
			)
			(fill no)
			(layer "F.Fab")
		)
		(pad "1" smd custom
			(at 0 -0.4445)
			(size 0.1397 0.1397)
			(layers "F.Cu" "F.Mask" "F.Paste")
			(net "P12V")
			(options
				(clearance outline)
				(anchor circle)
			)
			(primitives
				(gr_poly
					(pts
						(arc
							(start -0.1778 -0.2794)
							(mid -0.249642 -0.249642)
							(end -0.2794 -0.1778)
						)
						(arc
							(start -0.2794 0.1778)
							(mid -0.249642 0.249642)
							(end -0.1778 0.2794)
						)
						(arc
							(start 0.1778 0.2794)
							(mid 0.249642 0.249642)
							(end 0.2794 0.1778)
						)
						(arc
							(start 0.2794 -0.1778)
							(mid 0.249642 -0.249642)
							(end 0.1778 -0.2794)
						)
					)
					(width 0)
					(fill yes)
				)
			)
		)
		(pad "2" smd custom
			(at 0 0.4445)
			(size 0.1397 0.1397)
			(layers "F.Cu" "F.Mask" "F.Paste")
			(net "HDD5_LED_G")
			(options
				(clearance outline)
				(anchor circle)
			)
			(primitives
				(gr_poly
					(pts
						(arc
							(start -0.1778 -0.2794)
							(mid -0.249642 -0.249642)
							(end -0.2794 -0.1778)
						)
						(arc
							(start -0.2794 0.1778)
							(mid -0.249642 0.249642)
							(end -0.1778 0.2794)
						)
						(arc
							(start 0.1778 0.2794)
							(mid 0.249642 0.249642)
							(end 0.2794 0.1778)
						)
						(arc
							(start 0.2794 -0.1778)
							(mid 0.249642 -0.249642)
							(end 0.1778 -0.2794)
						)
					)
					(width 0)
					(fill yes)
				)
			)
		)
	)
	(footprint ""
		(layer "F.Cu")
		(at 227.837746 -33.2867 180)
		(property "Reference" "PC12"
			(at 0 0 180)
			(layer "F.SilkS")
			(hide yes)
			(effects
				(font
					(size 1.27 1.27)
				)
			)
		)
		(property "Value" "SC10U16V6KX-2GP"
			(at -0.0762 -5.1308 180)
			(unlocked yes)
			(layer "F.Fab")
			(hide yes)
			(effects
				(font
					(size 1.016 1.016)
					(thickness 0.1524)
				)
			)
		)
		(property "Device Type" "C1206H71"
			(at -0.127 -6.6548 180)
			(unlocked yes)
			(layer "F.Fab")
			(hide yes)
			(effects
				(font
					(size 1.016 1.016)
					(thickness 0.1524)
				)
			)
		)
		(duplicate_pad_numbers_are_jumpers no)
		(fp_line
			(start 1.016 2.2352)
			(end -1.016 2.2352)
			(stroke
				(width 0.1524)
				(type default)
			)
			(layer "F.SilkS")
		)
		(fp_line
			(start 1.016 0.8382)
			(end 1.016 2.2352)
			(stroke
				(width 0.1524)
				(type default)
			)
			(layer "F.SilkS")
		)
		(fp_line
			(start 1.016 -2.2352)
			(end 1.016 -0.8382)
			(stroke
				(width 0.1524)
				(type default)
			)
			(layer "F.SilkS")
		)
		(fp_line
			(start -1.016 2.2352)
			(end -1.016 0.8382)
			(stroke
				(width 0.1524)
				(type default)
			)
			(layer "F.SilkS")
		)
		(fp_line
			(start -1.016 -0.8382)
			(end -1.016 -2.2352)
			(stroke
				(width 0.1524)
				(type default)
			)
			(layer "F.SilkS")
		)
		(fp_line
			(start -1.016 -2.2352)
			(end 1.016 -2.2352)
			(stroke
				(width 0.1524)
				(type default)
			)
			(layer "F.SilkS")
		)
		(fp_rect
			(start -1.0922 2.3114)
			(end 1.0922 -2.3114)
			(stroke
				(width 0)
				(type default)
			)
			(fill no)
			(layer "F.CrtYd")
		)
		(fp_poly
			(pts
				(xy 1.0922 -2.3114) (xy 1.0922 2.3114) (xy -1.0922 2.3114) (xy -1.0922 -2.3114)
			)
			(stroke
				(width 0)
				(type default)
			)
			(fill no)
			(layer "F.Fab")
		)
		(pad "1" smd rect
			(at 0 -1.397 180)
			(size 1.651 1.27)
			(layers "F.Cu" "F.Mask" "F.Paste")
			(net "P5VA")
		)
		(pad "2" smd rect
			(at 0 1.397 180)
			(size 1.651 1.27)
			(layers "F.Cu" "F.Mask" "F.Paste")
			(net "GND")
		)
	)
	(footprint ""
		(layer "F.Cu")
		(at 99.313746 -13.6017 90)
		(property "Reference" "U45"
			(at 0 0 90)
			(layer "F.SilkS")
			(hide yes)
			(effects
				(font
					(size 1.27 1.27)
				)
			)
		)
		(property "Value" "74LVC1G08GW-1-GP"
			(at -2.3368 -8.6868 90)
			(unlocked yes)
			(layer "F.Fab")
			(hide yes)
			(effects
				(font
					(size 1.016 1.016)
					(thickness 0.1524)
				)
			)
		)
		(property "Device Type" "SC70-5H44"
			(at -2.3114 -10.414 90)
			(unlocked yes)
			(layer "F.Fab")
			(hide yes)
			(effects
				(font
					(size 1.016 1.016)
					(thickness 0.1524)
				)
			)
		)
		(duplicate_pad_numbers_are_jumpers no)
		(fp_line
			(start 1.3843 -1.8034)
			(end 1.3843 -1.1176)
			(stroke
				(width 0.3302)
				(type default)
			)
			(layer "F.SilkS")
		)
		(fp_line
			(start 0.6604 -1.8034)
			(end 1.3843 -1.8034)
			(stroke
				(width 0.3302)
				(type default)
			)
			(layer "F.SilkS")
		)
		(fp_line
			(start 1.27 -1.7018)
			(end 1.27 1.7018)
			(stroke
				(width 0.1524)
				(type default)
			)
			(layer "F.SilkS")
		)
		(fp_line
			(start -1.27 -1.7018)
			(end 1.27 -1.7018)
			(stroke
				(width 0.1524)
				(type default)
			)
			(layer "F.SilkS")
		)
		(fp_line
			(start 1.27 1.7018)
			(end -1.27 1.7018)
			(stroke
				(width 0.1524)
				(type default)
			)
			(layer "F.SilkS")
		)
		(fp_line
			(start -1.27 1.7018)
			(end -1.27 -1.7018)
			(stroke
				(width 0.1524)
				(type default)
			)
			(layer "F.SilkS")
		)
		(fp_rect
			(start -1.524 1.9558)
			(end 1.524 -1.9558)
			(stroke
				(width 0)
				(type default)
			)
			(fill no)
			(layer "F.CrtYd")
		)
		(fp_poly
			(pts
				(xy -1.524 -1.9558) (xy 1.524 -1.9558) (xy 1.524 1.9558) (xy -1.524 1.9558)
			)
			(stroke
				(width 0)
				(type default)
			)
			(fill no)
			(layer "F.Fab")
		)
		(pad "1" smd rect
			(at 0.65024 -0.8255 90)
			(size 0.4064 1.2192)
			(layers "F.Cu" "F.Mask" "F.Paste")
			(net "SAS_EXP_B_PWR14")
		)
		(pad "2" smd rect
			(at 0 -0.8255 90)
			(size 0.4064 1.2192)
			(layers "F.Cu" "F.Mask" "F.Paste")
			(net "SAS_EXP_A_PWR14")
		)
		(pad "3" smd rect
			(at -0.65024 -0.8255 90)
			(size 0.4064 1.2192)
			(layers "F.Cu" "F.Mask" "F.Paste")
			(net "GND")
		)
		(pad "4" smd rect
			(at -0.65024 0.8255 90)
			(size 0.4064 1.2192)
			(layers "F.Cu" "F.Mask" "F.Paste")
			(net "DRIVE_PWR14")
		)
		(pad "5" smd rect
			(at 0.65024 0.8255 90)
			(size 0.4064 1.2192)
			(layers "F.Cu" "F.Mask" "F.Paste")
			(net "P3V3")
		)
	)
	(footprint ""
		(layer "F.Cu")
		(at 176.161446 -459.139036)
		(property "Reference" "C362"
			(at 0 0 0)
			(layer "F.SilkS")
			(hide yes)
			(effects
				(font
					(size 1.27 1.27)
				)
			)
		)
		(property "Value" "SCD1U16V2KX-3GP"
			(at 1.1811 -2.7051 0)
			(unlocked yes)
			(layer "F.Fab")
			(hide yes)
			(effects
				(font
					(size 1.016 1.016)
					(thickness 0.1524)
				)
			)
		)
		(property "Device Type" "C402H22"
			(at 1.1811 -4.2291 0)
			(unlocked yes)
			(layer "F.Fab")
			(hide yes)
			(effects
				(font
					(size 1.016 1.016)
					(thickness 0.1524)
				)
			)
		)
		(duplicate_pad_numbers_are_jumpers no)
		(fp_rect
			(start -0.4318 0.9525)
			(end 0.4318 -0.9525)
			(stroke
				(width 0)
				(type default)
			)
			(fill no)
			(layer "F.CrtYd")
		)
		(fp_rect
			(start -0.4318 0.9525)
			(end 0.4318 -0.9525)
			(stroke
				(width 0)
				(type default)
			)
			(fill no)
			(layer "F.Fab")
		)
		(pad "1" smd custom
			(at 0 -0.4445)
			(size 0.1524 0.1524)
			(layers "F.Cu" "F.Mask" "F.Paste")
			(net "P12V_SENSE")
			(options
				(clearance outline)
				(anchor circle)
			)
			(primitives
				(gr_poly
					(pts
						(arc
							(start 0.3048 -0.2032)
							(mid 0.275042 -0.275042)
							(end 0.2032 -0.3048)
						)
						(arc
							(start -0.2032 -0.3048)
							(mid -0.275042 -0.275042)
							(end -0.3048 -0.2032)
						)
						(arc
							(start -0.3048 0.2032)
							(mid -0.275042 0.275042)
							(end -0.2032 0.3048)
						)
						(arc
							(start 0.2032 0.3048)
							(mid 0.275042 0.275042)
							(end 0.3048 0.2032)
						)
					)
					(width 0)
					(fill yes)
				)
			)
		)
		(pad "2" smd custom
			(at 0 0.4445)
			(size 0.1524 0.1524)
			(layers "F.Cu" "F.Mask" "F.Paste")
			(net "GND")
			(options
				(clearance outline)
				(anchor circle)
			)
			(primitives
				(gr_poly
					(pts
						(arc
							(start 0.3048 -0.2032)
							(mid 0.275042 -0.275042)
							(end 0.2032 -0.3048)
						)
						(arc
							(start -0.2032 -0.3048)
							(mid -0.275042 -0.275042)
							(end -0.3048 -0.2032)
						)
						(arc
							(start -0.3048 0.2032)
							(mid -0.275042 0.275042)
							(end -0.2032 0.3048)
						)
						(arc
							(start 0.2032 0.3048)
							(mid 0.275042 0.275042)
							(end 0.3048 0.2032)
						)
					)
					(width 0)
					(fill yes)
				)
			)
		)
	)
	(footprint ""
		(layer "F.Cu")
		(at 25.527 -280.797 180)
		(property "Reference" "R415"
			(at 0 0 180)
			(layer "F.SilkS")
			(hide yes)
			(effects
				(font
					(size 1.27 1.27)
				)
			)
		)
		(property "Value" "0R2J-2-GP"
			(at 0.064008 -3.993896 180)
			(unlocked yes)
			(layer "F.Fab")
			(hide yes)
			(effects
				(font
					(size 1.016 1.016)
					(thickness 0.1524)
				)
			)
		)
		(property "Device Type" "R402H16"
			(at 0.064008 -5.517896 180)
			(unlocked yes)
			(layer "F.Fab")
			(hide yes)
			(effects
				(font
					(size 1.016 1.016)
					(thickness 0.1524)
				)
			)
		)
		(duplicate_pad_numbers_are_jumpers no)
		(fp_line
			(start 0.508 -0.9398)
			(end -0.508 -0.9398)
			(stroke
				(width 0.1524)
				(type default)
			)
			(layer "F.SilkS")
		)
		(fp_line
			(start -0.508 -0.9398)
			(end -0.508 0.9398)
			(stroke
				(width 0.1524)
				(type default)
			)
			(layer "F.SilkS")
		)
		(fp_rect
			(start -0.508 0.9398)
			(end 0.508 -0.9398)
			(stroke
				(width 0)
				(type default)
			)
			(fill no)
			(layer "F.CrtYd")
		)
		(fp_rect
			(start -0.508 0.9398)
			(end 0.508 -0.9398)
			(stroke
				(width 0)
				(type default)
			)
			(fill no)
			(layer "F.Fab")
		)
		(pad "1" smd custom
			(at 0 -0.4445 180)
			(size 0.1397 0.1397)
			(layers "F.Cu" "F.Mask" "F.Paste")
			(net "SW_HDD7_G")
			(options
				(clearance outline)
				(anchor circle)
			)
			(primitives
				(gr_poly
					(pts
						(arc
							(start -0.1778 -0.2794)
							(mid -0.249642 -0.249642)
							(end -0.2794 -0.1778)
						)
						(arc
							(start -0.2794 0.1778)
							(mid -0.249642 0.249642)
							(end -0.1778 0.2794)
						)
						(arc
							(start 0.1778 0.2794)
							(mid 0.249642 0.249642)
							(end 0.2794 0.1778)
						)
						(arc
							(start 0.2794 -0.1778)
							(mid 0.249642 -0.249642)
							(end 0.1778 -0.2794)
						)
					)
					(width 0)
					(fill yes)
				)
			)
		)
		(pad "2" smd custom
			(at 0 0.4445 180)
			(size 0.1397 0.1397)
			(layers "F.Cu" "F.Mask" "F.Paste")
			(net "SW_HDD7_R")
			(options
				(clearance outline)
				(anchor circle)
			)
			(primitives
				(gr_poly
					(pts
						(arc
							(start -0.1778 -0.2794)
							(mid -0.249642 -0.249642)
							(end -0.2794 -0.1778)
						)
						(arc
							(start -0.2794 0.1778)
							(mid -0.249642 0.249642)
							(end -0.1778 0.2794)
						)
						(arc
							(start 0.1778 0.2794)
							(mid 0.249642 0.249642)
							(end 0.2794 0.1778)
						)
						(arc
							(start 0.2794 -0.1778)
							(mid 0.249642 -0.249642)
							(end 0.1778 -0.2794)
						)
					)
					(width 0)
					(fill yes)
				)
			)
		)
	)
	(footprint ""
		(layer "F.Cu")
		(at 216.153746 -77.9907 180)
		(property "Reference" "C173"
			(at 0 0 180)
			(layer "F.SilkS")
			(hide yes)
			(effects
				(font
					(size 1.27 1.27)
				)
			)
		)
		(property "Value" "SC10U16V6KX-2GP"
			(at -0.0762 -5.1308 180)
			(unlocked yes)
			(layer "F.Fab")
			(hide yes)
			(effects
				(font
					(size 1.016 1.016)
					(thickness 0.1524)
				)
			)
		)
		(property "Device Type" "C1206H71"
			(at -0.127 -6.6548 180)
			(unlocked yes)
			(layer "F.Fab")
			(hide yes)
			(effects
				(font
					(size 1.016 1.016)
					(thickness 0.1524)
				)
			)
		)
		(duplicate_pad_numbers_are_jumpers no)
		(fp_line
			(start 1.016 2.2352)
			(end -1.016 2.2352)
			(stroke
				(width 0.1524)
				(type default)
			)
			(layer "F.SilkS")
		)
		(fp_line
			(start 1.016 0.8382)
			(end 1.016 2.2352)
			(stroke
				(width 0.1524)
				(type default)
			)
			(layer "F.SilkS")
		)
		(fp_line
			(start 1.016 -2.2352)
			(end 1.016 -0.8382)
			(stroke
				(width 0.1524)
				(type default)
			)
			(layer "F.SilkS")
		)
		(fp_line
			(start -1.016 2.2352)
			(end -1.016 0.8382)
			(stroke
				(width 0.1524)
				(type default)
			)
			(layer "F.SilkS")
		)
		(fp_line
			(start -1.016 -0.8382)
			(end -1.016 -2.2352)
			(stroke
				(width 0.1524)
				(type default)
			)
			(layer "F.SilkS")
		)
		(fp_line
			(start -1.016 -2.2352)
			(end 1.016 -2.2352)
			(stroke
				(width 0.1524)
				(type default)
			)
			(layer "F.SilkS")
		)
		(fp_rect
			(start -1.0922 2.3114)
			(end 1.0922 -2.3114)
			(stroke
				(width 0)
				(type default)
			)
			(fill no)
			(layer "F.CrtYd")
		)
		(fp_poly
			(pts
				(xy 1.0922 -2.3114) (xy 1.0922 2.3114) (xy -1.0922 2.3114) (xy -1.0922 -2.3114)
			)
			(stroke
				(width 0)
				(type default)
			)
			(fill no)
			(layer "F.Fab")
		)
		(pad "1" smd rect
			(at 0 -1.397 180)
			(size 1.651 1.27)
			(layers "F.Cu" "F.Mask" "F.Paste")
			(net "P5V_HDD4")
		)
		(pad "2" smd rect
			(at 0 1.397 180)
			(size 1.651 1.27)
			(layers "F.Cu" "F.Mask" "F.Paste")
			(net "GND")
		)
	)
	(footprint ""
		(layer "F.Cu")
		(at 80.6958 -196.1388 -90)
		(property "Reference" "R416"
			(at 0 0 270)
			(layer "F.SilkS")
			(hide yes)
			(effects
				(font
					(size 1.27 1.27)
				)
			)
		)
		(property "Value" "0R2J-2-GP"
			(at 0.064008 -3.993896 270)
			(unlocked yes)
			(layer "F.Fab")
			(hide yes)
			(effects
				(font
					(size 1.016 1.016)
					(thickness 0.1524)
				)
			)
		)
		(property "Device Type" "R402H16"
			(at 0.064008 -5.517896 270)
			(unlocked yes)
			(layer "F.Fab")
			(hide yes)
			(effects
				(font
					(size 1.016 1.016)
					(thickness 0.1524)
				)
			)
		)
		(duplicate_pad_numbers_are_jumpers no)
		(fp_line
			(start -0.508 -0.9398)
			(end -0.508 0.9398)
			(stroke
				(width 0.1524)
				(type default)
			)
			(layer "F.SilkS")
		)
		(fp_line
			(start 0.508 -0.9398)
			(end -0.508 -0.9398)
			(stroke
				(width 0.1524)
				(type default)
			)
			(layer "F.SilkS")
		)
		(fp_rect
			(start -0.508 0.9398)
			(end 0.508 -0.9398)
			(stroke
				(width 0)
				(type default)
			)
			(fill no)
			(layer "F.CrtYd")
		)
		(fp_rect
			(start -0.508 0.9398)
			(end 0.508 -0.9398)
			(stroke
				(width 0)
				(type default)
			)
			(fill no)
			(layer "F.Fab")
		)
		(pad "1" smd custom
			(at 0 -0.4445 270)
			(size 0.1397 0.1397)
			(layers "F.Cu" "F.Mask" "F.Paste")
			(net "SW_HDD8_G")
			(options
				(clearance outline)
				(anchor circle)
			)
			(primitives
				(gr_poly
					(pts
						(arc
							(start -0.1778 -0.2794)
							(mid -0.249642 -0.249642)
							(end -0.2794 -0.1778)
						)
						(arc
							(start -0.2794 0.1778)
							(mid -0.249642 0.249642)
							(end -0.1778 0.2794)
						)
						(arc
							(start 0.1778 0.2794)
							(mid 0.249642 0.249642)
							(end 0.2794 0.1778)
						)
						(arc
							(start 0.2794 -0.1778)
							(mid 0.249642 -0.249642)
							(end 0.1778 -0.2794)
						)
					)
					(width 0)
					(fill yes)
				)
			)
		)
		(pad "2" smd custom
			(at 0 0.4445 270)
			(size 0.1397 0.1397)
			(layers "F.Cu" "F.Mask" "F.Paste")
			(net "SW_HDD8_R")
			(options
				(clearance outline)
				(anchor circle)
			)
			(primitives
				(gr_poly
					(pts
						(arc
							(start -0.1778 -0.2794)
							(mid -0.249642 -0.249642)
							(end -0.2794 -0.1778)
						)
						(arc
							(start -0.2794 0.1778)
							(mid -0.249642 0.249642)
							(end -0.1778 0.2794)
						)
						(arc
							(start 0.1778 0.2794)
							(mid 0.249642 0.249642)
							(end 0.2794 0.1778)
						)
						(arc
							(start 0.2794 -0.1778)
							(mid 0.249642 -0.249642)
							(end 0.1778 -0.2794)
						)
					)
					(width 0)
					(fill yes)
				)
			)
		)
	)
	(footprint ""
		(layer "F.Cu")
		(at 207.136746 -463.6897 90)
		(property "Reference" "R326"
			(at 0 0 90)
			(layer "F.SilkS")
			(hide yes)
			(effects
				(font
					(size 1.27 1.27)
				)
			)
		)
		(property "Value" "0R2J-2-GP"
			(at 0.064008 -3.993896 90)
			(unlocked yes)
			(layer "F.Fab")
			(hide yes)
			(effects
				(font
					(size 1.016 1.016)
					(thickness 0.1524)
				)
			)
		)
		(property "Device Type" "R402H16"
			(at 0.064008 -5.517896 90)
			(unlocked yes)
			(layer "F.Fab")
			(hide yes)
			(effects
				(font
					(size 1.016 1.016)
					(thickness 0.1524)
				)
			)
		)
		(duplicate_pad_numbers_are_jumpers no)
		(fp_line
			(start 0.508 -0.9398)
			(end -0.508 -0.9398)
			(stroke
				(width 0.1524)
				(type default)
			)
			(layer "F.SilkS")
		)
		(fp_line
			(start -0.508 -0.9398)
			(end -0.508 0.9398)
			(stroke
				(width 0.1524)
				(type default)
			)
			(layer "F.SilkS")
		)
		(fp_rect
			(start -0.508 0.9398)
			(end 0.508 -0.9398)
			(stroke
				(width 0)
				(type default)
			)
			(fill no)
			(layer "F.CrtYd")
		)
		(fp_rect
			(start -0.508 0.9398)
			(end 0.508 -0.9398)
			(stroke
				(width 0)
				(type default)
			)
			(fill no)
			(layer "F.Fab")
		)
		(pad "1" smd custom
			(at 0 -0.4445 90)
			(size 0.1397 0.1397)
			(layers "F.Cu" "F.Mask" "F.Paste")
			(net "I2C_B_SDA")
			(options
				(clearance outline)
				(anchor circle)
			)
			(primitives
				(gr_poly
					(pts
						(arc
							(start -0.1778 -0.2794)
							(mid -0.249642 -0.249642)
							(end -0.2794 -0.1778)
						)
						(arc
							(start -0.2794 0.1778)
							(mid -0.249642 0.249642)
							(end -0.1778 0.2794)
						)
						(arc
							(start 0.1778 0.2794)
							(mid 0.249642 0.249642)
							(end 0.2794 0.1778)
						)
						(arc
							(start 0.2794 -0.1778)
							(mid 0.249642 -0.249642)
							(end 0.1778 -0.2794)
						)
					)
					(width 0)
					(fill yes)
				)
			)
		)
		(pad "2" smd custom
			(at 0 0.4445 90)
			(size 0.1397 0.1397)
			(layers "F.Cu" "F.Mask" "F.Paste")
			(net "TMP3_SDA")
			(options
				(clearance outline)
				(anchor circle)
			)
			(primitives
				(gr_poly
					(pts
						(arc
							(start -0.1778 -0.2794)
							(mid -0.249642 -0.249642)
							(end -0.2794 -0.1778)
						)
						(arc
							(start -0.2794 0.1778)
							(mid -0.249642 0.249642)
							(end -0.1778 0.2794)
						)
						(arc
							(start 0.1778 0.2794)
							(mid 0.249642 0.249642)
							(end 0.2794 0.1778)
						)
						(arc
							(start 0.2794 -0.1778)
							(mid 0.249642 -0.249642)
							(end 0.1778 -0.2794)
						)
					)
					(width 0)
					(fill yes)
				)
			)
		)
	)
	(footprint ""
		(layer "F.Cu")
		(at 37.210746 -112.296702 180)
		(property "Reference" "R295"
			(at 0 0 180)
			(layer "F.SilkS")
			(hide yes)
			(effects
				(font
					(size 1.27 1.27)
				)
			)
		)
		(property "Value" "0R2J-2-GP"
			(at 0.064008 -3.993896 180)
			(unlocked yes)
			(layer "F.Fab")
			(hide yes)
			(effects
				(font
					(size 1.016 1.016)
					(thickness 0.1524)
				)
			)
		)
		(property "Device Type" "R402H16"
			(at 0.064008 -5.517896 180)
			(unlocked yes)
			(layer "F.Fab")
			(hide yes)
			(effects
				(font
					(size 1.016 1.016)
					(thickness 0.1524)
				)
			)
		)
		(duplicate_pad_numbers_are_jumpers no)
		(fp_line
			(start 0.508 -0.9398)
			(end -0.508 -0.9398)
			(stroke
				(width 0.1524)
				(type default)
			)
			(layer "F.SilkS")
		)
		(fp_line
			(start -0.508 -0.9398)
			(end -0.508 0.9398)
			(stroke
				(width 0.1524)
				(type default)
			)
			(layer "F.SilkS")
		)
		(fp_rect
			(start -0.508 0.9398)
			(end 0.508 -0.9398)
			(stroke
				(width 0)
				(type default)
			)
			(fill no)
			(layer "F.CrtYd")
		)
		(fp_rect
			(start -0.508 0.9398)
			(end 0.508 -0.9398)
			(stroke
				(width 0)
				(type default)
			)
			(fill no)
			(layer "F.Fab")
		)
		(pad "1" smd custom
			(at 0 -0.4445 180)
			(size 0.1397 0.1397)
			(layers "F.Cu" "F.Mask" "F.Paste")
			(net "DRIVE_PWR13")
			(options
				(clearance outline)
				(anchor circle)
			)
			(primitives
				(gr_poly
					(pts
						(arc
							(start -0.1778 -0.2794)
							(mid -0.249642 -0.249642)
							(end -0.2794 -0.1778)
						)
						(arc
							(start -0.2794 0.1778)
							(mid -0.249642 0.249642)
							(end -0.1778 0.2794)
						)
						(arc
							(start 0.1778 0.2794)
							(mid 0.249642 0.249642)
							(end 0.2794 0.1778)
						)
						(arc
							(start 0.2794 -0.1778)
							(mid 0.249642 -0.249642)
							(end 0.1778 -0.2794)
						)
					)
					(width 0)
					(fill yes)
				)
			)
		)
		(pad "2" smd custom
			(at 0 0.4445 180)
			(size 0.1397 0.1397)
			(layers "F.Cu" "F.Mask" "F.Paste")
			(net "SW_PWR_HDD13")
			(options
				(clearance outline)
				(anchor circle)
			)
			(primitives
				(gr_poly
					(pts
						(arc
							(start -0.1778 -0.2794)
							(mid -0.249642 -0.249642)
							(end -0.2794 -0.1778)
						)
						(arc
							(start -0.2794 0.1778)
							(mid -0.249642 0.249642)
							(end -0.1778 0.2794)
						)
						(arc
							(start 0.1778 0.2794)
							(mid 0.249642 0.249642)
							(end 0.2794 0.1778)
						)
						(arc
							(start 0.2794 -0.1778)
							(mid 0.249642 -0.249642)
							(end 0.1778 -0.2794)
						)
					)
					(width 0)
					(fill yes)
				)
			)
		)
	)
	(footprint ""
		(layer "F.Cu")
		(at 78.358746 -188.4807 -90)
		(property "Reference" "R220"
			(at 0 0 270)
			(layer "F.SilkS")
			(hide yes)
			(effects
				(font
					(size 1.27 1.27)
				)
			)
		)
		(property "Value" "1KR2F-3-GP"
			(at 0.064008 -3.993896 270)
			(unlocked yes)
			(layer "F.Fab")
			(hide yes)
			(effects
				(font
					(size 1.016 1.016)
					(thickness 0.1524)
				)
			)
		)
		(property "Device Type" "R402H16"
			(at 0.064008 -5.517896 270)
			(unlocked yes)
			(layer "F.Fab")
			(hide yes)
			(effects
				(font
					(size 1.016 1.016)
					(thickness 0.1524)
				)
			)
		)
		(duplicate_pad_numbers_are_jumpers no)
		(fp_line
			(start -0.508 -0.9398)
			(end -0.508 0.9398)
			(stroke
				(width 0.1524)
				(type default)
			)
			(layer "F.SilkS")
		)
		(fp_line
			(start 0.508 -0.9398)
			(end -0.508 -0.9398)
			(stroke
				(width 0.1524)
				(type default)
			)
			(layer "F.SilkS")
		)
		(fp_rect
			(start -0.508 0.9398)
			(end 0.508 -0.9398)
			(stroke
				(width 0)
				(type default)
			)
			(fill no)
			(layer "F.CrtYd")
		)
		(fp_rect
			(start -0.508 0.9398)
			(end 0.508 -0.9398)
			(stroke
				(width 0)
				(type default)
			)
			(fill no)
			(layer "F.Fab")
		)
		(pad "1" smd custom
			(at 0 -0.4445 270)
			(size 0.1397 0.1397)
			(layers "F.Cu" "F.Mask" "F.Paste")
			(net "P3V3")
			(options
				(clearance outline)
				(anchor circle)
			)
			(primitives
				(gr_poly
					(pts
						(arc
							(start -0.1778 -0.2794)
							(mid -0.249642 -0.249642)
							(end -0.2794 -0.1778)
						)
						(arc
							(start -0.2794 0.1778)
							(mid -0.249642 0.249642)
							(end -0.1778 0.2794)
						)
						(arc
							(start 0.1778 0.2794)
							(mid 0.249642 0.249642)
							(end 0.2794 0.1778)
						)
						(arc
							(start 0.2794 -0.1778)
							(mid 0.249642 -0.249642)
							(end 0.1778 -0.2794)
						)
					)
					(width 0)
					(fill yes)
				)
			)
		)
		(pad "2" smd custom
			(at 0 0.4445 270)
			(size 0.1397 0.1397)
			(layers "F.Cu" "F.Mask" "F.Paste")
			(net "SW_PWR_HDD8")
			(options
				(clearance outline)
				(anchor circle)
			)
			(primitives
				(gr_poly
					(pts
						(arc
							(start -0.1778 -0.2794)
							(mid -0.249642 -0.249642)
							(end -0.2794 -0.1778)
						)
						(arc
							(start -0.2794 0.1778)
							(mid -0.249642 0.249642)
							(end -0.1778 0.2794)
						)
						(arc
							(start 0.1778 0.2794)
							(mid 0.249642 0.249642)
							(end 0.2794 0.1778)
						)
						(arc
							(start 0.2794 -0.1778)
							(mid 0.249642 -0.249642)
							(end 0.1778 -0.2794)
						)
					)
					(width 0)
					(fill yes)
				)
			)
		)
	)
	(footprint ""
		(layer "F.Cu")
		(at 20.192746 -51.9557 -90)
		(property "Reference" "R297"
			(at 0 0 270)
			(layer "F.SilkS")
			(hide yes)
			(effects
				(font
					(size 1.27 1.27)
				)
			)
		)
		(property "Value" "402R2F-GP"
			(at 0.064008 -3.993896 270)
			(unlocked yes)
			(layer "F.Fab")
			(hide yes)
			(effects
				(font
					(size 1.016 1.016)
					(thickness 0.1524)
				)
			)
		)
		(property "Device Type" "R402H16"
			(at 0.064008 -5.517896 270)
			(unlocked yes)
			(layer "F.Fab")
			(hide yes)
			(effects
				(font
					(size 1.016 1.016)
					(thickness 0.1524)
				)
			)
		)
		(duplicate_pad_numbers_are_jumpers no)
		(fp_line
			(start -0.508 -0.9398)
			(end -0.508 0.9398)
			(stroke
				(width 0.1524)
				(type default)
			)
			(layer "F.SilkS")
		)
		(fp_line
			(start 0.508 -0.9398)
			(end -0.508 -0.9398)
			(stroke
				(width 0.1524)
				(type default)
			)
			(layer "F.SilkS")
		)
		(fp_rect
			(start -0.508 0.9398)
			(end 0.508 -0.9398)
			(stroke
				(width 0)
				(type default)
			)
			(fill no)
			(layer "F.CrtYd")
		)
		(fp_rect
			(start -0.508 0.9398)
			(end 0.508 -0.9398)
			(stroke
				(width 0)
				(type default)
			)
			(fill no)
			(layer "F.Fab")
		)
		(pad "1" smd custom
			(at 0 -0.4445 270)
			(size 0.1397 0.1397)
			(layers "F.Cu" "F.Mask" "F.Paste")
			(net "P5VC_HDD14_LED")
			(options
				(clearance outline)
				(anchor circle)
			)
			(primitives
				(gr_poly
					(pts
						(arc
							(start -0.1778 -0.2794)
							(mid -0.249642 -0.249642)
							(end -0.2794 -0.1778)
						)
						(arc
							(start -0.2794 0.1778)
							(mid -0.249642 0.249642)
							(end -0.1778 0.2794)
						)
						(arc
							(start 0.1778 0.2794)
							(mid 0.249642 0.249642)
							(end 0.2794 0.1778)
						)
						(arc
							(start 0.2794 -0.1778)
							(mid 0.249642 -0.249642)
							(end 0.1778 -0.2794)
						)
					)
					(width 0)
					(fill yes)
				)
			)
		)
		(pad "2" smd custom
			(at 0 0.4445 270)
			(size 0.1397 0.1397)
			(layers "F.Cu" "F.Mask" "F.Paste")
			(net "DRV_ACT_14")
			(options
				(clearance outline)
				(anchor circle)
			)
			(primitives
				(gr_poly
					(pts
						(arc
							(start -0.1778 -0.2794)
							(mid -0.249642 -0.249642)
							(end -0.2794 -0.1778)
						)
						(arc
							(start -0.2794 0.1778)
							(mid -0.249642 0.249642)
							(end -0.1778 0.2794)
						)
						(arc
							(start 0.1778 0.2794)
							(mid 0.249642 0.249642)
							(end 0.2794 0.1778)
						)
						(arc
							(start 0.2794 -0.1778)
							(mid 0.249642 -0.249642)
							(end 0.1778 -0.2794)
						)
					)
					(width 0)
					(fill yes)
				)
			)
		)
	)
	(footprint ""
		(layer "F.Cu")
		(at 81.661 -96.52 -90)
		(property "Reference" "D24"
			(at 0 0 270)
			(layer "F.SilkS")
			(hide yes)
			(effects
				(font
					(size 1.27 1.27)
				)
			)
		)
		(property "Value" "RB551V30-1-GP"
			(at 0 -6.7818 270)
			(unlocked yes)
			(layer "F.Fab")
			(hide yes)
			(effects
				(font
					(size 1.016 1.016)
					(thickness 0.1524)
				)
			)
		)
		(property "Device Type" "SOD323AKH44"
			(at 0 -8.6868 270)
			(unlocked yes)
			(layer "F.Fab")
			(hide yes)
			(effects
				(font
					(size 1.016 1.016)
					(thickness 0.1524)
				)
			)
		)
		(duplicate_pad_numbers_are_jumpers no)
		(fp_line
			(start -0.889 2.159)
			(end -0.889 -1.9304)
			(stroke
				(width 0.1524)
				(type default)
			)
			(layer "F.SilkS")
		)
		(fp_line
			(start 0.889 2.159)
			(end -0.889 2.159)
			(stroke
				(width 0.1524)
				(type default)
			)
			(layer "F.SilkS")
		)
		(fp_line
			(start 0.762 2.0574)
			(end -0.762 2.0574)
			(stroke
				(width 0.508)
				(type default)
			)
			(layer "F.SilkS")
		)
		(fp_line
			(start -0.889 -1.9304)
			(end 0.889 -1.9304)
			(stroke
				(width 0.1524)
				(type default)
			)
			(layer "F.SilkS")
		)
		(fp_line
			(start 0.889 -1.9304)
			(end 0.889 2.159)
			(stroke
				(width 0.1524)
				(type default)
			)
			(layer "F.SilkS")
		)
		(fp_rect
			(start -1.016 2.3114)
			(end 1.016 -2.0066)
			(stroke
				(width 0)
				(type default)
			)
			(fill no)
			(layer "F.CrtYd")
		)
		(fp_poly
			(pts
				(xy -1.016 -2.0066) (xy 1.016 -2.0066) (xy 1.016 2.3114) (xy -1.016 2.3114)
			)
			(stroke
				(width 0)
				(type default)
			)
			(fill no)
			(layer "F.Fab")
		)
		(pad "A" smd rect
			(at 0 -1.143 270)
			(size 0.5588 1.016)
			(layers "F.Cu" "F.Mask" "F.Paste")
			(net "SW_HDD9_R")
		)
		(pad "K" smd rect
			(at 0 1.143 270)
			(size 0.5588 1.016)
			(layers "F.Cu" "F.Mask" "F.Paste")
			(net "SW_HDD9_N")
		)
	)
	(footprint ""
		(layer "F.Cu")
		(at 45.338746 -40.9067 90)
		(property "Reference" "R228"
			(at 0 0 90)
			(layer "F.SilkS")
			(hide yes)
			(effects
				(font
					(size 1.27 1.27)
				)
			)
		)
		(property "Value" "0R2J-2-GP"
			(at 0.064008 -3.993896 90)
			(unlocked yes)
			(layer "F.Fab")
			(hide yes)
			(effects
				(font
					(size 1.016 1.016)
					(thickness 0.1524)
				)
			)
		)
		(property "Device Type" "R402H16"
			(at 0.064008 -5.517896 90)
			(unlocked yes)
			(layer "F.Fab")
			(hide yes)
			(effects
				(font
					(size 1.016 1.016)
					(thickness 0.1524)
				)
			)
		)
		(duplicate_pad_numbers_are_jumpers no)
		(fp_line
			(start 0.508 -0.9398)
			(end -0.508 -0.9398)
			(stroke
				(width 0.1524)
				(type default)
			)
			(layer "F.SilkS")
		)
		(fp_line
			(start -0.508 -0.9398)
			(end -0.508 0.9398)
			(stroke
				(width 0.1524)
				(type default)
			)
			(layer "F.SilkS")
		)
		(fp_rect
			(start -0.508 0.9398)
			(end 0.508 -0.9398)
			(stroke
				(width 0)
				(type default)
			)
			(fill no)
			(layer "F.CrtYd")
		)
		(fp_rect
			(start -0.508 0.9398)
			(end 0.508 -0.9398)
			(stroke
				(width 0)
				(type default)
			)
			(fill no)
			(layer "F.Fab")
		)
		(pad "1" smd custom
			(at 0 -0.4445 90)
			(size 0.1397 0.1397)
			(layers "F.Cu" "F.Mask" "F.Paste")
			(net "DRV_ACT_NET9")
			(options
				(clearance outline)
				(anchor circle)
			)
			(primitives
				(gr_poly
					(pts
						(arc
							(start -0.1778 -0.2794)
							(mid -0.249642 -0.249642)
							(end -0.2794 -0.1778)
						)
						(arc
							(start -0.2794 0.1778)
							(mid -0.249642 0.249642)
							(end -0.1778 0.2794)
						)
						(arc
							(start 0.1778 0.2794)
							(mid 0.249642 0.249642)
							(end 0.2794 0.1778)
						)
						(arc
							(start 0.2794 -0.1778)
							(mid 0.249642 -0.249642)
							(end 0.1778 -0.2794)
						)
					)
					(width 0)
					(fill yes)
				)
			)
		)
		(pad "2" smd custom
			(at 0 0.4445 90)
			(size 0.1397 0.1397)
			(layers "F.Cu" "F.Mask" "F.Paste")
			(net "DRIVE_ACT_9")
			(options
				(clearance outline)
				(anchor circle)
			)
			(primitives
				(gr_poly
					(pts
						(arc
							(start -0.1778 -0.2794)
							(mid -0.249642 -0.249642)
							(end -0.2794 -0.1778)
						)
						(arc
							(start -0.2794 0.1778)
							(mid -0.249642 0.249642)
							(end -0.1778 0.2794)
						)
						(arc
							(start 0.1778 0.2794)
							(mid 0.249642 0.249642)
							(end 0.2794 0.1778)
						)
						(arc
							(start 0.2794 -0.1778)
							(mid 0.249642 -0.249642)
							(end 0.1778 -0.2794)
						)
					)
					(width 0)
					(fill yes)
				)
			)
		)
	)
	(footprint ""
		(layer "F.Cu")
		(at 80.01 -94.488 180)
		(property "Reference" "R551"
			(at 0 0 180)
			(layer "F.SilkS")
			(hide yes)
			(effects
				(font
					(size 1.27 1.27)
				)
			)
		)
		(property "Value" "200KR2F-L-GP"
			(at 0.064008 -3.993896 180)
			(unlocked yes)
			(layer "F.Fab")
			(hide yes)
			(effects
				(font
					(size 1.016 1.016)
					(thickness 0.1524)
				)
			)
		)
		(property "Device Type" "R402H16"
			(at 0.064008 -5.517896 180)
			(unlocked yes)
			(layer "F.Fab")
			(hide yes)
			(effects
				(font
					(size 1.016 1.016)
					(thickness 0.1524)
				)
			)
		)
		(duplicate_pad_numbers_are_jumpers no)
		(fp_line
			(start 0.508 -0.9398)
			(end -0.508 -0.9398)
			(stroke
				(width 0.1524)
				(type default)
			)
			(layer "F.SilkS")
		)
		(fp_line
			(start -0.508 -0.9398)
			(end -0.508 0.9398)
			(stroke
				(width 0.1524)
				(type default)
			)
			(layer "F.SilkS")
		)
		(fp_rect
			(start -0.508 0.9398)
			(end 0.508 -0.9398)
			(stroke
				(width 0)
				(type default)
			)
			(fill no)
			(layer "F.CrtYd")
		)
		(fp_rect
			(start -0.508 0.9398)
			(end 0.508 -0.9398)
			(stroke
				(width 0)
				(type default)
			)
			(fill no)
			(layer "F.Fab")
		)
		(pad "1" smd custom
			(at 0 -0.4445 180)
			(size 0.1397 0.1397)
			(layers "F.Cu" "F.Mask" "F.Paste")
			(net "SW_HDD9_R")
			(options
				(clearance outline)
				(anchor circle)
			)
			(primitives
				(gr_poly
					(pts
						(arc
							(start -0.1778 -0.2794)
							(mid -0.249642 -0.249642)
							(end -0.2794 -0.1778)
						)
						(arc
							(start -0.2794 0.1778)
							(mid -0.249642 0.249642)
							(end -0.1778 0.2794)
						)
						(arc
							(start 0.1778 0.2794)
							(mid 0.249642 0.249642)
							(end 0.2794 0.1778)
						)
						(arc
							(start 0.2794 -0.1778)
							(mid 0.249642 -0.249642)
							(end 0.1778 -0.2794)
						)
					)
					(width 0)
					(fill yes)
				)
			)
		)
		(pad "2" smd custom
			(at 0 0.4445 180)
			(size 0.1397 0.1397)
			(layers "F.Cu" "F.Mask" "F.Paste")
			(net "SW_HDD9_N")
			(options
				(clearance outline)
				(anchor circle)
			)
			(primitives
				(gr_poly
					(pts
						(arc
							(start -0.1778 -0.2794)
							(mid -0.249642 -0.249642)
							(end -0.2794 -0.1778)
						)
						(arc
							(start -0.2794 0.1778)
							(mid -0.249642 0.249642)
							(end -0.1778 0.2794)
						)
						(arc
							(start 0.1778 0.2794)
							(mid 0.249642 0.249642)
							(end 0.2794 0.1778)
						)
						(arc
							(start 0.2794 -0.1778)
							(mid 0.249642 -0.249642)
							(end 0.1778 -0.2794)
						)
					)
					(width 0)
					(fill yes)
				)
			)
		)
	)
	(footprint ""
		(layer "F.Cu")
		(at 45.338746 -143.2687 90)
		(property "Reference" "R216"
			(at 0 0 90)
			(layer "F.SilkS")
			(hide yes)
			(effects
				(font
					(size 1.27 1.27)
				)
			)
		)
		(property "Value" "0R2J-2-GP"
			(at 0.064008 -3.993896 90)
			(unlocked yes)
			(layer "F.Fab")
			(hide yes)
			(effects
				(font
					(size 1.016 1.016)
					(thickness 0.1524)
				)
			)
		)
		(property "Device Type" "R402H16"
			(at 0.064008 -5.517896 90)
			(unlocked yes)
			(layer "F.Fab")
			(hide yes)
			(effects
				(font
					(size 1.016 1.016)
					(thickness 0.1524)
				)
			)
		)
		(duplicate_pad_numbers_are_jumpers no)
		(fp_line
			(start 0.508 -0.9398)
			(end -0.508 -0.9398)
			(stroke
				(width 0.1524)
				(type default)
			)
			(layer "F.SilkS")
		)
		(fp_line
			(start -0.508 -0.9398)
			(end -0.508 0.9398)
			(stroke
				(width 0.1524)
				(type default)
			)
			(layer "F.SilkS")
		)
		(fp_rect
			(start -0.508 0.9398)
			(end 0.508 -0.9398)
			(stroke
				(width 0)
				(type default)
			)
			(fill no)
			(layer "F.CrtYd")
		)
		(fp_rect
			(start -0.508 0.9398)
			(end 0.508 -0.9398)
			(stroke
				(width 0)
				(type default)
			)
			(fill no)
			(layer "F.Fab")
		)
		(pad "1" smd custom
			(at 0 -0.4445 90)
			(size 0.1397 0.1397)
			(layers "F.Cu" "F.Mask" "F.Paste")
			(net "FLT_NET_HDD8")
			(options
				(clearance outline)
				(anchor circle)
			)
			(primitives
				(gr_poly
					(pts
						(arc
							(start -0.1778 -0.2794)
							(mid -0.249642 -0.249642)
							(end -0.2794 -0.1778)
						)
						(arc
							(start -0.2794 0.1778)
							(mid -0.249642 0.249642)
							(end -0.1778 0.2794)
						)
						(arc
							(start 0.1778 0.2794)
							(mid 0.249642 0.249642)
							(end 0.2794 0.1778)
						)
						(arc
							(start 0.2794 -0.1778)
							(mid 0.249642 -0.249642)
							(end 0.1778 -0.2794)
						)
					)
					(width 0)
					(fill yes)
				)
			)
		)
		(pad "2" smd custom
			(at 0 0.4445 90)
			(size 0.1397 0.1397)
			(layers "F.Cu" "F.Mask" "F.Paste")
			(net "FLT_HDD8_DRIVE")
			(options
				(clearance outline)
				(anchor circle)
			)
			(primitives
				(gr_poly
					(pts
						(arc
							(start -0.1778 -0.2794)
							(mid -0.249642 -0.249642)
							(end -0.2794 -0.1778)
						)
						(arc
							(start -0.2794 0.1778)
							(mid -0.249642 0.249642)
							(end -0.1778 0.2794)
						)
						(arc
							(start 0.1778 0.2794)
							(mid 0.249642 0.249642)
							(end 0.2794 0.1778)
						)
						(arc
							(start 0.2794 -0.1778)
							(mid 0.249642 -0.249642)
							(end 0.1778 -0.2794)
						)
					)
					(width 0)
					(fill yes)
				)
			)
		)
	)
	(footprint ""
		(layer "F.Cu")
		(at 41.0718 -428.1932)
		(property "Reference" "Q67"
			(at 0 0 0)
			(layer "F.SilkS")
			(hide yes)
			(effects
				(font
					(size 1.27 1.27)
				)
			)
		)
		(property "Value" "2N7002-11-GP"
			(at 0.127 -8.9662 0)
			(unlocked yes)
			(layer "F.Fab")
			(hide yes)
			(effects
				(font
					(size 1.016 1.016)
					(thickness 0.1524)
				)
			)
		)
		(property "Device Type" "SOT23DGS2D4H44"
			(at 0.127 -10.4902 0)
			(unlocked yes)
			(layer "F.Fab")
			(hide yes)
			(effects
				(font
					(size 1.016 1.016)
					(thickness 0.1524)
				)
			)
		)
		(duplicate_pad_numbers_are_jumpers no)
		(fp_line
			(start -1.651 -1.778)
			(end -1.651 1.778)
			(stroke
				(width 0.1524)
				(type default)
			)
			(layer "F.SilkS")
		)
		(fp_line
			(start -1.651 1.778)
			(end 1.651 1.778)
			(stroke
				(width 0.1524)
				(type default)
			)
			(layer "F.SilkS")
		)
		(fp_line
			(start 1.651 -1.778)
			(end -1.651 -1.778)
			(stroke
				(width 0.1524)
				(type default)
			)
			(layer "F.SilkS")
		)
		(fp_line
			(start 1.651 1.778)
			(end 1.651 -1.778)
			(stroke
				(width 0.1524)
				(type default)
			)
			(layer "F.SilkS")
		)
		(fp_poly
			(pts
				(xy -1.778 1.8796) (xy -1.778 -1.8796) (xy 1.778 -1.8796) (xy 1.778 1.8796)
			)
			(stroke
				(width 0)
				(type default)
			)
			(fill no)
			(layer "F.CrtYd")
		)
		(fp_poly
			(pts
				(xy -1.778 1.8796) (xy -1.778 -1.8796) (xy 1.778 -1.8796) (xy 1.778 1.8796)
			)
			(stroke
				(width 0)
				(type default)
			)
			(fill no)
			(layer "F.Fab")
		)
		(pad "D" smd custom
			(at 0 -0.9525)
			(size 0.1905 0.1905)
			(layers "F.Cu" "F.Mask" "F.Paste")
			(net "HDD10_LED_G")
			(options
				(clearance outline)
				(anchor circle)
			)
			(primitives
				(gr_poly
					(pts
						(arc
							(start -0.1778 0.5715)
							(mid -0.321484 0.511984)
							(end -0.381 0.3683)
						)
						(arc
							(start -0.381 -0.3683)
							(mid -0.321484 -0.511984)
							(end -0.1778 -0.5715)
						)
						(arc
							(start 0.1778 -0.5715)
							(mid 0.321484 -0.511984)
							(end 0.381 -0.3683)
						)
						(arc
							(start 0.381 0.3683)
							(mid 0.321484 0.511984)
							(end 0.1778 0.5715)
						)
					)
					(width 0)
					(fill yes)
				)
			)
		)
		(pad "G" smd custom
			(at -0.98425 0.9525)
			(size 0.1905 0.1905)
			(layers "F.Cu" "F.Mask" "F.Paste")
			(net "HDD10_LED_B")
			(options
				(clearance outline)
				(anchor circle)
			)
			(primitives
				(gr_poly
					(pts
						(arc
							(start -0.1778 0.5715)
							(mid -0.321484 0.511984)
							(end -0.381 0.3683)
						)
						(arc
							(start -0.381 -0.3683)
							(mid -0.321484 -0.511984)
							(end -0.1778 -0.5715)
						)
						(arc
							(start 0.1778 -0.5715)
							(mid 0.321484 -0.511984)
							(end 0.381 -0.3683)
						)
						(arc
							(start 0.381 0.3683)
							(mid 0.321484 0.511984)
							(end 0.1778 0.5715)
						)
					)
					(width 0)
					(fill yes)
				)
			)
		)
		(pad "S" smd custom
			(at 0.98425 0.9525)
			(size 0.1905 0.1905)
			(layers "F.Cu" "F.Mask" "F.Paste")
			(net "GND")
			(options
				(clearance outline)
				(anchor circle)
			)
			(primitives
				(gr_poly
					(pts
						(arc
							(start -0.1778 0.5715)
							(mid -0.321484 0.511984)
							(end -0.381 0.3683)
						)
						(arc
							(start -0.381 -0.3683)
							(mid -0.321484 -0.511984)
							(end -0.1778 -0.5715)
						)
						(arc
							(start 0.1778 -0.5715)
							(mid 0.321484 -0.511984)
							(end 0.381 -0.3683)
						)
						(arc
							(start 0.381 0.3683)
							(mid 0.321484 0.511984)
							(end 0.1778 0.5715)
						)
					)
					(width 0)
					(fill yes)
				)
			)
		)
	)
	(footprint ""
		(layer "F.Cu")
		(at 26.034746 -35.9537 90)
		(property "Reference" "C327"
			(at 0 0 90)
			(layer "F.SilkS")
			(hide yes)
			(effects
				(font
					(size 1.27 1.27)
				)
			)
		)
		(property "Value" "SCD01U50V2KX-1GP"
			(at 1.1811 -2.7051 90)
			(unlocked yes)
			(layer "F.Fab")
			(hide yes)
			(effects
				(font
					(size 1.016 1.016)
					(thickness 0.1524)
				)
			)
		)
		(property "Device Type" "C402H22"
			(at 1.1811 -4.2291 90)
			(unlocked yes)
			(layer "F.Fab")
			(hide yes)
			(effects
				(font
					(size 1.016 1.016)
					(thickness 0.1524)
				)
			)
		)
		(duplicate_pad_numbers_are_jumpers no)
		(fp_rect
			(start -0.4318 0.9525)
			(end 0.4318 -0.9525)
			(stroke
				(width 0)
				(type default)
			)
			(fill no)
			(layer "F.CrtYd")
		)
		(fp_rect
			(start -0.4318 0.9525)
			(end 0.4318 -0.9525)
			(stroke
				(width 0)
				(type default)
			)
			(fill no)
			(layer "F.Fab")
		)
		(pad "1" smd custom
			(at 0 -0.4445 90)
			(size 0.1524 0.1524)
			(layers "F.Cu" "F.Mask" "F.Paste")
			(net "SAS2X28_DRIVE_RX_P_A14")
			(options
				(clearance outline)
				(anchor circle)
			)
			(primitives
				(gr_poly
					(pts
						(arc
							(start 0.3048 -0.2032)
							(mid 0.275042 -0.275042)
							(end 0.2032 -0.3048)
						)
						(arc
							(start -0.2032 -0.3048)
							(mid -0.275042 -0.275042)
							(end -0.3048 -0.2032)
						)
						(arc
							(start -0.3048 0.2032)
							(mid -0.275042 0.275042)
							(end -0.2032 0.3048)
						)
						(arc
							(start 0.2032 0.3048)
							(mid 0.275042 0.275042)
							(end 0.3048 0.2032)
						)
					)
					(width 0)
					(fill yes)
				)
			)
		)
		(pad "2" smd custom
			(at 0 0.4445 90)
			(size 0.1524 0.1524)
			(layers "F.Cu" "F.Mask" "F.Paste")
			(net "SAS2X28_A_HDD14_RX_+")
			(options
				(clearance outline)
				(anchor circle)
			)
			(primitives
				(gr_poly
					(pts
						(arc
							(start 0.3048 -0.2032)
							(mid 0.275042 -0.275042)
							(end 0.2032 -0.3048)
						)
						(arc
							(start -0.2032 -0.3048)
							(mid -0.275042 -0.275042)
							(end -0.3048 -0.2032)
						)
						(arc
							(start -0.3048 0.2032)
							(mid -0.275042 0.275042)
							(end -0.2032 0.3048)
						)
						(arc
							(start 0.2032 0.3048)
							(mid 0.275042 0.275042)
							(end 0.3048 0.2032)
						)
					)
					(width 0)
					(fill yes)
				)
			)
		)
	)
	(footprint ""
		(layer "F.Cu")
		(at 47.752 -107.315 180)
		(property "Reference" "R576"
			(at 0 0 180)
			(layer "F.SilkS")
			(hide yes)
			(effects
				(font
					(size 1.27 1.27)
				)
			)
		)
		(property "Value" "300KR2F-GP"
			(at 0.064008 -3.993896 180)
			(unlocked yes)
			(layer "F.Fab")
			(hide yes)
			(effects
				(font
					(size 1.016 1.016)
					(thickness 0.1524)
				)
			)
		)
		(property "Device Type" "R402H16"
			(at 0.064008 -5.517896 180)
			(unlocked yes)
			(layer "F.Fab")
			(hide yes)
			(effects
				(font
					(size 1.016 1.016)
					(thickness 0.1524)
				)
			)
		)
		(duplicate_pad_numbers_are_jumpers no)
		(fp_line
			(start 0.508 -0.9398)
			(end -0.508 -0.9398)
			(stroke
				(width 0.1524)
				(type default)
			)
			(layer "F.SilkS")
		)
		(fp_line
			(start -0.508 -0.9398)
			(end -0.508 0.9398)
			(stroke
				(width 0.1524)
				(type default)
			)
			(layer "F.SilkS")
		)
		(fp_rect
			(start -0.508 0.9398)
			(end 0.508 -0.9398)
			(stroke
				(width 0)
				(type default)
			)
			(fill no)
			(layer "F.CrtYd")
		)
		(fp_rect
			(start -0.508 0.9398)
			(end 0.508 -0.9398)
			(stroke
				(width 0)
				(type default)
			)
			(fill no)
			(layer "F.Fab")
		)
		(pad "1" smd custom
			(at 0 -0.4445 180)
			(size 0.1397 0.1397)
			(layers "F.Cu" "F.Mask" "F.Paste")
			(net "SW_HDD13_N")
			(options
				(clearance outline)
				(anchor circle)
			)
			(primitives
				(gr_poly
					(pts
						(arc
							(start -0.1778 -0.2794)
							(mid -0.249642 -0.249642)
							(end -0.2794 -0.1778)
						)
						(arc
							(start -0.2794 0.1778)
							(mid -0.249642 0.249642)
							(end -0.1778 0.2794)
						)
						(arc
							(start 0.1778 0.2794)
							(mid 0.249642 0.249642)
							(end 0.2794 0.1778)
						)
						(arc
							(start 0.2794 -0.1778)
							(mid 0.249642 -0.249642)
							(end 0.1778 -0.2794)
						)
					)
					(width 0)
					(fill yes)
				)
			)
		)
		(pad "2" smd custom
			(at 0 0.4445 180)
			(size 0.1397 0.1397)
			(layers "F.Cu" "F.Mask" "F.Paste")
			(net "P12V")
			(options
				(clearance outline)
				(anchor circle)
			)
			(primitives
				(gr_poly
					(pts
						(arc
							(start -0.1778 -0.2794)
							(mid -0.249642 -0.249642)
							(end -0.2794 -0.1778)
						)
						(arc
							(start -0.2794 0.1778)
							(mid -0.249642 0.249642)
							(end -0.1778 0.2794)
						)
						(arc
							(start 0.1778 0.2794)
							(mid 0.249642 0.249642)
							(end 0.2794 0.1778)
						)
						(arc
							(start 0.2794 -0.1778)
							(mid 0.249642 -0.249642)
							(end 0.1778 -0.2794)
						)
					)
					(width 0)
					(fill yes)
				)
			)
		)
	)
	(footprint ""
		(layer "F.Cu")
		(at 221.799912 -40.620696 90)
		(property "Reference" "R159"
			(at 0 0 90)
			(layer "F.SilkS")
			(hide yes)
			(effects
				(font
					(size 1.27 1.27)
				)
			)
		)
		(property "Value" "330R2F-GP"
			(at 0.064008 -3.993896 90)
			(unlocked yes)
			(layer "F.Fab")
			(hide yes)
			(effects
				(font
					(size 1.016 1.016)
					(thickness 0.1524)
				)
			)
		)
		(property "Device Type" "R402H16"
			(at 0.064008 -5.517896 90)
			(unlocked yes)
			(layer "F.Fab")
			(hide yes)
			(effects
				(font
					(size 1.016 1.016)
					(thickness 0.1524)
				)
			)
		)
		(duplicate_pad_numbers_are_jumpers no)
		(fp_line
			(start 0.508 -0.9398)
			(end -0.508 -0.9398)
			(stroke
				(width 0.1524)
				(type default)
			)
			(layer "F.SilkS")
		)
		(fp_line
			(start -0.508 -0.9398)
			(end -0.508 0.9398)
			(stroke
				(width 0.1524)
				(type default)
			)
			(layer "F.SilkS")
		)
		(fp_rect
			(start -0.508 0.9398)
			(end 0.508 -0.9398)
			(stroke
				(width 0)
				(type default)
			)
			(fill no)
			(layer "F.CrtYd")
		)
		(fp_rect
			(start -0.508 0.9398)
			(end 0.508 -0.9398)
			(stroke
				(width 0)
				(type default)
			)
			(fill no)
			(layer "F.Fab")
		)
		(pad "1" smd custom
			(at 0 -0.4445 90)
			(size 0.1397 0.1397)
			(layers "F.Cu" "F.Mask" "F.Paste")
			(net "P3V3_HDD4_LED")
			(options
				(clearance outline)
				(anchor circle)
			)
			(primitives
				(gr_poly
					(pts
						(arc
							(start -0.1778 -0.2794)
							(mid -0.249642 -0.249642)
							(end -0.2794 -0.1778)
						)
						(arc
							(start -0.2794 0.1778)
							(mid -0.249642 0.249642)
							(end -0.1778 0.2794)
						)
						(arc
							(start 0.1778 0.2794)
							(mid 0.249642 0.249642)
							(end 0.2794 0.1778)
						)
						(arc
							(start 0.2794 -0.1778)
							(mid 0.249642 -0.249642)
							(end 0.1778 -0.2794)
						)
					)
					(width 0)
					(fill yes)
				)
			)
		)
		(pad "2" smd custom
			(at 0 0.4445 90)
			(size 0.1397 0.1397)
			(layers "F.Cu" "F.Mask" "F.Paste")
			(net "FLT_HDD4")
			(options
				(clearance outline)
				(anchor circle)
			)
			(primitives
				(gr_poly
					(pts
						(arc
							(start -0.1778 -0.2794)
							(mid -0.249642 -0.249642)
							(end -0.2794 -0.1778)
						)
						(arc
							(start -0.2794 0.1778)
							(mid -0.249642 0.249642)
							(end -0.1778 0.2794)
						)
						(arc
							(start 0.1778 0.2794)
							(mid 0.249642 0.249642)
							(end 0.2794 0.1778)
						)
						(arc
							(start 0.2794 -0.1778)
							(mid 0.249642 -0.249642)
							(end 0.1778 -0.2794)
						)
					)
					(width 0)
					(fill yes)
				)
			)
		)
	)
	(footprint ""
		(layer "F.Cu")
		(at 190.373 -88.9)
		(property "Reference" "R166"
			(at 0 0 0)
			(layer "F.SilkS")
			(hide yes)
			(effects
				(font
					(size 1.27 1.27)
				)
			)
		)
		(property "Value" "200KR2F-L-GP"
			(at 0.064008 -3.993896 0)
			(unlocked yes)
			(layer "F.Fab")
			(hide yes)
			(effects
				(font
					(size 1.016 1.016)
					(thickness 0.1524)
				)
			)
		)
		(property "Device Type" "R402H16"
			(at 0.064008 -5.517896 0)
			(unlocked yes)
			(layer "F.Fab")
			(hide yes)
			(effects
				(font
					(size 1.016 1.016)
					(thickness 0.1524)
				)
			)
		)
		(duplicate_pad_numbers_are_jumpers no)
		(fp_line
			(start -0.508 -0.9398)
			(end -0.508 0.9398)
			(stroke
				(width 0.1524)
				(type default)
			)
			(layer "F.SilkS")
		)
		(fp_line
			(start 0.508 -0.9398)
			(end -0.508 -0.9398)
			(stroke
				(width 0.1524)
				(type default)
			)
			(layer "F.SilkS")
		)
		(fp_rect
			(start -0.508 0.9398)
			(end 0.508 -0.9398)
			(stroke
				(width 0)
				(type default)
			)
			(fill no)
			(layer "F.CrtYd")
		)
		(fp_rect
			(start -0.508 0.9398)
			(end 0.508 -0.9398)
			(stroke
				(width 0)
				(type default)
			)
			(fill no)
			(layer "F.Fab")
		)
		(pad "1" smd custom
			(at 0 -0.4445)
			(size 0.1397 0.1397)
			(layers "F.Cu" "F.Mask" "F.Paste")
			(net "P12V")
			(options
				(clearance outline)
				(anchor circle)
			)
			(primitives
				(gr_poly
					(pts
						(arc
							(start -0.1778 -0.2794)
							(mid -0.249642 -0.249642)
							(end -0.2794 -0.1778)
						)
						(arc
							(start -0.2794 0.1778)
							(mid -0.249642 0.249642)
							(end -0.1778 0.2794)
						)
						(arc
							(start 0.1778 0.2794)
							(mid 0.249642 0.249642)
							(end 0.2794 0.1778)
						)
						(arc
							(start 0.2794 -0.1778)
							(mid 0.249642 -0.249642)
							(end 0.1778 -0.2794)
						)
					)
					(width 0)
					(fill yes)
				)
			)
		)
		(pad "2" smd custom
			(at 0 0.4445)
			(size 0.1397 0.1397)
			(layers "F.Cu" "F.Mask" "F.Paste")
			(net "SW_HDD4_P")
			(options
				(clearance outline)
				(anchor circle)
			)
			(primitives
				(gr_poly
					(pts
						(arc
							(start -0.1778 -0.2794)
							(mid -0.249642 -0.249642)
							(end -0.2794 -0.1778)
						)
						(arc
							(start -0.2794 0.1778)
							(mid -0.249642 0.249642)
							(end -0.1778 0.2794)
						)
						(arc
							(start 0.1778 0.2794)
							(mid 0.249642 0.249642)
							(end 0.2794 0.1778)
						)
						(arc
							(start 0.2794 -0.1778)
							(mid 0.249642 -0.249642)
							(end 0.1778 -0.2794)
						)
					)
					(width 0)
					(fill yes)
				)
			)
		)
	)
	(footprint ""
		(layer "F.Cu")
		(at 61.213746 -21.8567)
		(property "Reference" "PC23"
			(at 0 0 0)
			(layer "F.SilkS")
			(hide yes)
			(effects
				(font
					(size 1.27 1.27)
				)
			)
		)
		(property "Value" "SC4D7U25V5KX-GP"
			(at -0.0762 -6.1214 0)
			(unlocked yes)
			(layer "F.Fab")
			(hide yes)
			(effects
				(font
					(size 1.016 1.016)
					(thickness 0.1524)
				)
			)
		)
		(property "Device Type" "C805H54"
			(at -0.0762 -8.1534 0)
			(unlocked yes)
			(layer "F.Fab")
			(hide yes)
			(effects
				(font
					(size 1.016 1.016)
					(thickness 0.1524)
				)
			)
		)
		(duplicate_pad_numbers_are_jumpers no)
		(fp_line
			(start 0.635 0)
			(end -0.635 0)
			(stroke
				(width 0.508)
				(type default)
			)
			(layer "F.SilkS")
		)
		(fp_rect
			(start -0.9652 1.778)
			(end 0.9652 -1.778)
			(stroke
				(width 0)
				(type default)
			)
			(fill no)
			(layer "F.CrtYd")
		)
		(fp_poly
			(pts
				(xy -0.9652 -1.778) (xy 0.9652 -1.778) (xy 0.9652 1.778) (xy -0.9652 1.778)
			)
			(stroke
				(width 0)
				(type default)
			)
			(fill no)
			(layer "F.Fab")
		)
		(pad "1" smd rect
			(at 0 -0.9652)
			(size 1.397 1.143)
			(layers "F.Cu" "F.Mask" "F.Paste")
			(net "P5VB_VDD")
		)
		(pad "2" smd rect
			(at 0 0.9652)
			(size 1.397 1.143)
			(layers "F.Cu" "F.Mask" "F.Paste")
			(net "GND")
		)
	)
	(footprint ""
		(layer "F.Cu")
		(at 233.247946 -246.6594 90)
		(property "Reference" "Q36"
			(at 0 0 90)
			(layer "F.SilkS")
			(hide yes)
			(effects
				(font
					(size 1.27 1.27)
				)
			)
		)
		(property "Value" "PMBS3904-1-GP"
			(at 0 -9.0932 90)
			(unlocked yes)
			(layer "F.Fab")
			(hide yes)
			(effects
				(font
					(size 1.016 1.016)
					(thickness 0.1524)
				)
			)
		)
		(property "Device Type" "SOT-23-10H44"
			(at 0 -10.6172 90)
			(unlocked yes)
			(layer "F.Fab")
			(hide yes)
			(effects
				(font
					(size 1.016 1.016)
					(thickness 0.1524)
				)
			)
		)
		(duplicate_pad_numbers_are_jumpers no)
		(fp_line
			(start 1.651 -1.778)
			(end -1.651 -1.778)
			(stroke
				(width 0.1524)
				(type default)
			)
			(layer "F.SilkS")
		)
		(fp_line
			(start -1.651 -1.778)
			(end -1.651 1.778)
			(stroke
				(width 0.1524)
				(type default)
			)
			(layer "F.SilkS")
		)
		(fp_line
			(start 1.651 1.778)
			(end 1.651 -1.778)
			(stroke
				(width 0.1524)
				(type default)
			)
			(layer "F.SilkS")
		)
		(fp_line
			(start -1.651 1.778)
			(end 1.651 1.778)
			(stroke
				(width 0.1524)
				(type default)
			)
			(layer "F.SilkS")
		)
		(fp_line
			(start -0.9906 1.86309)
			(end -0.701294 2.15265)
			(stroke
				(width 0.0127)
				(type default)
			)
			(layer "F.SilkS")
		)
		(fp_line
			(start -0.994156 1.8669)
			(end -0.987044 1.8669)
			(stroke
				(width 0.0127)
				(type default)
			)
			(layer "F.SilkS")
		)
		(fp_line
			(start -1.003808 1.876552)
			(end -0.977646 1.876552)
			(stroke
				(width 0.0127)
				(type default)
			)
			(layer "F.SilkS")
		)
		(fp_line
			(start -0.635 1.8796)
			(end -1.7526 1.8796)
			(stroke
				(width 0.3302)
				(type default)
			)
			(layer "F.SilkS")
		)
		(fp_line
			(start -1.7526 1.8796)
			(end -1.7526 0.9906)
			(stroke
				(width 0.3302)
				(type default)
			)
			(layer "F.SilkS")
		)
		(fp_line
			(start -1.013206 1.88595)
			(end -0.967994 1.88595)
			(stroke
				(width 0.0127)
				(type default)
			)
			(layer "F.SilkS")
		)
		(fp_line
			(start -1.022858 1.895602)
			(end -0.958596 1.895602)
			(stroke
				(width 0.0127)
				(type default)
			)
			(layer "F.SilkS")
		)
		(fp_line
			(start -1.032256 1.905)
			(end -0.948944 1.905)
			(stroke
				(width 0.0127)
				(type default)
			)
			(layer "F.SilkS")
		)
		(fp_line
			(start -1.041908 1.914652)
			(end -0.939546 1.914652)
			(stroke
				(width 0.0127)
				(type default)
			)
			(layer "F.SilkS")
		)
		(fp_line
			(start -1.051306 1.92405)
			(end -0.929894 1.92405)
			(stroke
				(width 0.0127)
				(type default)
			)
			(layer "F.SilkS")
		)
		(fp_line
			(start -1.060958 1.933702)
			(end -0.920496 1.933702)
			(stroke
				(width 0.0127)
				(type default)
			)
			(layer "F.SilkS")
		)
		(fp_line
			(start -1.070356 1.9431)
			(end -0.910844 1.9431)
			(stroke
				(width 0.0127)
				(type default)
			)
			(layer "F.SilkS")
		)
		(fp_line
			(start -1.080008 1.952752)
			(end -0.901446 1.952752)
			(stroke
				(width 0.0127)
				(type default)
			)
			(layer "F.SilkS")
		)
		(fp_line
			(start -1.089406 1.96215)
			(end -0.891794 1.96215)
			(stroke
				(width 0.0127)
				(type default)
			)
			(layer "F.SilkS")
		)
		(fp_line
			(start -1.099058 1.971802)
			(end -0.882396 1.971802)
			(stroke
				(width 0.0127)
				(type default)
			)
			(layer "F.SilkS")
		)
		(fp_line
			(start -1.108456 1.9812)
			(end -0.872744 1.9812)
			(stroke
				(width 0.0127)
				(type default)
			)
			(layer "F.SilkS")
		)
		(fp_line
			(start -1.118108 1.990852)
			(end -0.863346 1.990852)
			(stroke
				(width 0.0127)
				(type default)
			)
			(layer "F.SilkS")
		)
		(fp_line
			(start -1.127506 2.00025)
			(end -0.853694 2.00025)
			(stroke
				(width 0.0127)
				(type default)
			)
			(layer "F.SilkS")
		)
		(fp_line
			(start -1.137158 2.009902)
			(end -0.844296 2.009902)
			(stroke
				(width 0.0127)
				(type default)
			)
			(layer "F.SilkS")
		)
		(fp_line
			(start -1.146556 2.0193)
			(end -0.834644 2.0193)
			(stroke
				(width 0.0127)
				(type default)
			)
			(layer "F.SilkS")
		)
		(fp_line
			(start -1.156208 2.028952)
			(end -0.825246 2.028952)
			(stroke
				(width 0.0127)
				(type default)
			)
			(layer "F.SilkS")
		)
		(fp_line
			(start -1.165606 2.03835)
			(end -0.815594 2.03835)
			(stroke
				(width 0.0127)
				(type default)
			)
			(layer "F.SilkS")
		)
		(fp_line
			(start -1.175258 2.048002)
			(end -0.806196 2.048002)
			(stroke
				(width 0.0127)
				(type default)
			)
			(layer "F.SilkS")
		)
		(fp_line
			(start -1.184656 2.0574)
			(end -0.796544 2.0574)
			(stroke
				(width 0.0127)
				(type default)
			)
			(layer "F.SilkS")
		)
		(fp_line
			(start -1.194308 2.067052)
			(end -0.787146 2.067052)
			(stroke
				(width 0.0127)
				(type default)
			)
			(layer "F.SilkS")
		)
		(fp_line
			(start -1.203706 2.07645)
			(end -0.777494 2.07645)
			(stroke
				(width 0.0127)
				(type default)
			)
			(layer "F.SilkS")
		)
		(fp_line
			(start -1.213358 2.086102)
			(end -0.768096 2.086102)
			(stroke
				(width 0.0127)
				(type default)
			)
			(layer "F.SilkS")
		)
		(fp_line
			(start -1.222756 2.0955)
			(end -0.758444 2.0955)
			(stroke
				(width 0.0127)
				(type default)
			)
			(layer "F.SilkS")
		)
		(fp_line
			(start -1.232408 2.105152)
			(end -0.749046 2.105152)
			(stroke
				(width 0.0127)
				(type default)
			)
			(layer "F.SilkS")
		)
		(fp_line
			(start -1.241806 2.11455)
			(end -0.739394 2.11455)
			(stroke
				(width 0.0127)
				(type default)
			)
			(layer "F.SilkS")
		)
		(fp_line
			(start -1.251458 2.124202)
			(end -0.729996 2.124202)
			(stroke
				(width 0.0127)
				(type default)
			)
			(layer "F.SilkS")
		)
		(fp_line
			(start -1.260856 2.1336)
			(end -0.720344 2.1336)
			(stroke
				(width 0.0127)
				(type default)
			)
			(layer "F.SilkS")
		)
		(fp_line
			(start -0.719074 2.145538)
			(end -1.265936 2.14122)
			(stroke
				(width 0.0127)
				(type default)
			)
			(layer "F.SilkS")
		)
		(fp_line
			(start -1.279398 2.152142)
			(end -0.9906 1.86309)
			(stroke
				(width 0.0127)
				(type default)
			)
			(layer "F.SilkS")
		)
		(fp_line
			(start -0.71628 2.15265)
			(end -1.26492 2.15265)
			(stroke
				(width 0.0127)
				(type default)
			)
			(layer "F.SilkS")
		)
		(fp_line
			(start -1.279144 2.15265)
			(end -0.701294 2.15265)
			(stroke
				(width 0.0127)
				(type default)
			)
			(layer "F.SilkS")
		)
		(fp_poly
			(pts
				(xy -1.285748 2.159) (xy -1.285748 1.8796) (xy -1.778 1.8796) (xy -1.778 -1.8796) (xy 1.778 -1.8796)
				(xy 1.778 1.8796) (xy -0.694944 1.8796) (xy -0.694944 2.159)
			)
			(stroke
				(width 0)
				(type default)
			)
			(fill no)
			(layer "F.CrtYd")
		)
		(fp_poly
			(pts
				(xy -1.285748 2.159) (xy -1.285748 1.8796) (xy -1.778 1.8796) (xy -1.778 -1.8796) (xy 1.778 -1.8796)
				(xy 1.778 1.8796) (xy -0.694944 1.8796) (xy -0.694944 2.159)
			)
			(stroke
				(width 0)
				(type default)
			)
			(fill no)
			(layer "F.Fab")
		)
		(pad "1" smd rect
			(at -0.98425 0.9525 90)
			(size 0.762 1.143)
			(layers "F.Cu" "F.Mask" "F.Paste")
			(net "FLT_HDD2_B")
		)
		(pad "2" smd rect
			(at 0.98425 0.9525 90)
			(size 0.762 1.143)
			(layers "F.Cu" "F.Mask" "F.Paste")
			(net "GND")
		)
		(pad "3" smd rect
			(at 0 -0.9525 90)
			(size 0.762 1.143)
			(layers "F.Cu" "F.Mask" "F.Paste")
			(net "DRIVE_ACT_2")
		)
	)
	(footprint ""
		(layer "F.Cu")
		(at 11.734546 -52.8066 -90)
		(property "Reference" "Q48"
			(at 0 0 270)
			(layer "F.SilkS")
			(hide yes)
			(effects
				(font
					(size 1.27 1.27)
				)
			)
		)
		(property "Value" "PMBS3904-1-GP"
			(at 0 -9.0932 270)
			(unlocked yes)
			(layer "F.Fab")
			(hide yes)
			(effects
				(font
					(size 1.016 1.016)
					(thickness 0.1524)
				)
			)
		)
		(property "Device Type" "SOT-23-10H44"
			(at 0 -10.6172 270)
			(unlocked yes)
			(layer "F.Fab")
			(hide yes)
			(effects
				(font
					(size 1.016 1.016)
					(thickness 0.1524)
				)
			)
		)
		(duplicate_pad_numbers_are_jumpers no)
		(fp_line
			(start -1.279144 2.15265)
			(end -0.701294 2.15265)
			(stroke
				(width 0.0127)
				(type default)
			)
			(layer "F.SilkS")
		)
		(fp_line
			(start -0.71628 2.15265)
			(end -1.26492 2.15265)
			(stroke
				(width 0.0127)
				(type default)
			)
			(layer "F.SilkS")
		)
		(fp_line
			(start -1.279398 2.152142)
			(end -0.9906 1.86309)
			(stroke
				(width 0.0127)
				(type default)
			)
			(layer "F.SilkS")
		)
		(fp_line
			(start -0.719074 2.145538)
			(end -1.265936 2.14122)
			(stroke
				(width 0.0127)
				(type default)
			)
			(layer "F.SilkS")
		)
		(fp_line
			(start -1.260856 2.1336)
			(end -0.720344 2.1336)
			(stroke
				(width 0.0127)
				(type default)
			)
			(layer "F.SilkS")
		)
		(fp_line
			(start -1.251458 2.124202)
			(end -0.729996 2.124202)
			(stroke
				(width 0.0127)
				(type default)
			)
			(layer "F.SilkS")
		)
		(fp_line
			(start -1.241806 2.11455)
			(end -0.739394 2.11455)
			(stroke
				(width 0.0127)
				(type default)
			)
			(layer "F.SilkS")
		)
		(fp_line
			(start -1.232408 2.105152)
			(end -0.749046 2.105152)
			(stroke
				(width 0.0127)
				(type default)
			)
			(layer "F.SilkS")
		)
		(fp_line
			(start -1.222756 2.0955)
			(end -0.758444 2.0955)
			(stroke
				(width 0.0127)
				(type default)
			)
			(layer "F.SilkS")
		)
		(fp_line
			(start -1.213358 2.086102)
			(end -0.768096 2.086102)
			(stroke
				(width 0.0127)
				(type default)
			)
			(layer "F.SilkS")
		)
		(fp_line
			(start -1.203706 2.07645)
			(end -0.777494 2.07645)
			(stroke
				(width 0.0127)
				(type default)
			)
			(layer "F.SilkS")
		)
		(fp_line
			(start -1.194308 2.067052)
			(end -0.787146 2.067052)
			(stroke
				(width 0.0127)
				(type default)
			)
			(layer "F.SilkS")
		)
		(fp_line
			(start -1.184656 2.0574)
			(end -0.796544 2.0574)
			(stroke
				(width 0.0127)
				(type default)
			)
			(layer "F.SilkS")
		)
		(fp_line
			(start -1.175258 2.048002)
			(end -0.806196 2.048002)
			(stroke
				(width 0.0127)
				(type default)
			)
			(layer "F.SilkS")
		)
		(fp_line
			(start -1.165606 2.03835)
			(end -0.815594 2.03835)
			(stroke
				(width 0.0127)
				(type default)
			)
			(layer "F.SilkS")
		)
		(fp_line
			(start -1.156208 2.028952)
			(end -0.825246 2.028952)
			(stroke
				(width 0.0127)
				(type default)
			)
			(layer "F.SilkS")
		)
		(fp_line
			(start -1.146556 2.0193)
			(end -0.834644 2.0193)
			(stroke
				(width 0.0127)
				(type default)
			)
			(layer "F.SilkS")
		)
		(fp_line
			(start -1.137158 2.009902)
			(end -0.844296 2.009902)
			(stroke
				(width 0.0127)
				(type default)
			)
			(layer "F.SilkS")
		)
		(fp_line
			(start -1.127506 2.00025)
			(end -0.853694 2.00025)
			(stroke
				(width 0.0127)
				(type default)
			)
			(layer "F.SilkS")
		)
		(fp_line
			(start -1.118108 1.990852)
			(end -0.863346 1.990852)
			(stroke
				(width 0.0127)
				(type default)
			)
			(layer "F.SilkS")
		)
		(fp_line
			(start -1.108456 1.9812)
			(end -0.872744 1.9812)
			(stroke
				(width 0.0127)
				(type default)
			)
			(layer "F.SilkS")
		)
		(fp_line
			(start -1.099058 1.971802)
			(end -0.882396 1.971802)
			(stroke
				(width 0.0127)
				(type default)
			)
			(layer "F.SilkS")
		)
		(fp_line
			(start -1.089406 1.96215)
			(end -0.891794 1.96215)
			(stroke
				(width 0.0127)
				(type default)
			)
			(layer "F.SilkS")
		)
		(fp_line
			(start -1.080008 1.952752)
			(end -0.901446 1.952752)
			(stroke
				(width 0.0127)
				(type default)
			)
			(layer "F.SilkS")
		)
		(fp_line
			(start -1.070356 1.9431)
			(end -0.910844 1.9431)
			(stroke
				(width 0.0127)
				(type default)
			)
			(layer "F.SilkS")
		)
		(fp_line
			(start -1.060958 1.933702)
			(end -0.920496 1.933702)
			(stroke
				(width 0.0127)
				(type default)
			)
			(layer "F.SilkS")
		)
		(fp_line
			(start -1.051306 1.92405)
			(end -0.929894 1.92405)
			(stroke
				(width 0.0127)
				(type default)
			)
			(layer "F.SilkS")
		)
		(fp_line
			(start -1.041908 1.914652)
			(end -0.939546 1.914652)
			(stroke
				(width 0.0127)
				(type default)
			)
			(layer "F.SilkS")
		)
		(fp_line
			(start -1.032256 1.905)
			(end -0.948944 1.905)
			(stroke
				(width 0.0127)
				(type default)
			)
			(layer "F.SilkS")
		)
		(fp_line
			(start -1.022858 1.895602)
			(end -0.958596 1.895602)
			(stroke
				(width 0.0127)
				(type default)
			)
			(layer "F.SilkS")
		)
		(fp_line
			(start -1.013206 1.88595)
			(end -0.967994 1.88595)
			(stroke
				(width 0.0127)
				(type default)
			)
			(layer "F.SilkS")
		)
		(fp_line
			(start -1.7526 1.8796)
			(end -1.7526 0.9906)
			(stroke
				(width 0.3302)
				(type default)
			)
			(layer "F.SilkS")
		)
		(fp_line
			(start -0.635 1.8796)
			(end -1.7526 1.8796)
			(stroke
				(width 0.3302)
				(type default)
			)
			(layer "F.SilkS")
		)
		(fp_line
			(start -1.003808 1.876552)
			(end -0.977646 1.876552)
			(stroke
				(width 0.0127)
				(type default)
			)
			(layer "F.SilkS")
		)
		(fp_line
			(start -0.994156 1.8669)
			(end -0.987044 1.8669)
			(stroke
				(width 0.0127)
				(type default)
			)
			(layer "F.SilkS")
		)
		(fp_line
			(start -0.9906 1.86309)
			(end -0.701294 2.15265)
			(stroke
				(width 0.0127)
				(type default)
			)
			(layer "F.SilkS")
		)
		(fp_line
			(start -1.651 1.778)
			(end 1.651 1.778)
			(stroke
				(width 0.1524)
				(type default)
			)
			(layer "F.SilkS")
		)
		(fp_line
			(start 1.651 1.778)
			(end 1.651 -1.778)
			(stroke
				(width 0.1524)
				(type default)
			)
			(layer "F.SilkS")
		)
		(fp_line
			(start -1.651 -1.778)
			(end -1.651 1.778)
			(stroke
				(width 0.1524)
				(type default)
			)
			(layer "F.SilkS")
		)
		(fp_line
			(start 1.651 -1.778)
			(end -1.651 -1.778)
			(stroke
				(width 0.1524)
				(type default)
			)
			(layer "F.SilkS")
		)
		(fp_poly
			(pts
				(xy -1.285748 2.159) (xy -1.285748 1.8796) (xy -1.778 1.8796) (xy -1.778 -1.8796) (xy 1.778 -1.8796)
				(xy 1.778 1.8796) (xy -0.694944 1.8796) (xy -0.694944 2.159)
			)
			(stroke
				(width 0)
				(type default)
			)
			(fill no)
			(layer "F.CrtYd")
		)
		(fp_poly
			(pts
				(xy -1.285748 2.159) (xy -1.285748 1.8796) (xy -1.778 1.8796) (xy -1.778 -1.8796) (xy 1.778 -1.8796)
				(xy 1.778 1.8796) (xy -0.694944 1.8796) (xy -0.694944 2.159)
			)
			(stroke
				(width 0)
				(type default)
			)
			(fill no)
			(layer "F.Fab")
		)
		(pad "1" smd rect
			(at -0.98425 0.9525 270)
			(size 0.762 1.143)
			(layers "F.Cu" "F.Mask" "F.Paste")
			(net "FLT_HDD14_B")
		)
		(pad "2" smd rect
			(at 0.98425 0.9525 270)
			(size 0.762 1.143)
			(layers "F.Cu" "F.Mask" "F.Paste")
			(net "GND")
		)
		(pad "3" smd rect
			(at 0 -0.9525 270)
			(size 0.762 1.143)
			(layers "F.Cu" "F.Mask" "F.Paste")
			(net "DRIVE_ACT_14")
		)
	)
	(footprint ""
		(layer "F.Cu")
		(at 32.86506 -366.964214 -90)
		(property "Reference" "C199"
			(at 0 0 270)
			(layer "F.SilkS")
			(hide yes)
			(effects
				(font
					(size 1.27 1.27)
				)
			)
		)
		(property "Value" "SCD01U50V2KX-1GP"
			(at 1.1811 -2.7051 270)
			(unlocked yes)
			(layer "F.Fab")
			(hide yes)
			(effects
				(font
					(size 1.016 1.016)
					(thickness 0.1524)
				)
			)
		)
		(property "Device Type" "C402H22"
			(at 1.1811 -4.2291 270)
			(unlocked yes)
			(layer "F.Fab")
			(hide yes)
			(effects
				(font
					(size 1.016 1.016)
					(thickness 0.1524)
				)
			)
		)
		(duplicate_pad_numbers_are_jumpers no)
		(fp_rect
			(start -0.4318 0.9525)
			(end 0.4318 -0.9525)
			(stroke
				(width 0)
				(type default)
			)
			(fill no)
			(layer "F.CrtYd")
		)
		(fp_rect
			(start -0.4318 0.9525)
			(end 0.4318 -0.9525)
			(stroke
				(width 0)
				(type default)
			)
			(fill no)
			(layer "F.Fab")
		)
		(pad "1" smd custom
			(at 0 -0.4445 270)
			(size 0.1524 0.1524)
			(layers "F.Cu" "F.Mask" "F.Paste")
			(net "SAS2X28_DRIVE_RX_P_A6")
			(options
				(clearance outline)
				(anchor circle)
			)
			(primitives
				(gr_poly
					(pts
						(arc
							(start 0.3048 -0.2032)
							(mid 0.275042 -0.275042)
							(end 0.2032 -0.3048)
						)
						(arc
							(start -0.2032 -0.3048)
							(mid -0.275042 -0.275042)
							(end -0.3048 -0.2032)
						)
						(arc
							(start -0.3048 0.2032)
							(mid -0.275042 0.275042)
							(end -0.2032 0.3048)
						)
						(arc
							(start 0.2032 0.3048)
							(mid 0.275042 0.275042)
							(end 0.3048 0.2032)
						)
					)
					(width 0)
					(fill yes)
				)
			)
		)
		(pad "2" smd custom
			(at 0 0.4445 270)
			(size 0.1524 0.1524)
			(layers "F.Cu" "F.Mask" "F.Paste")
			(net "SAS2X28_A_HDD6_RX_+")
			(options
				(clearance outline)
				(anchor circle)
			)
			(primitives
				(gr_poly
					(pts
						(arc
							(start 0.3048 -0.2032)
							(mid 0.275042 -0.275042)
							(end 0.2032 -0.3048)
						)
						(arc
							(start -0.2032 -0.3048)
							(mid -0.275042 -0.275042)
							(end -0.3048 -0.2032)
						)
						(arc
							(start -0.3048 0.2032)
							(mid -0.275042 0.275042)
							(end -0.2032 0.3048)
						)
						(arc
							(start 0.2032 0.3048)
							(mid 0.275042 0.275042)
							(end 0.3048 0.2032)
						)
					)
					(width 0)
					(fill yes)
				)
			)
		)
	)
	(footprint ""
		(layer "F.Cu")
		(at 198.114412 -77.831696)
		(property "Reference" "C165"
			(at 0 0 0)
			(layer "F.SilkS")
			(hide yes)
			(effects
				(font
					(size 1.27 1.27)
				)
			)
		)
		(property "Value" "SCD1U10V2KX-5GP"
			(at 1.1811 -2.7051 0)
			(unlocked yes)
			(layer "F.Fab")
			(hide yes)
			(effects
				(font
					(size 1.016 1.016)
					(thickness 0.1524)
				)
			)
		)
		(property "Device Type" "C402H22"
			(at 1.1811 -4.2291 0)
			(unlocked yes)
			(layer "F.Fab")
			(hide yes)
			(effects
				(font
					(size 1.016 1.016)
					(thickness 0.1524)
				)
			)
		)
		(duplicate_pad_numbers_are_jumpers no)
		(fp_rect
			(start -0.4318 0.9525)
			(end 0.4318 -0.9525)
			(stroke
				(width 0)
				(type default)
			)
			(fill no)
			(layer "F.CrtYd")
		)
		(fp_rect
			(start -0.4318 0.9525)
			(end 0.4318 -0.9525)
			(stroke
				(width 0)
				(type default)
			)
			(fill no)
			(layer "F.Fab")
		)
		(pad "1" smd custom
			(at 0 -0.4445)
			(size 0.1524 0.1524)
			(layers "F.Cu" "F.Mask" "F.Paste")
			(net "P3V3")
			(options
				(clearance outline)
				(anchor circle)
			)
			(primitives
				(gr_poly
					(pts
						(arc
							(start 0.3048 -0.2032)
							(mid 0.275042 -0.275042)
							(end 0.2032 -0.3048)
						)
						(arc
							(start -0.2032 -0.3048)
							(mid -0.275042 -0.275042)
							(end -0.3048 -0.2032)
						)
						(arc
							(start -0.3048 0.2032)
							(mid -0.275042 0.275042)
							(end -0.2032 0.3048)
						)
						(arc
							(start 0.2032 0.3048)
							(mid 0.275042 0.275042)
							(end 0.3048 0.2032)
						)
					)
					(width 0)
					(fill yes)
				)
			)
		)
		(pad "2" smd custom
			(at 0 0.4445)
			(size 0.1524 0.1524)
			(layers "F.Cu" "F.Mask" "F.Paste")
			(net "GND")
			(options
				(clearance outline)
				(anchor circle)
			)
			(primitives
				(gr_poly
					(pts
						(arc
							(start 0.3048 -0.2032)
							(mid 0.275042 -0.275042)
							(end 0.2032 -0.3048)
						)
						(arc
							(start -0.2032 -0.3048)
							(mid -0.275042 -0.275042)
							(end -0.3048 -0.2032)
						)
						(arc
							(start -0.3048 0.2032)
							(mid -0.275042 0.275042)
							(end -0.2032 0.3048)
						)
						(arc
							(start 0.2032 0.3048)
							(mid 0.275042 0.275042)
							(end 0.3048 0.2032)
						)
					)
					(width 0)
					(fill yes)
				)
			)
		)
	)
	(footprint ""
		(layer "F.Cu")
		(at 227.499926 -479.67011 90)
		(property "Reference" "SKT1"
			(at 0 0 90)
			(layer "F.SilkS")
			(hide yes)
			(effects
				(font
					(size 1.27 1.27)
				)
			)
		)
		(property "Value" "SKT-SATA14P-15P-12-GP"
			(at -22.6187 8.1788 90)
			(unlocked yes)
			(layer "F.Fab")
			(hide yes)
			(effects
				(font
					(size 1.016 1.016)
					(thickness 0.1524)
				)
			)
		)
		(property "Device Type" "87945-1001"
			(at -22.6187 6.6548 90)
			(unlocked yes)
			(layer "F.Fab")
			(hide yes)
			(effects
				(font
					(size 1.016 1.016)
					(thickness 0.1524)
				)
			)
		)
		(duplicate_pad_numbers_are_jumpers no)
		(fp_line
			(start -15.3924 -5.8547)
			(end -16.3576 -5.8547)
			(stroke
				(width 0.3302)
				(type default)
			)
			(layer "F.SilkS")
		)
		(fp_line
			(start 20.4724 -5.7658)
			(end 20.4724 -2.3114)
			(stroke
				(width 0.1524)
				(type default)
			)
			(layer "F.SilkS")
		)
		(fp_line
			(start -20.4724 -5.7658)
			(end 20.4724 -5.7658)
			(stroke
				(width 0.1524)
				(type default)
			)
			(layer "F.SilkS")
		)
		(fp_line
			(start 23.7617 -2.3114)
			(end 23.7617 2.3114)
			(stroke
				(width 0.1524)
				(type default)
			)
			(layer "F.SilkS")
		)
		(fp_line
			(start 20.4724 -2.3114)
			(end 23.7617 -2.3114)
			(stroke
				(width 0.1524)
				(type default)
			)
			(layer "F.SilkS")
		)
		(fp_line
			(start -20.4724 -2.3114)
			(end -20.4724 -5.7658)
			(stroke
				(width 0.1524)
				(type default)
			)
			(layer "F.SilkS")
		)
		(fp_line
			(start -23.7617 -2.3114)
			(end -20.4724 -2.3114)
			(stroke
				(width 0.1524)
				(type default)
			)
			(layer "F.SilkS")
		)
		(fp_line
			(start 23.117556 -0.5461)
			(end 23.117556 0.5461)
			(stroke
				(width 0.3048)
				(type default)
			)
			(layer "F.SilkS")
		)
		(fp_line
			(start -20.882356 -0.5461)
			(end -20.882356 0.5461)
			(stroke
				(width 0.3048)
				(type default)
			)
			(layer "F.SilkS")
		)
		(fp_line
			(start 20.882356 0.5461)
			(end 20.882356 -0.5461)
			(stroke
				(width 0.3048)
				(type default)
			)
			(layer "F.SilkS")
		)
		(fp_line
			(start -23.117556 0.5461)
			(end -23.117556 -0.5461)
			(stroke
				(width 0.3048)
				(type default)
			)
			(layer "F.SilkS")
		)
		(fp_line
			(start 23.7617 2.3114)
			(end 20.4724 2.3114)
			(stroke
				(width 0.1524)
				(type default)
			)
			(layer "F.SilkS")
		)
		(fp_line
			(start 20.4724 2.3114)
			(end 20.4724 9.652)
			(stroke
				(width 0.1524)
				(type default)
			)
			(layer "F.SilkS")
		)
		(fp_line
			(start -20.4724 2.3114)
			(end -23.7617 2.3114)
			(stroke
				(width 0.1524)
				(type default)
			)
			(layer "F.SilkS")
		)
		(fp_line
			(start -23.7617 2.3114)
			(end -23.7617 -2.3114)
			(stroke
				(width 0.1524)
				(type default)
			)
			(layer "F.SilkS")
		)
		(fp_line
			(start 17.8435 7.9502)
			(end -17.8435 7.9502)
			(stroke
				(width 0.1524)
				(type default)
			)
			(layer "F.SilkS")
		)
		(fp_line
			(start -17.8435 7.9502)
			(end -17.8435 9.652)
			(stroke
				(width 0.1524)
				(type default)
			)
			(layer "F.SilkS")
		)
		(fp_line
			(start 20.4724 9.652)
			(end 17.8435 9.652)
			(stroke
				(width 0.1524)
				(type default)
			)
			(layer "F.SilkS")
		)
		(fp_line
			(start 17.8435 9.652)
			(end 17.8435 7.9502)
			(stroke
				(width 0.1524)
				(type default)
			)
			(layer "F.SilkS")
		)
		(fp_line
			(start -17.8435 9.652)
			(end -20.4724 9.652)
			(stroke
				(width 0.1524)
				(type default)
			)
			(layer "F.SilkS")
		)
		(fp_line
			(start -20.4724 9.652)
			(end -20.4724 2.3114)
			(stroke
				(width 0.1524)
				(type default)
			)
			(layer "F.SilkS")
		)
		(fp_arc
			(start 20.882356 -0.5461)
			(mid 21.999956 -1.6637)
			(end 23.117556 -0.5461)
			(stroke
				(width 0.3048)
				(type default)
			)
			(layer "F.SilkS")
		)
		(fp_arc
			(start -23.117556 -0.5461)
			(mid -21.999956 -1.6637)
			(end -20.882356 -0.5461)
			(stroke
				(width 0.3048)
				(type default)
			)
			(layer "F.SilkS")
		)
		(fp_arc
			(start 23.117556 0.5461)
			(mid 21.999956 1.6637)
			(end 20.882356 0.5461)
			(stroke
				(width 0.3048)
				(type default)
			)
			(layer "F.SilkS")
		)
		(fp_arc
			(start -20.882356 0.5461)
			(mid -21.999956 1.6637)
			(end -23.117556 0.5461)
			(stroke
				(width 0.3048)
				(type default)
			)
			(layer "F.SilkS")
		)
		(fp_poly
			(pts
				(xy -15.87119 -5.838698) (xy -15.23619 -6.473698) (xy -16.50619 -6.473698)
			)
			(stroke
				(width 0)
				(type default)
			)
			(fill yes)
			(layer "F.SilkS")
		)
		(fp_poly
			(pts
				(xy -20.2184 -5.5118) (xy 20.2184 -5.5118) (xy 20.2184 -2.0574) (xy 23.5077 -2.0574) (xy 23.5077 2.0574)
				(xy 20.2184 2.0574) (xy 20.2184 9.398) (xy 18.0975 9.398) (xy 18.0975 7.6962) (xy -18.0975 7.6962)
				(xy -18.0975 9.398) (xy -20.2184 9.398) (xy -20.2184 2.0574) (xy -23.5077 2.0574) (xy -23.5077 -2.0574)
				(xy -20.2184 -2.0574)
			)
			(stroke
				(width 0)
				(type default)
			)
			(fill no)
			(layer "F.CrtYd")
		)
		(fp_poly
			(pts
				(xy -20.2184 -5.5118) (xy -20.2184 -6.0198) (xy -20.7264 -6.0198) (xy -20.7264 -2.5654) (xy -24.0157 -2.5654)
				(xy -24.0157 2.5654) (xy -20.7264 2.5654) (xy -20.7264 9.906) (xy -17.5895 9.906) (xy -17.5895 8.2042)
				(xy 17.5895 8.2042) (xy 17.5895 9.906) (xy 20.7264 9.906) (xy 20.7264 2.5654) (xy 24.0157 2.5654)
				(xy 24.0157 -2.5654) (xy 20.7264 -2.5654) (xy 20.7264 -6.0198) (xy -20.21586 -6.0198) (xy -20.21586 -5.5118)
				(xy 20.2184 -5.5118) (xy 20.2184 -2.0574) (xy 23.5077 -2.0574) (xy 23.5077 2.0574) (xy 20.2184 2.0574)
				(xy 20.2184 9.398) (xy 18.0975 9.398) (xy 18.0975 7.6962) (xy -18.0975 7.6962) (xy -18.0975 9.398)
				(xy -20.2184 9.398) (xy -20.2184 2.0574) (xy -23.5077 2.0574) (xy -23.5077 -2.0574) (xy -20.2184 -2.0574)
			)
			(stroke
				(width 0)
				(type default)
			)
			(fill no)
			(layer "F.CrtYd")
		)
		(fp_poly
			(pts
				(xy -20.7264 -6.0198) (xy -20.7264 -2.5654) (xy -24.0157 -2.5654) (xy -24.0157 2.5654) (xy -20.7264 2.5654)
				(xy -20.7264 9.906) (xy -17.5895 9.906) (xy -17.5895 8.2042) (xy 17.5895 8.2042) (xy 17.5895 9.906)
				(xy 20.7264 9.906) (xy 20.7264 2.5654) (xy 24.0157 2.5654) (xy 24.0157 -2.5654) (xy 20.7264 -2.5654)
				(xy 20.7264 -6.0198)
			)
			(stroke
				(width 0)
				(type default)
			)
			(fill no)
			(layer "F.Fab")
		)
		(pad "" np_thru_hole circle
			(at -18.999962 -2.350008 90)
			(size 0.254 0.254)
			(drill 1.8542)
			(layers "*.Cu" "*.Mask")
			(clearance 1.1557)
			(thermal_gap 1.1557)
		)
		(pad "" np_thru_hole circle
			(at 18.999962 -2.350008 90)
			(size 0.254 0.254)
			(drill 1.8542)
			(layers "*.Cu" "*.Mask")
			(clearance 1.1557)
			(thermal_gap 1.1557)
		)
		(pad "H1" thru_hole oval
			(at -21.999956 0 90)
			(size 1.524 2.6162)
			(drill oval 0.8128 1.905)
			(layers "*.Cu" "*.Mask")
			(remove_unused_layers no)
			(net "GND")
			(clearance 0.1524)
			(thermal_gap 0.1524)
		)
		(pad "H2" thru_hole oval
			(at 21.999956 0 90)
			(size 1.524 2.6162)
			(drill oval 0.8128 1.905)
			(layers "*.Cu" "*.Mask")
			(remove_unused_layers no)
			(net "GND")
			(clearance 0.1524)
			(thermal_gap 0.1524)
		)
		(pad "P1" smd rect
			(at -1.89992 -4.249928 90)
			(size 0.6604 2.3876)
			(layers "F.Cu" "F.Mask" "F.Paste")
			(net "Net_75")
		)
		(pad "P2" smd rect
			(at -0.62992 -4.249928 90)
			(size 0.6604 2.3876)
			(layers "F.Cu" "F.Mask" "F.Paste")
			(net "Net_74")
		)
		(pad "P3" smd rect
			(at 0.64008 -4.249928 90)
			(size 0.6604 2.3876)
			(layers "F.Cu" "F.Mask" "F.Paste")
			(net "Net_73")
		)
		(pad "P4" smd rect
			(at 1.91008 -4.249928 90)
			(size 0.6604 2.3876)
			(layers "F.Cu" "F.Mask" "F.Paste")
			(net "GND")
		)
		(pad "P5" smd rect
			(at 3.18008 -4.249928 90)
			(size 0.6604 2.3876)
			(layers "F.Cu" "F.Mask" "F.Paste")
			(net "HDD_PRSNT_NET0")
		)
		(pad "P6" smd rect
			(at 4.45008 -4.249928 90)
			(size 0.6604 2.3876)
			(layers "F.Cu" "F.Mask" "F.Paste")
			(net "GND")
		)
		(pad "P7" smd rect
			(at 5.72008 -4.249928 90)
			(size 0.6604 2.3876)
			(layers "F.Cu" "F.Mask" "F.Paste")
			(net "5V_PRE_0")
		)
		(pad "P8" smd rect
			(at 6.99008 -4.249928 90)
			(size 0.6604 2.3876)
			(layers "F.Cu" "F.Mask" "F.Paste")
			(net "P5V_HDD0")
		)
		(pad "P9" smd rect
			(at 8.26008 -4.249928 90)
			(size 0.6604 2.3876)
			(layers "F.Cu" "F.Mask" "F.Paste")
			(net "P5V_HDD0")
		)
		(pad "P10" smd rect
			(at 9.53008 -4.249928 90)
			(size 0.6604 2.3876)
			(layers "F.Cu" "F.Mask" "F.Paste")
			(net "GND")
		)
		(pad "P11" smd rect
			(at 10.80008 -4.249928 90)
			(size 0.6604 2.3876)
			(layers "F.Cu" "F.Mask" "F.Paste")
			(net "ACT_HDD0")
		)
		(pad "P12" smd rect
			(at 12.07008 -4.249928 90)
			(size 0.6604 2.3876)
			(layers "F.Cu" "F.Mask" "F.Paste")
			(net "GND")
		)
		(pad "P13" smd rect
			(at 13.34008 -4.249928 90)
			(size 0.6604 2.3876)
			(layers "F.Cu" "F.Mask" "F.Paste")
			(net "12V_PRE_0")
		)
		(pad "P14" smd rect
			(at 14.61008 -4.249928 90)
			(size 0.6604 2.3876)
			(layers "F.Cu" "F.Mask" "F.Paste")
			(net "P12V_HDD0")
		)
		(pad "P15" smd rect
			(at 15.88008 -4.249928 90)
			(size 0.6604 2.3876)
			(layers "F.Cu" "F.Mask" "F.Paste")
			(net "P12V_HDD0")
		)
		(pad "S1" smd rect
			(at -15.86992 -4.249928 90)
			(size 0.6604 2.3876)
			(layers "F.Cu" "F.Mask" "F.Paste")
			(net "GND")
		)
		(pad "S2" smd rect
			(at -14.59992 -4.249928 90)
			(size 0.6604 2.3876)
			(layers "F.Cu" "F.Mask" "F.Paste")
			(net "SAS2X28_A_HDD0_TX_+")
		)
		(pad "S3" smd rect
			(at -13.32992 -4.249928 90)
			(size 0.6604 2.3876)
			(layers "F.Cu" "F.Mask" "F.Paste")
			(net "SAS2X28_A_HDD0_TX_-")
		)
		(pad "S4" smd rect
			(at -12.05992 -4.249928 90)
			(size 0.6604 2.3876)
			(layers "F.Cu" "F.Mask" "F.Paste")
			(net "GND")
		)
		(pad "S5" smd rect
			(at -10.78992 -4.249928 90)
			(size 0.6604 2.3876)
			(layers "F.Cu" "F.Mask" "F.Paste")
			(net "SAS2X28_DRIVE_RX_N_A0")
		)
		(pad "S6" smd rect
			(at -9.51992 -4.249928 90)
			(size 0.6604 2.3876)
			(layers "F.Cu" "F.Mask" "F.Paste")
			(net "SAS2X28_DRIVE_RX_P_A0")
		)
		(pad "S7" smd rect
			(at -8.24992 -4.249928 90)
			(size 0.6604 2.3876)
			(layers "F.Cu" "F.Mask" "F.Paste")
			(net "GND")
		)
		(pad "S8" smd rect
			(at -7.480046 -2.100072 90)
			(size 0.508 1.905)
			(layers "F.Cu" "F.Mask" "F.Paste")
			(net "GND")
		)
		(pad "S9" smd rect
			(at -6.679946 -2.100072 90)
			(size 0.508 1.905)
			(layers "F.Cu" "F.Mask" "F.Paste")
			(net "SAS2X28_B_HDD0_TX_+")
		)
		(pad "S10" smd rect
			(at -5.8801 -2.100072 90)
			(size 0.508 1.905)
			(layers "F.Cu" "F.Mask" "F.Paste")
			(net "SAS2X28_B_HDD0_TX_-")
		)
		(pad "S11" smd rect
			(at -5.08 -2.100072 90)
			(size 0.508 1.905)
			(layers "F.Cu" "F.Mask" "F.Paste")
			(net "GND")
		)
		(pad "S12" smd rect
			(at -4.2799 -2.100072 90)
			(size 0.508 1.905)
			(layers "F.Cu" "F.Mask" "F.Paste")
			(net "SAS2X28_DRIVE_RX_N_B0")
		)
		(pad "S13" smd rect
			(at -3.480054 -2.100072 90)
			(size 0.508 1.905)
			(layers "F.Cu" "F.Mask" "F.Paste")
			(net "SAS2X28_DRIVE_RX_P_B0")
		)
		(pad "S14" smd rect
			(at -2.679954 -2.100072 90)
			(size 0.508 1.905)
			(layers "F.Cu" "F.Mask" "F.Paste")
			(net "GND")
		)
		(zone
			(layers "F.Cu" "B.Cu" "In1.Cu" "In2.Cu" "In3.Cu" "In4.Cu" "In5.Cu" "In6.Cu")
			(hatch none 0.5)
			(connect_pads
				(clearance 0)
			)
			(min_thickness 0.25)
			(keepout
				(tracks not_allowed)
				(vias allowed)
				(pads allowed)
				(copperpour not_allowed)
				(footprints allowed)
			)
			(placement
				(enabled no)
				(sheetname "")
			)
			(fill
				(thermal_gap 0.5)
				(thermal_bridge_width 0.5)
				(island_removal_mode 0)
			)
			(polygon
				(pts
					(arc
						(start 226.381818 -498.670072)
						(mid 223.918018 -498.670072)
						(end 226.381818 -498.670072)
					)
				)
			)
		)
		(zone
			(layers "F.Cu" "B.Cu" "In1.Cu" "In2.Cu" "In3.Cu" "In4.Cu" "In5.Cu" "In6.Cu")
			(hatch none 0.5)
			(connect_pads
				(clearance 0)
			)
			(min_thickness 0.25)
			(keepout
				(tracks not_allowed)
				(vias allowed)
				(pads allowed)
				(copperpour not_allowed)
				(footprints allowed)
			)
			(placement
				(enabled no)
				(sheetname "")
			)
			(fill
				(thermal_gap 0.5)
				(thermal_bridge_width 0.5)
				(island_removal_mode 0)
			)
			(polygon
				(pts
					(arc
						(start 226.381818 -460.670148)
						(mid 223.918018 -460.670148)
						(end 226.381818 -460.670148)
					)
				)
			)
		)
	)
	(footprint ""
		(layer "F.Cu")
		(at 42.500042 -453.159876 180)
		(property "Reference" "LED6"
			(at 0 0 180)
			(layer "F.SilkS")
			(hide yes)
			(effects
				(font
					(size 1.27 1.27)
				)
			)
		)
		(property "Value" "LED-RB-4-GP"
			(at 5.88899 1.80848 180)
			(unlocked yes)
			(layer "F.Fab")
			(hide yes)
			(effects
				(font
					(size 1.016 1.016)
					(thickness 0.1524)
				)
			)
		)
		(property "Device Type" "LED1613-4PH20"
			(at 5.88899 0.28448 180)
			(unlocked yes)
			(layer "F.Fab")
			(hide yes)
			(effects
				(font
					(size 1.016 1.016)
					(thickness 0.1524)
				)
			)
		)
		(duplicate_pad_numbers_are_jumpers no)
		(fp_line
			(start 1.4478 0.9652)
			(end -1.4478 0.9652)
			(stroke
				(width 0.1524)
				(type default)
			)
			(layer "F.SilkS")
		)
		(fp_line
			(start 1.4478 -0.9652)
			(end 1.4478 0.9652)
			(stroke
				(width 0.1524)
				(type default)
			)
			(layer "F.SilkS")
		)
		(fp_line
			(start -1.4478 0.9652)
			(end -1.4478 -0.9652)
			(stroke
				(width 0.1524)
				(type default)
			)
			(layer "F.SilkS")
		)
		(fp_line
			(start -1.4478 0.9652)
			(end -1.4478 -0.9652)
			(stroke
				(width 0.508)
				(type default)
			)
			(layer "F.SilkS")
		)
		(fp_line
			(start -1.4478 -0.9652)
			(end 1.4478 -0.9652)
			(stroke
				(width 0.1524)
				(type default)
			)
			(layer "F.SilkS")
		)
		(fp_rect
			(start -0.8001 0.6477)
			(end 0.8001 -0.6477)
			(stroke
				(width 0)
				(type default)
			)
			(fill no)
			(layer "F.CrtYd")
		)
		(fp_poly
			(pts
				(xy -1.7018 1.2192) (xy -1.7018 -0.06223) (xy -0.8001 -0.06223) (xy -0.8001 0.6477) (xy 0.8001 0.6477)
				(xy 0.8001 -0.6477) (xy -0.8001 -0.6477) (xy -0.8001 -0.0635) (xy -1.7018 -0.0635) (xy -1.7018 -1.2192)
				(xy 1.7018 -1.2192) (xy 1.7018 1.2192)
			)
			(stroke
				(width 0)
				(type default)
			)
			(fill no)
			(layer "F.CrtYd")
		)
		(fp_rect
			(start -1.7018 1.2192)
			(end 1.7018 -1.2192)
			(stroke
				(width 0)
				(type default)
			)
			(fill no)
			(layer "F.Fab")
		)
		(pad "1" smd rect
			(at -0.73025 0.4064 180)
			(size 0.9144 0.6096)
			(layers "F.Cu" "F.Mask" "F.Paste")
			(net "DRV_ACT_NET5")
		)
		(pad "2" smd rect
			(at -0.73025 -0.4064 180)
			(size 0.9144 0.6096)
			(layers "F.Cu" "F.Mask" "F.Paste")
			(net "FLT_NET_HDD5")
		)
		(pad "3" smd rect
			(at 0.73025 -0.4064 180)
			(size 0.9144 0.6096)
			(layers "F.Cu" "F.Mask" "F.Paste")
			(net "FLT_HDD5")
		)
		(pad "4" smd rect
			(at 0.73025 0.4064 180)
			(size 0.9144 0.6096)
			(layers "F.Cu" "F.Mask" "F.Paste")
			(net "DRV_ACT_5")
		)
	)
	(footprint ""
		(layer "F.Cu")
		(at 55.244746 -25.2857 180)
		(property "Reference" "PR29"
			(at 0 0 180)
			(layer "F.SilkS")
			(hide yes)
			(effects
				(font
					(size 1.27 1.27)
				)
			)
		)
		(property "Value" "73K2R2F-GP"
			(at 0.064008 -3.993896 180)
			(unlocked yes)
			(layer "F.Fab")
			(hide yes)
			(effects
				(font
					(size 1.016 1.016)
					(thickness 0.1524)
				)
			)
		)
		(property "Device Type" "R402H16"
			(at 0.064008 -5.517896 180)
			(unlocked yes)
			(layer "F.Fab")
			(hide yes)
			(effects
				(font
					(size 1.016 1.016)
					(thickness 0.1524)
				)
			)
		)
		(duplicate_pad_numbers_are_jumpers no)
		(fp_line
			(start 0.508 -0.9398)
			(end -0.508 -0.9398)
			(stroke
				(width 0.1524)
				(type default)
			)
			(layer "F.SilkS")
		)
		(fp_line
			(start -0.508 -0.9398)
			(end -0.508 0.9398)
			(stroke
				(width 0.1524)
				(type default)
			)
			(layer "F.SilkS")
		)
		(fp_rect
			(start -0.508 0.9398)
			(end 0.508 -0.9398)
			(stroke
				(width 0)
				(type default)
			)
			(fill no)
			(layer "F.CrtYd")
		)
		(fp_rect
			(start -0.508 0.9398)
			(end 0.508 -0.9398)
			(stroke
				(width 0)
				(type default)
			)
			(fill no)
			(layer "F.Fab")
		)
		(pad "1" smd custom
			(at 0 -0.4445 180)
			(size 0.1397 0.1397)
			(layers "F.Cu" "F.Mask" "F.Paste")
			(net "P5VB_VFB")
			(options
				(clearance outline)
				(anchor circle)
			)
			(primitives
				(gr_poly
					(pts
						(arc
							(start -0.1778 -0.2794)
							(mid -0.249642 -0.249642)
							(end -0.2794 -0.1778)
						)
						(arc
							(start -0.2794 0.1778)
							(mid -0.249642 0.249642)
							(end -0.1778 0.2794)
						)
						(arc
							(start 0.1778 0.2794)
							(mid 0.249642 0.249642)
							(end 0.2794 0.1778)
						)
						(arc
							(start 0.2794 -0.1778)
							(mid 0.249642 -0.249642)
							(end 0.1778 -0.2794)
						)
					)
					(width 0)
					(fill yes)
				)
			)
		)
		(pad "2" smd custom
			(at 0 0.4445 180)
			(size 0.1397 0.1397)
			(layers "F.Cu" "F.Mask" "F.Paste")
			(net "P5VB_VFB_NET")
			(options
				(clearance outline)
				(anchor circle)
			)
			(primitives
				(gr_poly
					(pts
						(arc
							(start -0.1778 -0.2794)
							(mid -0.249642 -0.249642)
							(end -0.2794 -0.1778)
						)
						(arc
							(start -0.2794 0.1778)
							(mid -0.249642 0.249642)
							(end -0.1778 0.2794)
						)
						(arc
							(start 0.1778 0.2794)
							(mid 0.249642 0.249642)
							(end 0.2794 0.1778)
						)
						(arc
							(start 0.2794 -0.1778)
							(mid 0.249642 -0.249642)
							(end 0.1778 -0.2794)
						)
					)
					(width 0)
					(fill yes)
				)
			)
		)
	)
	(footprint ""
		(layer "F.Cu")
		(at 60.832746 -19.4437 90)
		(property "Reference" "PR19"
			(at 0 0 90)
			(layer "F.SilkS")
			(hide yes)
			(effects
				(font
					(size 1.27 1.27)
				)
			)
		)
		(property "Value" "0R3J-0-U-GP"
			(at -0.0254 -2.5146 90)
			(unlocked yes)
			(layer "F.Fab")
			(hide yes)
			(effects
				(font
					(size 1.016 1.016)
					(thickness 0.1524)
				)
			)
		)
		(property "Device Type" "R603H22"
			(at -0.0254 -4.0386 90)
			(unlocked yes)
			(layer "F.Fab")
			(hide yes)
			(effects
				(font
					(size 1.016 1.016)
					(thickness 0.1524)
				)
			)
		)
		(duplicate_pad_numbers_are_jumpers no)
		(fp_line
			(start 0.2032 0)
			(end 0.4826 0)
			(stroke
				(width 0.2032)
				(type default)
			)
			(layer "F.SilkS")
		)
		(fp_line
			(start -0.4826 0)
			(end -0.2032 0)
			(stroke
				(width 0.2032)
				(type default)
			)
			(layer "F.SilkS")
		)
		(fp_rect
			(start -0.5842 1.3335)
			(end 0.5842 -1.3335)
			(stroke
				(width 0)
				(type default)
			)
			(fill no)
			(layer "F.CrtYd")
		)
		(fp_rect
			(start -0.5842 1.3335)
			(end 0.5842 -1.3335)
			(stroke
				(width 0)
				(type default)
			)
			(fill no)
			(layer "F.Fab")
		)
		(pad "1" smd custom
			(at 0 -0.762 90)
			(size 0.2159 0.2159)
			(layers "F.Cu" "F.Mask" "F.Paste")
			(net "P5VB_12VIN")
			(options
				(clearance outline)
				(anchor circle)
			)
			(primitives
				(gr_poly
					(pts
						(arc
							(start -0.3302 -0.4318)
							(mid -0.402042 -0.402042)
							(end -0.4318 -0.3302)
						)
						(arc
							(start -0.4318 0.3302)
							(mid -0.402042 0.402042)
							(end -0.3302 0.4318)
						)
						(arc
							(start 0.3302 0.4318)
							(mid 0.402042 0.402042)
							(end 0.4318 0.3302)
						)
						(arc
							(start 0.4318 -0.3302)
							(mid 0.402042 -0.402042)
							(end 0.3302 -0.4318)
						)
					)
					(width 0)
					(fill yes)
				)
			)
		)
		(pad "2" smd custom
			(at 0 0.762 90)
			(size 0.2159 0.2159)
			(layers "F.Cu" "F.Mask" "F.Paste")
			(net "P5VB_VDD")
			(options
				(clearance outline)
				(anchor circle)
			)
			(primitives
				(gr_poly
					(pts
						(arc
							(start -0.3302 -0.4318)
							(mid -0.402042 -0.402042)
							(end -0.4318 -0.3302)
						)
						(arc
							(start -0.4318 0.3302)
							(mid -0.402042 0.402042)
							(end -0.3302 0.4318)
						)
						(arc
							(start 0.3302 0.4318)
							(mid 0.402042 0.402042)
							(end 0.4318 0.3302)
						)
						(arc
							(start 0.4318 -0.3302)
							(mid 0.402042 -0.402042)
							(end 0.3302 -0.4318)
						)
					)
					(width 0)
					(fill yes)
				)
			)
		)
	)
	(footprint ""
		(layer "F.Cu")
		(at 43.941746 -232.692702 -90)
		(property "Reference" "R274"
			(at 0 0 270)
			(layer "F.SilkS")
			(hide yes)
			(effects
				(font
					(size 1.27 1.27)
				)
			)
		)
		(property "Value" "4K7R2J-2-GP"
			(at 0.064008 -3.993896 270)
			(unlocked yes)
			(layer "F.Fab")
			(hide yes)
			(effects
				(font
					(size 1.016 1.016)
					(thickness 0.1524)
				)
			)
		)
		(property "Device Type" "R402H16"
			(at 0.064008 -5.517896 270)
			(unlocked yes)
			(layer "F.Fab")
			(hide yes)
			(effects
				(font
					(size 1.016 1.016)
					(thickness 0.1524)
				)
			)
		)
		(duplicate_pad_numbers_are_jumpers no)
		(fp_line
			(start -0.508 -0.9398)
			(end -0.508 0.9398)
			(stroke
				(width 0.1524)
				(type default)
			)
			(layer "F.SilkS")
		)
		(fp_line
			(start 0.508 -0.9398)
			(end -0.508 -0.9398)
			(stroke
				(width 0.1524)
				(type default)
			)
			(layer "F.SilkS")
		)
		(fp_rect
			(start -0.508 0.9398)
			(end 0.508 -0.9398)
			(stroke
				(width 0)
				(type default)
			)
			(fill no)
			(layer "F.CrtYd")
		)
		(fp_rect
			(start -0.508 0.9398)
			(end 0.508 -0.9398)
			(stroke
				(width 0)
				(type default)
			)
			(fill no)
			(layer "F.Fab")
		)
		(pad "1" smd custom
			(at 0 -0.4445 270)
			(size 0.1397 0.1397)
			(layers "F.Cu" "F.Mask" "F.Paste")
			(net "P3V3")
			(options
				(clearance outline)
				(anchor circle)
			)
			(primitives
				(gr_poly
					(pts
						(arc
							(start -0.1778 -0.2794)
							(mid -0.249642 -0.249642)
							(end -0.2794 -0.1778)
						)
						(arc
							(start -0.2794 0.1778)
							(mid -0.249642 0.249642)
							(end -0.1778 0.2794)
						)
						(arc
							(start 0.1778 0.2794)
							(mid 0.249642 0.249642)
							(end 0.2794 0.1778)
						)
						(arc
							(start 0.2794 -0.1778)
							(mid 0.249642 -0.249642)
							(end 0.1778 -0.2794)
						)
					)
					(width 0)
					(fill yes)
				)
			)
		)
		(pad "2" smd custom
			(at 0 0.4445 270)
			(size 0.1397 0.1397)
			(layers "F.Cu" "F.Mask" "F.Paste")
			(net "HDD_PRSNT_NET12")
			(options
				(clearance outline)
				(anchor circle)
			)
			(primitives
				(gr_poly
					(pts
						(arc
							(start -0.1778 -0.2794)
							(mid -0.249642 -0.249642)
							(end -0.2794 -0.1778)
						)
						(arc
							(start -0.2794 0.1778)
							(mid -0.249642 0.249642)
							(end -0.1778 0.2794)
						)
						(arc
							(start 0.1778 0.2794)
							(mid 0.249642 0.249642)
							(end 0.2794 0.1778)
						)
						(arc
							(start 0.2794 -0.1778)
							(mid 0.249642 -0.249642)
							(end 0.1778 -0.2794)
						)
					)
					(width 0)
					(fill yes)
				)
			)
		)
	)
	(footprint ""
		(layer "F.Cu")
		(at 28.701746 -278.5237 -90)
		(property "Reference" "U24"
			(at 0 0 270)
			(layer "F.SilkS")
			(hide yes)
			(effects
				(font
					(size 1.27 1.27)
				)
			)
		)
		(property "Value" "74LVC1G08GW-1-GP"
			(at -2.3368 -8.6868 270)
			(unlocked yes)
			(layer "F.Fab")
			(hide yes)
			(effects
				(font
					(size 1.016 1.016)
					(thickness 0.1524)
				)
			)
		)
		(property "Device Type" "SC70-5H44"
			(at -2.3114 -10.414 270)
			(unlocked yes)
			(layer "F.Fab")
			(hide yes)
			(effects
				(font
					(size 1.016 1.016)
					(thickness 0.1524)
				)
			)
		)
		(duplicate_pad_numbers_are_jumpers no)
		(fp_line
			(start -1.27 1.7018)
			(end -1.27 -1.7018)
			(stroke
				(width 0.1524)
				(type default)
			)
			(layer "F.SilkS")
		)
		(fp_line
			(start 1.27 1.7018)
			(end -1.27 1.7018)
			(stroke
				(width 0.1524)
				(type default)
			)
			(layer "F.SilkS")
		)
		(fp_line
			(start -1.27 -1.7018)
			(end 1.27 -1.7018)
			(stroke
				(width 0.1524)
				(type default)
			)
			(layer "F.SilkS")
		)
		(fp_line
			(start 1.27 -1.7018)
			(end 1.27 1.7018)
			(stroke
				(width 0.1524)
				(type default)
			)
			(layer "F.SilkS")
		)
		(fp_line
			(start 0.6604 -1.8034)
			(end 1.3843 -1.8034)
			(stroke
				(width 0.3302)
				(type default)
			)
			(layer "F.SilkS")
		)
		(fp_line
			(start 1.3843 -1.8034)
			(end 1.3843 -1.1176)
			(stroke
				(width 0.3302)
				(type default)
			)
			(layer "F.SilkS")
		)
		(fp_rect
			(start -1.524 1.9558)
			(end 1.524 -1.9558)
			(stroke
				(width 0)
				(type default)
			)
			(fill no)
			(layer "F.CrtYd")
		)
		(fp_poly
			(pts
				(xy -1.524 -1.9558) (xy 1.524 -1.9558) (xy 1.524 1.9558) (xy -1.524 1.9558)
			)
			(stroke
				(width 0)
				(type default)
			)
			(fill no)
			(layer "F.Fab")
		)
		(pad "1" smd rect
			(at 0.65024 -0.8255 270)
			(size 0.4064 1.2192)
			(layers "F.Cu" "F.Mask" "F.Paste")
			(net "SAS_EXP_B_PWR7")
		)
		(pad "2" smd rect
			(at 0 -0.8255 270)
			(size 0.4064 1.2192)
			(layers "F.Cu" "F.Mask" "F.Paste")
			(net "SAS_EXP_A_PWR7")
		)
		(pad "3" smd rect
			(at -0.65024 -0.8255 270)
			(size 0.4064 1.2192)
			(layers "F.Cu" "F.Mask" "F.Paste")
			(net "GND")
		)
		(pad "4" smd rect
			(at -0.65024 0.8255 270)
			(size 0.4064 1.2192)
			(layers "F.Cu" "F.Mask" "F.Paste")
			(net "DRIVE_PWR7")
		)
		(pad "5" smd rect
			(at 0.65024 0.8255 270)
			(size 0.4064 1.2192)
			(layers "F.Cu" "F.Mask" "F.Paste")
			(net "P3V3")
		)
	)
	(footprint ""
		(layer "F.Cu")
		(at 14.715744 -259.3467 -90)
		(property "Reference" "R270"
			(at 0 0 270)
			(layer "F.SilkS")
			(hide yes)
			(effects
				(font
					(size 1.27 1.27)
				)
			)
		)
		(property "Value" "0R2J-2-GP"
			(at 0.064008 -3.993896 270)
			(unlocked yes)
			(layer "F.Fab")
			(hide yes)
			(effects
				(font
					(size 1.016 1.016)
					(thickness 0.1524)
				)
			)
		)
		(property "Device Type" "R402H16"
			(at 0.064008 -5.517896 270)
			(unlocked yes)
			(layer "F.Fab")
			(hide yes)
			(effects
				(font
					(size 1.016 1.016)
					(thickness 0.1524)
				)
			)
		)
		(duplicate_pad_numbers_are_jumpers no)
		(fp_line
			(start -0.508 -0.9398)
			(end -0.508 0.9398)
			(stroke
				(width 0.1524)
				(type default)
			)
			(layer "F.SilkS")
		)
		(fp_line
			(start 0.508 -0.9398)
			(end -0.508 -0.9398)
			(stroke
				(width 0.1524)
				(type default)
			)
			(layer "F.SilkS")
		)
		(fp_rect
			(start -0.508 0.9398)
			(end 0.508 -0.9398)
			(stroke
				(width 0)
				(type default)
			)
			(fill no)
			(layer "F.CrtYd")
		)
		(fp_rect
			(start -0.508 0.9398)
			(end 0.508 -0.9398)
			(stroke
				(width 0)
				(type default)
			)
			(fill no)
			(layer "F.Fab")
		)
		(pad "1" smd custom
			(at 0 -0.4445 270)
			(size 0.1397 0.1397)
			(layers "F.Cu" "F.Mask" "F.Paste")
			(net "DRV_ACT_NET12")
			(options
				(clearance outline)
				(anchor circle)
			)
			(primitives
				(gr_poly
					(pts
						(arc
							(start -0.1778 -0.2794)
							(mid -0.249642 -0.249642)
							(end -0.2794 -0.1778)
						)
						(arc
							(start -0.2794 0.1778)
							(mid -0.249642 0.249642)
							(end -0.1778 0.2794)
						)
						(arc
							(start 0.1778 0.2794)
							(mid 0.249642 0.249642)
							(end 0.2794 0.1778)
						)
						(arc
							(start 0.2794 -0.1778)
							(mid 0.249642 -0.249642)
							(end 0.1778 -0.2794)
						)
					)
					(width 0)
					(fill yes)
				)
			)
		)
		(pad "2" smd custom
			(at 0 0.4445 270)
			(size 0.1397 0.1397)
			(layers "F.Cu" "F.Mask" "F.Paste")
			(net "DRIVE_ACT_12")
			(options
				(clearance outline)
				(anchor circle)
			)
			(primitives
				(gr_poly
					(pts
						(arc
							(start -0.1778 -0.2794)
							(mid -0.249642 -0.249642)
							(end -0.2794 -0.1778)
						)
						(arc
							(start -0.2794 0.1778)
							(mid -0.249642 0.249642)
							(end -0.1778 0.2794)
						)
						(arc
							(start 0.1778 0.2794)
							(mid 0.249642 0.249642)
							(end 0.2794 0.1778)
						)
						(arc
							(start 0.2794 -0.1778)
							(mid 0.249642 -0.249642)
							(end 0.1778 -0.2794)
						)
					)
					(width 0)
					(fill yes)
				)
			)
		)
	)
	(footprint ""
		(layer "F.Cu")
		(at 166.509446 -457.742036)
		(property "Reference" "C353"
			(at 0 0 0)
			(layer "F.SilkS")
			(hide yes)
			(effects
				(font
					(size 1.27 1.27)
				)
			)
		)
		(property "Value" "SCD1U16V2KX-3GP"
			(at 1.1811 -2.7051 0)
			(unlocked yes)
			(layer "F.Fab")
			(hide yes)
			(effects
				(font
					(size 1.016 1.016)
					(thickness 0.1524)
				)
			)
		)
		(property "Device Type" "C402H22"
			(at 1.1811 -4.2291 0)
			(unlocked yes)
			(layer "F.Fab")
			(hide yes)
			(effects
				(font
					(size 1.016 1.016)
					(thickness 0.1524)
				)
			)
		)
		(duplicate_pad_numbers_are_jumpers no)
		(fp_rect
			(start -0.4318 0.9525)
			(end 0.4318 -0.9525)
			(stroke
				(width 0)
				(type default)
			)
			(fill no)
			(layer "F.CrtYd")
		)
		(fp_rect
			(start -0.4318 0.9525)
			(end 0.4318 -0.9525)
			(stroke
				(width 0)
				(type default)
			)
			(fill no)
			(layer "F.Fab")
		)
		(pad "1" smd custom
			(at 0 -0.4445)
			(size 0.1524 0.1524)
			(layers "F.Cu" "F.Mask" "F.Paste")
			(net "P5VA_SENSE")
			(options
				(clearance outline)
				(anchor circle)
			)
			(primitives
				(gr_poly
					(pts
						(arc
							(start 0.3048 -0.2032)
							(mid 0.275042 -0.275042)
							(end 0.2032 -0.3048)
						)
						(arc
							(start -0.2032 -0.3048)
							(mid -0.275042 -0.275042)
							(end -0.3048 -0.2032)
						)
						(arc
							(start -0.3048 0.2032)
							(mid -0.275042 0.275042)
							(end -0.2032 0.3048)
						)
						(arc
							(start 0.2032 0.3048)
							(mid 0.275042 0.275042)
							(end 0.3048 0.2032)
						)
					)
					(width 0)
					(fill yes)
				)
			)
		)
		(pad "2" smd custom
			(at 0 0.4445)
			(size 0.1524 0.1524)
			(layers "F.Cu" "F.Mask" "F.Paste")
			(net "GND")
			(options
				(clearance outline)
				(anchor circle)
			)
			(primitives
				(gr_poly
					(pts
						(arc
							(start 0.3048 -0.2032)
							(mid 0.275042 -0.275042)
							(end 0.2032 -0.3048)
						)
						(arc
							(start -0.2032 -0.3048)
							(mid -0.275042 -0.275042)
							(end -0.3048 -0.2032)
						)
						(arc
							(start -0.3048 0.2032)
							(mid -0.275042 0.275042)
							(end -0.2032 0.3048)
						)
						(arc
							(start 0.2032 0.3048)
							(mid 0.275042 0.275042)
							(end 0.3048 0.2032)
						)
					)
					(width 0)
					(fill yes)
				)
			)
		)
	)
	(footprint ""
		(layer "F.Cu")
		(at 33.893252 -160.92551 -90)
		(property "Reference" "C231"
			(at 0 0 270)
			(layer "F.SilkS")
			(hide yes)
			(effects
				(font
					(size 1.27 1.27)
				)
			)
		)
		(property "Value" "SCD01U50V2KX-1GP"
			(at 1.1811 -2.7051 270)
			(unlocked yes)
			(layer "F.Fab")
			(hide yes)
			(effects
				(font
					(size 1.016 1.016)
					(thickness 0.1524)
				)
			)
		)
		(property "Device Type" "C402H22"
			(at 1.1811 -4.2291 270)
			(unlocked yes)
			(layer "F.Fab")
			(hide yes)
			(effects
				(font
					(size 1.016 1.016)
					(thickness 0.1524)
				)
			)
		)
		(duplicate_pad_numbers_are_jumpers no)
		(fp_rect
			(start -0.4318 0.9525)
			(end 0.4318 -0.9525)
			(stroke
				(width 0)
				(type default)
			)
			(fill no)
			(layer "F.CrtYd")
		)
		(fp_rect
			(start -0.4318 0.9525)
			(end 0.4318 -0.9525)
			(stroke
				(width 0)
				(type default)
			)
			(fill no)
			(layer "F.Fab")
		)
		(pad "1" smd custom
			(at 0 -0.4445 270)
			(size 0.1524 0.1524)
			(layers "F.Cu" "F.Mask" "F.Paste")
			(net "SAS2X28_DRIVE_RX_P_A8")
			(options
				(clearance outline)
				(anchor circle)
			)
			(primitives
				(gr_poly
					(pts
						(arc
							(start 0.3048 -0.2032)
							(mid 0.275042 -0.275042)
							(end 0.2032 -0.3048)
						)
						(arc
							(start -0.2032 -0.3048)
							(mid -0.275042 -0.275042)
							(end -0.3048 -0.2032)
						)
						(arc
							(start -0.3048 0.2032)
							(mid -0.275042 0.275042)
							(end -0.2032 0.3048)
						)
						(arc
							(start 0.2032 0.3048)
							(mid 0.275042 0.275042)
							(end 0.3048 0.2032)
						)
					)
					(width 0)
					(fill yes)
				)
			)
		)
		(pad "2" smd custom
			(at 0 0.4445 270)
			(size 0.1524 0.1524)
			(layers "F.Cu" "F.Mask" "F.Paste")
			(net "SAS2X28_A_HDD8_RX_+")
			(options
				(clearance outline)
				(anchor circle)
			)
			(primitives
				(gr_poly
					(pts
						(arc
							(start 0.3048 -0.2032)
							(mid 0.275042 -0.275042)
							(end 0.2032 -0.3048)
						)
						(arc
							(start -0.2032 -0.3048)
							(mid -0.275042 -0.275042)
							(end -0.3048 -0.2032)
						)
						(arc
							(start -0.3048 0.2032)
							(mid -0.275042 0.275042)
							(end -0.2032 0.3048)
						)
						(arc
							(start 0.2032 0.3048)
							(mid 0.275042 0.275042)
							(end 0.3048 0.2032)
						)
					)
					(width 0)
					(fill yes)
				)
			)
		)
	)
	(footprint ""
		(layer "F.Cu")
		(at 218.1606 -393.9032 180)
		(property "Reference" "C129"
			(at 0 0 180)
			(layer "F.SilkS")
			(hide yes)
			(effects
				(font
					(size 1.27 1.27)
				)
			)
		)
		(property "Value" "SC10U25V6KX-1GP"
			(at -0.0762 -5.1308 180)
			(unlocked yes)
			(layer "F.Fab")
			(hide yes)
			(effects
				(font
					(size 1.016 1.016)
					(thickness 0.1524)
				)
			)
		)
		(property "Device Type" "C1206H71"
			(at -0.127 -6.6548 180)
			(unlocked yes)
			(layer "F.Fab")
			(hide yes)
			(effects
				(font
					(size 1.016 1.016)
					(thickness 0.1524)
				)
			)
		)
		(duplicate_pad_numbers_are_jumpers no)
		(fp_line
			(start 1.016 2.2352)
			(end -1.016 2.2352)
			(stroke
				(width 0.1524)
				(type default)
			)
			(layer "F.SilkS")
		)
		(fp_line
			(start 1.016 0.8382)
			(end 1.016 2.2352)
			(stroke
				(width 0.1524)
				(type default)
			)
			(layer "F.SilkS")
		)
		(fp_line
			(start 1.016 -2.2352)
			(end 1.016 -0.8382)
			(stroke
				(width 0.1524)
				(type default)
			)
			(layer "F.SilkS")
		)
		(fp_line
			(start -1.016 2.2352)
			(end -1.016 0.8382)
			(stroke
				(width 0.1524)
				(type default)
			)
			(layer "F.SilkS")
		)
		(fp_line
			(start -1.016 -0.8382)
			(end -1.016 -2.2352)
			(stroke
				(width 0.1524)
				(type default)
			)
			(layer "F.SilkS")
		)
		(fp_line
			(start -1.016 -2.2352)
			(end 1.016 -2.2352)
			(stroke
				(width 0.1524)
				(type default)
			)
			(layer "F.SilkS")
		)
		(fp_rect
			(start -1.0922 2.3114)
			(end 1.0922 -2.3114)
			(stroke
				(width 0)
				(type default)
			)
			(fill no)
			(layer "F.CrtYd")
		)
		(fp_poly
			(pts
				(xy 1.0922 -2.3114) (xy 1.0922 2.3114) (xy -1.0922 2.3114) (xy -1.0922 -2.3114)
			)
			(stroke
				(width 0)
				(type default)
			)
			(fill no)
			(layer "F.Fab")
		)
		(pad "1" smd rect
			(at 0 -1.397 180)
			(size 1.651 1.27)
			(layers "F.Cu" "F.Mask" "F.Paste")
			(net "P12V_HDD1")
		)
		(pad "2" smd rect
			(at 0 1.397 180)
			(size 1.651 1.27)
			(layers "F.Cu" "F.Mask" "F.Paste")
			(net "GND")
		)
	)
	(footprint ""
		(layer "F.Cu")
		(at 56.752744 -481.42271 180)
		(property "Reference" "R176"
			(at 0 0 180)
			(layer "F.SilkS")
			(hide yes)
			(effects
				(font
					(size 1.27 1.27)
				)
			)
		)
		(property "Value" "4K7R2J-2-GP"
			(at 0.064008 -3.993896 180)
			(unlocked yes)
			(layer "F.Fab")
			(hide yes)
			(effects
				(font
					(size 1.016 1.016)
					(thickness 0.1524)
				)
			)
		)
		(property "Device Type" "R402H16"
			(at 0.064008 -5.517896 180)
			(unlocked yes)
			(layer "F.Fab")
			(hide yes)
			(effects
				(font
					(size 1.016 1.016)
					(thickness 0.1524)
				)
			)
		)
		(duplicate_pad_numbers_are_jumpers no)
		(fp_line
			(start 0.508 -0.9398)
			(end -0.508 -0.9398)
			(stroke
				(width 0.1524)
				(type default)
			)
			(layer "F.SilkS")
		)
		(fp_line
			(start -0.508 -0.9398)
			(end -0.508 0.9398)
			(stroke
				(width 0.1524)
				(type default)
			)
			(layer "F.SilkS")
		)
		(fp_rect
			(start -0.508 0.9398)
			(end 0.508 -0.9398)
			(stroke
				(width 0)
				(type default)
			)
			(fill no)
			(layer "F.CrtYd")
		)
		(fp_rect
			(start -0.508 0.9398)
			(end 0.508 -0.9398)
			(stroke
				(width 0)
				(type default)
			)
			(fill no)
			(layer "F.Fab")
		)
		(pad "1" smd custom
			(at 0 -0.4445 180)
			(size 0.1397 0.1397)
			(layers "F.Cu" "F.Mask" "F.Paste")
			(net "P3V3")
			(options
				(clearance outline)
				(anchor circle)
			)
			(primitives
				(gr_poly
					(pts
						(arc
							(start -0.1778 -0.2794)
							(mid -0.249642 -0.249642)
							(end -0.2794 -0.1778)
						)
						(arc
							(start -0.2794 0.1778)
							(mid -0.249642 0.249642)
							(end -0.1778 0.2794)
						)
						(arc
							(start 0.1778 0.2794)
							(mid 0.249642 0.249642)
							(end 0.2794 0.1778)
						)
						(arc
							(start 0.2794 -0.1778)
							(mid 0.249642 -0.249642)
							(end 0.1778 -0.2794)
						)
					)
					(width 0)
					(fill yes)
				)
			)
		)
		(pad "2" smd custom
			(at 0 0.4445 180)
			(size 0.1397 0.1397)
			(layers "F.Cu" "F.Mask" "F.Paste")
			(net "HDD_PRSNT_NET5")
			(options
				(clearance outline)
				(anchor circle)
			)
			(primitives
				(gr_poly
					(pts
						(arc
							(start -0.1778 -0.2794)
							(mid -0.249642 -0.249642)
							(end -0.2794 -0.1778)
						)
						(arc
							(start -0.2794 0.1778)
							(mid -0.249642 0.249642)
							(end -0.1778 0.2794)
						)
						(arc
							(start 0.1778 0.2794)
							(mid 0.249642 0.249642)
							(end 0.2794 0.1778)
						)
						(arc
							(start 0.2794 -0.1778)
							(mid 0.249642 -0.249642)
							(end 0.1778 -0.2794)
						)
					)
					(width 0)
					(fill yes)
				)
			)
		)
	)
	(footprint ""
		(layer "F.Cu")
		(at 4.445 -278.765 90)
		(property "Reference" "C148"
			(at 0 0 90)
			(layer "F.SilkS")
			(hide yes)
			(effects
				(font
					(size 1.27 1.27)
				)
			)
		)
		(property "Value" "SC1U25V3KX-1-GP"
			(at 0 -2.8194 90)
			(unlocked yes)
			(layer "F.Fab")
			(hide yes)
			(effects
				(font
					(size 1.016 1.016)
					(thickness 0.1524)
				)
			)
		)
		(property "Device Type" "C603H36"
			(at 0 -4.3434 90)
			(unlocked yes)
			(layer "F.Fab")
			(hide yes)
			(effects
				(font
					(size 1.016 1.016)
					(thickness 0.1524)
				)
			)
		)
		(duplicate_pad_numbers_are_jumpers no)
		(fp_line
			(start 0.508 0)
			(end -0.508 0)
			(stroke
				(width 0.2032)
				(type default)
			)
			(layer "F.SilkS")
		)
		(fp_rect
			(start -0.5842 1.3335)
			(end 0.5842 -1.3335)
			(stroke
				(width 0)
				(type default)
			)
			(fill no)
			(layer "F.CrtYd")
		)
		(fp_rect
			(start -0.5842 1.3335)
			(end 0.5842 -1.3335)
			(stroke
				(width 0)
				(type default)
			)
			(fill no)
			(layer "F.Fab")
		)
		(pad "1" smd custom
			(at 0 -0.762 90)
			(size 0.2159 0.2159)
			(layers "F.Cu" "F.Mask" "F.Paste")
			(net "P12V")
			(options
				(clearance outline)
				(anchor circle)
			)
			(primitives
				(gr_poly
					(pts
						(arc
							(start -0.3302 -0.4318)
							(mid -0.402042 -0.402042)
							(end -0.4318 -0.3302)
						)
						(arc
							(start -0.4318 0.3302)
							(mid -0.402042 0.402042)
							(end -0.3302 0.4318)
						)
						(arc
							(start 0.3302 0.4318)
							(mid 0.402042 0.402042)
							(end 0.4318 0.3302)
						)
						(arc
							(start 0.4318 -0.3302)
							(mid 0.402042 -0.402042)
							(end 0.3302 -0.4318)
						)
					)
					(width 0)
					(fill yes)
				)
			)
		)
		(pad "2" smd custom
			(at 0 0.762 90)
			(size 0.2159 0.2159)
			(layers "F.Cu" "F.Mask" "F.Paste")
			(net "GND")
			(options
				(clearance outline)
				(anchor circle)
			)
			(primitives
				(gr_poly
					(pts
						(arc
							(start -0.3302 -0.4318)
							(mid -0.402042 -0.402042)
							(end -0.4318 -0.3302)
						)
						(arc
							(start -0.4318 0.3302)
							(mid -0.402042 0.402042)
							(end -0.3302 0.4318)
						)
						(arc
							(start 0.3302 0.4318)
							(mid 0.402042 0.402042)
							(end 0.4318 0.3302)
						)
						(arc
							(start 0.4318 -0.3302)
							(mid 0.402042 -0.402042)
							(end 0.3302 -0.4318)
						)
					)
					(width 0)
					(fill yes)
				)
			)
		)
	)
	(footprint ""
		(layer "F.Cu")
		(at 225.323654 -438.7723 90)
		(property "Reference" "PR53"
			(at 0 0 90)
			(layer "F.SilkS")
			(hide yes)
			(effects
				(font
					(size 1.27 1.27)
				)
			)
		)
		(property "Value" "470KR2F-GP"
			(at 0.064008 -3.993896 90)
			(unlocked yes)
			(layer "F.Fab")
			(hide yes)
			(effects
				(font
					(size 1.016 1.016)
					(thickness 0.1524)
				)
			)
		)
		(property "Device Type" "R402H16"
			(at 0.064008 -5.517896 90)
			(unlocked yes)
			(layer "F.Fab")
			(hide yes)
			(effects
				(font
					(size 1.016 1.016)
					(thickness 0.1524)
				)
			)
		)
		(duplicate_pad_numbers_are_jumpers no)
		(fp_line
			(start 0.508 -0.9398)
			(end -0.508 -0.9398)
			(stroke
				(width 0.1524)
				(type default)
			)
			(layer "F.SilkS")
		)
		(fp_line
			(start -0.508 -0.9398)
			(end -0.508 0.9398)
			(stroke
				(width 0.1524)
				(type default)
			)
			(layer "F.SilkS")
		)
		(fp_rect
			(start -0.508 0.9398)
			(end 0.508 -0.9398)
			(stroke
				(width 0)
				(type default)
			)
			(fill no)
			(layer "F.CrtYd")
		)
		(fp_rect
			(start -0.508 0.9398)
			(end 0.508 -0.9398)
			(stroke
				(width 0)
				(type default)
			)
			(fill no)
			(layer "F.Fab")
		)
		(pad "1" smd custom
			(at 0 -0.4445 90)
			(size 0.1397 0.1397)
			(layers "F.Cu" "F.Mask" "F.Paste")
			(net "P3V3_EN")
			(options
				(clearance outline)
				(anchor circle)
			)
			(primitives
				(gr_poly
					(pts
						(arc
							(start -0.1778 -0.2794)
							(mid -0.249642 -0.249642)
							(end -0.2794 -0.1778)
						)
						(arc
							(start -0.2794 0.1778)
							(mid -0.249642 0.249642)
							(end -0.1778 0.2794)
						)
						(arc
							(start 0.1778 0.2794)
							(mid 0.249642 0.249642)
							(end 0.2794 0.1778)
						)
						(arc
							(start 0.2794 -0.1778)
							(mid 0.249642 -0.249642)
							(end 0.1778 -0.2794)
						)
					)
					(width 0)
					(fill yes)
				)
			)
		)
		(pad "2" smd custom
			(at 0 0.4445 90)
			(size 0.1397 0.1397)
			(layers "F.Cu" "F.Mask" "F.Paste")
			(net "GND")
			(options
				(clearance outline)
				(anchor circle)
			)
			(primitives
				(gr_poly
					(pts
						(arc
							(start -0.1778 -0.2794)
							(mid -0.249642 -0.249642)
							(end -0.2794 -0.1778)
						)
						(arc
							(start -0.2794 0.1778)
							(mid -0.249642 0.249642)
							(end -0.1778 0.2794)
						)
						(arc
							(start 0.1778 0.2794)
							(mid 0.249642 0.249642)
							(end 0.2794 0.1778)
						)
						(arc
							(start 0.2794 -0.1778)
							(mid 0.249642 -0.249642)
							(end 0.1778 -0.2794)
						)
					)
					(width 0)
					(fill yes)
				)
			)
		)
	)
	(footprint ""
		(layer "F.Cu")
		(at 194.177412 -82.911696 -90)
		(property "Reference" "U15"
			(at 0 0 270)
			(layer "F.SilkS")
			(hide yes)
			(effects
				(font
					(size 1.27 1.27)
				)
			)
		)
		(property "Value" "74LVC1G08GW-1-GP"
			(at -2.3368 -8.6868 270)
			(unlocked yes)
			(layer "F.Fab")
			(hide yes)
			(effects
				(font
					(size 1.016 1.016)
					(thickness 0.1524)
				)
			)
		)
		(property "Device Type" "SC70-5H44"
			(at -2.3114 -10.414 270)
			(unlocked yes)
			(layer "F.Fab")
			(hide yes)
			(effects
				(font
					(size 1.016 1.016)
					(thickness 0.1524)
				)
			)
		)
		(duplicate_pad_numbers_are_jumpers no)
		(fp_line
			(start -1.27 1.7018)
			(end -1.27 -1.7018)
			(stroke
				(width 0.1524)
				(type default)
			)
			(layer "F.SilkS")
		)
		(fp_line
			(start 1.27 1.7018)
			(end -1.27 1.7018)
			(stroke
				(width 0.1524)
				(type default)
			)
			(layer "F.SilkS")
		)
		(fp_line
			(start -1.27 -1.7018)
			(end 1.27 -1.7018)
			(stroke
				(width 0.1524)
				(type default)
			)
			(layer "F.SilkS")
		)
		(fp_line
			(start 1.27 -1.7018)
			(end 1.27 1.7018)
			(stroke
				(width 0.1524)
				(type default)
			)
			(layer "F.SilkS")
		)
		(fp_line
			(start 0.6604 -1.8034)
			(end 1.3843 -1.8034)
			(stroke
				(width 0.3302)
				(type default)
			)
			(layer "F.SilkS")
		)
		(fp_line
			(start 1.3843 -1.8034)
			(end 1.3843 -1.1176)
			(stroke
				(width 0.3302)
				(type default)
			)
			(layer "F.SilkS")
		)
		(fp_rect
			(start -1.524 1.9558)
			(end 1.524 -1.9558)
			(stroke
				(width 0)
				(type default)
			)
			(fill no)
			(layer "F.CrtYd")
		)
		(fp_poly
			(pts
				(xy -1.524 -1.9558) (xy 1.524 -1.9558) (xy 1.524 1.9558) (xy -1.524 1.9558)
			)
			(stroke
				(width 0)
				(type default)
			)
			(fill no)
			(layer "F.Fab")
		)
		(pad "1" smd rect
			(at 0.65024 -0.8255 270)
			(size 0.4064 1.2192)
			(layers "F.Cu" "F.Mask" "F.Paste")
			(net "SAS_EXP_B_PWR4")
		)
		(pad "2" smd rect
			(at 0 -0.8255 270)
			(size 0.4064 1.2192)
			(layers "F.Cu" "F.Mask" "F.Paste")
			(net "SAS_EXP_A_PWR4")
		)
		(pad "3" smd rect
			(at -0.65024 -0.8255 270)
			(size 0.4064 1.2192)
			(layers "F.Cu" "F.Mask" "F.Paste")
			(net "GND")
		)
		(pad "4" smd rect
			(at -0.65024 0.8255 270)
			(size 0.4064 1.2192)
			(layers "F.Cu" "F.Mask" "F.Paste")
			(net "DRIVE_PWR4")
		)
		(pad "5" smd rect
			(at 0.65024 0.8255 270)
			(size 0.4064 1.2192)
			(layers "F.Cu" "F.Mask" "F.Paste")
			(net "P3V3")
		)
	)
	(footprint ""
		(layer "F.Cu")
		(at 229.615746 -27.1907 -90)
		(property "Reference" "PR15"
			(at 0 0 270)
			(layer "F.SilkS")
			(hide yes)
			(effects
				(font
					(size 1.27 1.27)
				)
			)
		)
		(property "Value" "0R2J-2-GP"
			(at 0.064008 -3.993896 270)
			(unlocked yes)
			(layer "F.Fab")
			(hide yes)
			(effects
				(font
					(size 1.016 1.016)
					(thickness 0.1524)
				)
			)
		)
		(property "Device Type" "R402H16"
			(at 0.064008 -5.517896 270)
			(unlocked yes)
			(layer "F.Fab")
			(hide yes)
			(effects
				(font
					(size 1.016 1.016)
					(thickness 0.1524)
				)
			)
		)
		(duplicate_pad_numbers_are_jumpers no)
		(fp_line
			(start -0.508 -0.9398)
			(end -0.508 0.9398)
			(stroke
				(width 0.1524)
				(type default)
			)
			(layer "F.SilkS")
		)
		(fp_line
			(start 0.508 -0.9398)
			(end -0.508 -0.9398)
			(stroke
				(width 0.1524)
				(type default)
			)
			(layer "F.SilkS")
		)
		(fp_rect
			(start -0.508 0.9398)
			(end 0.508 -0.9398)
			(stroke
				(width 0)
				(type default)
			)
			(fill no)
			(layer "F.CrtYd")
		)
		(fp_rect
			(start -0.508 0.9398)
			(end 0.508 -0.9398)
			(stroke
				(width 0)
				(type default)
			)
			(fill no)
			(layer "F.Fab")
		)
		(pad "1" smd custom
			(at 0 -0.4445 270)
			(size 0.1397 0.1397)
			(layers "F.Cu" "F.Mask" "F.Paste")
			(net "P5VA_ROVP")
			(options
				(clearance outline)
				(anchor circle)
			)
			(primitives
				(gr_poly
					(pts
						(arc
							(start -0.1778 -0.2794)
							(mid -0.249642 -0.249642)
							(end -0.2794 -0.1778)
						)
						(arc
							(start -0.2794 0.1778)
							(mid -0.249642 0.249642)
							(end -0.1778 0.2794)
						)
						(arc
							(start 0.1778 0.2794)
							(mid 0.249642 0.249642)
							(end 0.2794 0.1778)
						)
						(arc
							(start 0.2794 -0.1778)
							(mid 0.249642 -0.249642)
							(end 0.1778 -0.2794)
						)
					)
					(width 0)
					(fill yes)
				)
			)
		)
		(pad "2" smd custom
			(at 0 0.4445 270)
			(size 0.1397 0.1397)
			(layers "F.Cu" "F.Mask" "F.Paste")
			(net "P5VA_AGND")
			(options
				(clearance outline)
				(anchor circle)
			)
			(primitives
				(gr_poly
					(pts
						(arc
							(start -0.1778 -0.2794)
							(mid -0.249642 -0.249642)
							(end -0.2794 -0.1778)
						)
						(arc
							(start -0.2794 0.1778)
							(mid -0.249642 0.249642)
							(end -0.1778 0.2794)
						)
						(arc
							(start 0.1778 0.2794)
							(mid 0.249642 0.249642)
							(end 0.2794 0.1778)
						)
						(arc
							(start 0.2794 -0.1778)
							(mid 0.249642 -0.249642)
							(end 0.1778 -0.2794)
						)
					)
					(width 0)
					(fill yes)
				)
			)
		)
	)
	(footprint ""
		(layer "F.Cu")
		(at 55.371746 -389.1407 180)
		(property "Reference" "C205"
			(at 0 0 180)
			(layer "F.SilkS")
			(hide yes)
			(effects
				(font
					(size 1.27 1.27)
				)
			)
		)
		(property "Value" "SC1U16V3KX-5GP"
			(at 0 -2.8194 180)
			(unlocked yes)
			(layer "F.Fab")
			(hide yes)
			(effects
				(font
					(size 1.016 1.016)
					(thickness 0.1524)
				)
			)
		)
		(property "Device Type" "C603H36"
			(at 0 -4.3434 180)
			(unlocked yes)
			(layer "F.Fab")
			(hide yes)
			(effects
				(font
					(size 1.016 1.016)
					(thickness 0.1524)
				)
			)
		)
		(duplicate_pad_numbers_are_jumpers no)
		(fp_line
			(start 0.508 0)
			(end -0.508 0)
			(stroke
				(width 0.2032)
				(type default)
			)
			(layer "F.SilkS")
		)
		(fp_rect
			(start -0.5842 1.3335)
			(end 0.5842 -1.3335)
			(stroke
				(width 0)
				(type default)
			)
			(fill no)
			(layer "F.CrtYd")
		)
		(fp_rect
			(start -0.5842 1.3335)
			(end 0.5842 -1.3335)
			(stroke
				(width 0)
				(type default)
			)
			(fill no)
			(layer "F.Fab")
		)
		(pad "1" smd custom
			(at 0 -0.762 180)
			(size 0.2159 0.2159)
			(layers "F.Cu" "F.Mask" "F.Paste")
			(net "P5V_HDD6")
			(options
				(clearance outline)
				(anchor circle)
			)
			(primitives
				(gr_poly
					(pts
						(arc
							(start -0.3302 -0.4318)
							(mid -0.402042 -0.402042)
							(end -0.4318 -0.3302)
						)
						(arc
							(start -0.4318 0.3302)
							(mid -0.402042 0.402042)
							(end -0.3302 0.4318)
						)
						(arc
							(start 0.3302 0.4318)
							(mid 0.402042 0.402042)
							(end 0.4318 0.3302)
						)
						(arc
							(start 0.4318 -0.3302)
							(mid 0.402042 -0.402042)
							(end 0.3302 -0.4318)
						)
					)
					(width 0)
					(fill yes)
				)
			)
		)
		(pad "2" smd custom
			(at 0 0.762 180)
			(size 0.2159 0.2159)
			(layers "F.Cu" "F.Mask" "F.Paste")
			(net "GND")
			(options
				(clearance outline)
				(anchor circle)
			)
			(primitives
				(gr_poly
					(pts
						(arc
							(start -0.3302 -0.4318)
							(mid -0.402042 -0.402042)
							(end -0.4318 -0.3302)
						)
						(arc
							(start -0.4318 0.3302)
							(mid -0.402042 0.402042)
							(end -0.3302 0.4318)
						)
						(arc
							(start 0.3302 0.4318)
							(mid 0.402042 0.402042)
							(end 0.4318 0.3302)
						)
						(arc
							(start 0.4318 -0.3302)
							(mid 0.402042 -0.402042)
							(end 0.3302 -0.4318)
						)
					)
					(width 0)
					(fill yes)
				)
			)
		)
	)
	(footprint ""
		(layer "F.Cu")
		(at 245.9228 -421.767 -90)
		(property "Reference" "C355"
			(at 0 0 270)
			(layer "F.SilkS")
			(hide yes)
			(effects
				(font
					(size 1.27 1.27)
				)
			)
		)
		(property "Value" "SC220P50V3JN-GP"
			(at 0 -2.8194 270)
			(unlocked yes)
			(layer "F.Fab")
			(hide yes)
			(effects
				(font
					(size 1.016 1.016)
					(thickness 0.1524)
				)
			)
		)
		(property "Device Type" "C603H36"
			(at 0 -4.3434 270)
			(unlocked yes)
			(layer "F.Fab")
			(hide yes)
			(effects
				(font
					(size 1.016 1.016)
					(thickness 0.1524)
				)
			)
		)
		(duplicate_pad_numbers_are_jumpers no)
		(fp_line
			(start 0.508 0)
			(end -0.508 0)
			(stroke
				(width 0.2032)
				(type default)
			)
			(layer "F.SilkS")
		)
		(fp_rect
			(start -0.5842 1.3335)
			(end 0.5842 -1.3335)
			(stroke
				(width 0)
				(type default)
			)
			(fill no)
			(layer "F.CrtYd")
		)
		(fp_rect
			(start -0.5842 1.3335)
			(end 0.5842 -1.3335)
			(stroke
				(width 0)
				(type default)
			)
			(fill no)
			(layer "F.Fab")
		)
		(pad "1" smd custom
			(at 0 -0.762 270)
			(size 0.2159 0.2159)
			(layers "F.Cu" "F.Mask" "F.Paste")
			(net "I2C_C_SDA")
			(options
				(clearance outline)
				(anchor circle)
			)
			(primitives
				(gr_poly
					(pts
						(arc
							(start -0.3302 -0.4318)
							(mid -0.402042 -0.402042)
							(end -0.4318 -0.3302)
						)
						(arc
							(start -0.4318 0.3302)
							(mid -0.402042 0.402042)
							(end -0.3302 0.4318)
						)
						(arc
							(start 0.3302 0.4318)
							(mid 0.402042 0.402042)
							(end 0.4318 0.3302)
						)
						(arc
							(start 0.4318 -0.3302)
							(mid 0.402042 -0.402042)
							(end 0.3302 -0.4318)
						)
					)
					(width 0)
					(fill yes)
				)
			)
		)
		(pad "2" smd custom
			(at 0 0.762 270)
			(size 0.2159 0.2159)
			(layers "F.Cu" "F.Mask" "F.Paste")
			(net "GND")
			(options
				(clearance outline)
				(anchor circle)
			)
			(primitives
				(gr_poly
					(pts
						(arc
							(start -0.3302 -0.4318)
							(mid -0.402042 -0.402042)
							(end -0.4318 -0.3302)
						)
						(arc
							(start -0.4318 0.3302)
							(mid -0.402042 0.402042)
							(end -0.3302 0.4318)
						)
						(arc
							(start 0.3302 0.4318)
							(mid 0.402042 0.402042)
							(end 0.4318 0.3302)
						)
						(arc
							(start 0.4318 -0.3302)
							(mid 0.402042 -0.402042)
							(end 0.3302 -0.4318)
						)
					)
					(width 0)
					(fill yes)
				)
			)
		)
	)
	(footprint ""
		(layer "F.Cu")
		(at 229.488746 -33.0327 180)
		(property "Reference" "PR6"
			(at 0 0 180)
			(layer "F.SilkS")
			(hide yes)
			(effects
				(font
					(size 1.27 1.27)
				)
			)
		)
		(property "Value" "10R2F-L-GP"
			(at 0.064008 -3.993896 180)
			(unlocked yes)
			(layer "F.Fab")
			(hide yes)
			(effects
				(font
					(size 1.016 1.016)
					(thickness 0.1524)
				)
			)
		)
		(property "Device Type" "R402H14"
			(at 0.064008 -5.517896 180)
			(unlocked yes)
			(layer "F.Fab")
			(hide yes)
			(effects
				(font
					(size 1.016 1.016)
					(thickness 0.1524)
				)
			)
		)
		(duplicate_pad_numbers_are_jumpers no)
		(fp_line
			(start 0.508 -0.9398)
			(end -0.508 -0.9398)
			(stroke
				(width 0.1524)
				(type default)
			)
			(layer "F.SilkS")
		)
		(fp_line
			(start -0.508 -0.9398)
			(end -0.508 0.9398)
			(stroke
				(width 0.1524)
				(type default)
			)
			(layer "F.SilkS")
		)
		(fp_rect
			(start -0.508 0.9398)
			(end 0.508 -0.9398)
			(stroke
				(width 0)
				(type default)
			)
			(fill no)
			(layer "F.CrtYd")
		)
		(fp_rect
			(start -0.508 0.9398)
			(end 0.508 -0.9398)
			(stroke
				(width 0)
				(type default)
			)
			(fill no)
			(layer "F.Fab")
		)
		(pad "1" smd custom
			(at 0 -0.4445 180)
			(size 0.1397 0.1397)
			(layers "F.Cu" "F.Mask" "F.Paste")
			(net "P5VA")
			(options
				(clearance outline)
				(anchor circle)
			)
			(primitives
				(gr_poly
					(pts
						(arc
							(start -0.1778 -0.2794)
							(mid -0.249642 -0.249642)
							(end -0.2794 -0.1778)
						)
						(arc
							(start -0.2794 0.1778)
							(mid -0.249642 0.249642)
							(end -0.1778 0.2794)
						)
						(arc
							(start 0.1778 0.2794)
							(mid 0.249642 0.249642)
							(end 0.2794 0.1778)
						)
						(arc
							(start 0.2794 -0.1778)
							(mid 0.249642 -0.249642)
							(end 0.1778 -0.2794)
						)
					)
					(width 0)
					(fill yes)
				)
			)
		)
		(pad "2" smd custom
			(at 0 0.4445 180)
			(size 0.1397 0.1397)
			(layers "F.Cu" "F.Mask" "F.Paste")
			(net "P5VA_VFB_NET")
			(options
				(clearance outline)
				(anchor circle)
			)
			(primitives
				(gr_poly
					(pts
						(arc
							(start -0.1778 -0.2794)
							(mid -0.249642 -0.249642)
							(end -0.2794 -0.1778)
						)
						(arc
							(start -0.2794 0.1778)
							(mid -0.249642 0.249642)
							(end -0.1778 0.2794)
						)
						(arc
							(start 0.1778 0.2794)
							(mid 0.249642 0.249642)
							(end 0.2794 0.1778)
						)
						(arc
							(start 0.2794 -0.1778)
							(mid 0.249642 -0.249642)
							(end 0.1778 -0.2794)
						)
					)
					(width 0)
					(fill yes)
				)
			)
		)
	)
	(footprint ""
		(layer "F.Cu")
		(at 77.342746 -11.077702 90)
		(property "Reference" "R304"
			(at 0 0 90)
			(layer "F.SilkS")
			(hide yes)
			(effects
				(font
					(size 1.27 1.27)
				)
			)
		)
		(property "Value" "2R2010J-1-GP"
			(at 0.254 -8.0772 90)
			(unlocked yes)
			(layer "F.Fab")
			(hide yes)
			(effects
				(font
					(size 1.016 1.016)
					(thickness 0.1524)
				)
			)
		)
		(property "Device Type" "R2010H28"
			(at 0.254 -9.6774 90)
			(unlocked yes)
			(layer "F.Fab")
			(hide yes)
			(effects
				(font
					(size 1.016 1.016)
					(thickness 0.1524)
				)
			)
		)
		(duplicate_pad_numbers_are_jumpers no)
		(fp_line
			(start 1.651 -3.302)
			(end -1.651 -3.302)
			(stroke
				(width 0.1524)
				(type default)
			)
			(layer "F.SilkS")
		)
		(fp_line
			(start -1.651 -3.302)
			(end -1.651 3.302)
			(stroke
				(width 0.1524)
				(type default)
			)
			(layer "F.SilkS")
		)
		(fp_line
			(start 1.651 3.302)
			(end 1.651 -3.302)
			(stroke
				(width 0.1524)
				(type default)
			)
			(layer "F.SilkS")
		)
		(fp_line
			(start -1.651 3.302)
			(end 1.651 3.302)
			(stroke
				(width 0.1524)
				(type default)
			)
			(layer "F.SilkS")
		)
		(fp_rect
			(start -1.7272 -3.3782)
			(end 1.7272 3.3782)
			(stroke
				(width 0)
				(type default)
			)
			(fill no)
			(layer "F.CrtYd")
		)
		(fp_poly
			(pts
				(xy 1.7272 3.3782) (xy 1.7272 -3.3782) (xy -1.7272 -3.3782) (xy -1.7272 3.3782)
			)
			(stroke
				(width 0)
				(type default)
			)
			(fill no)
			(layer "F.Fab")
		)
		(pad "1" smd rect
			(at 0 -2.3495 90)
			(size 2.794 1.143)
			(layers "F.Cu" "F.Mask" "F.Paste")
			(net "12V_PRE_14")
		)
		(pad "2" smd rect
			(at 0 2.3495 90)
			(size 2.794 1.143)
			(layers "F.Cu" "F.Mask" "F.Paste")
			(net "P12V_HDD14")
		)
	)
	(footprint ""
		(layer "F.Cu")
		(at 77.978 -94.488)
		(property "Reference" "R572"
			(at 0 0 0)
			(layer "F.SilkS")
			(hide yes)
			(effects
				(font
					(size 1.27 1.27)
				)
			)
		)
		(property "Value" "300KR2F-GP"
			(at 0.064008 -3.993896 0)
			(unlocked yes)
			(layer "F.Fab")
			(hide yes)
			(effects
				(font
					(size 1.016 1.016)
					(thickness 0.1524)
				)
			)
		)
		(property "Device Type" "R402H16"
			(at 0.064008 -5.517896 0)
			(unlocked yes)
			(layer "F.Fab")
			(hide yes)
			(effects
				(font
					(size 1.016 1.016)
					(thickness 0.1524)
				)
			)
		)
		(duplicate_pad_numbers_are_jumpers no)
		(fp_line
			(start -0.508 -0.9398)
			(end -0.508 0.9398)
			(stroke
				(width 0.1524)
				(type default)
			)
			(layer "F.SilkS")
		)
		(fp_line
			(start 0.508 -0.9398)
			(end -0.508 -0.9398)
			(stroke
				(width 0.1524)
				(type default)
			)
			(layer "F.SilkS")
		)
		(fp_rect
			(start -0.508 0.9398)
			(end 0.508 -0.9398)
			(stroke
				(width 0)
				(type default)
			)
			(fill no)
			(layer "F.CrtYd")
		)
		(fp_rect
			(start -0.508 0.9398)
			(end 0.508 -0.9398)
			(stroke
				(width 0)
				(type default)
			)
			(fill no)
			(layer "F.Fab")
		)
		(pad "1" smd custom
			(at 0 -0.4445)
			(size 0.1397 0.1397)
			(layers "F.Cu" "F.Mask" "F.Paste")
			(net "SW_HDD9_N")
			(options
				(clearance outline)
				(anchor circle)
			)
			(primitives
				(gr_poly
					(pts
						(arc
							(start -0.1778 -0.2794)
							(mid -0.249642 -0.249642)
							(end -0.2794 -0.1778)
						)
						(arc
							(start -0.2794 0.1778)
							(mid -0.249642 0.249642)
							(end -0.1778 0.2794)
						)
						(arc
							(start 0.1778 0.2794)
							(mid 0.249642 0.249642)
							(end 0.2794 0.1778)
						)
						(arc
							(start 0.2794 -0.1778)
							(mid 0.249642 -0.249642)
							(end 0.1778 -0.2794)
						)
					)
					(width 0)
					(fill yes)
				)
			)
		)
		(pad "2" smd custom
			(at 0 0.4445)
			(size 0.1397 0.1397)
			(layers "F.Cu" "F.Mask" "F.Paste")
			(net "P12V")
			(options
				(clearance outline)
				(anchor circle)
			)
			(primitives
				(gr_poly
					(pts
						(arc
							(start -0.1778 -0.2794)
							(mid -0.249642 -0.249642)
							(end -0.2794 -0.1778)
						)
						(arc
							(start -0.2794 0.1778)
							(mid -0.249642 0.249642)
							(end -0.1778 0.2794)
						)
						(arc
							(start 0.1778 0.2794)
							(mid 0.249642 0.249642)
							(end 0.2794 0.1778)
						)
						(arc
							(start 0.2794 -0.1778)
							(mid 0.249642 -0.249642)
							(end 0.1778 -0.2794)
						)
					)
					(width 0)
					(fill yes)
				)
			)
		)
	)
	(footprint ""
		(layer "F.Cu")
		(at 203.245974 -390.878822 -90)
		(property "Reference" "R426"
			(at 0 0 270)
			(layer "F.SilkS")
			(hide yes)
			(effects
				(font
					(size 1.27 1.27)
				)
			)
		)
		(property "Value" "4K7R2J-2-GP"
			(at 0.064008 -3.993896 270)
			(unlocked yes)
			(layer "F.Fab")
			(hide yes)
			(effects
				(font
					(size 1.016 1.016)
					(thickness 0.1524)
				)
			)
		)
		(property "Device Type" "R402H16"
			(at 0.064008 -5.517896 270)
			(unlocked yes)
			(layer "F.Fab")
			(hide yes)
			(effects
				(font
					(size 1.016 1.016)
					(thickness 0.1524)
				)
			)
		)
		(duplicate_pad_numbers_are_jumpers no)
		(fp_line
			(start -0.508 -0.9398)
			(end -0.508 0.9398)
			(stroke
				(width 0.1524)
				(type default)
			)
			(layer "F.SilkS")
		)
		(fp_line
			(start 0.508 -0.9398)
			(end -0.508 -0.9398)
			(stroke
				(width 0.1524)
				(type default)
			)
			(layer "F.SilkS")
		)
		(fp_rect
			(start -0.508 0.9398)
			(end 0.508 -0.9398)
			(stroke
				(width 0)
				(type default)
			)
			(fill no)
			(layer "F.CrtYd")
		)
		(fp_rect
			(start -0.508 0.9398)
			(end 0.508 -0.9398)
			(stroke
				(width 0)
				(type default)
			)
			(fill no)
			(layer "F.Fab")
		)
		(pad "1" smd custom
			(at 0 -0.4445 270)
			(size 0.1397 0.1397)
			(layers "F.Cu" "F.Mask" "F.Paste")
			(net "P3V3")
			(options
				(clearance outline)
				(anchor circle)
			)
			(primitives
				(gr_poly
					(pts
						(arc
							(start -0.1778 -0.2794)
							(mid -0.249642 -0.249642)
							(end -0.2794 -0.1778)
						)
						(arc
							(start -0.2794 0.1778)
							(mid -0.249642 0.249642)
							(end -0.1778 0.2794)
						)
						(arc
							(start 0.1778 0.2794)
							(mid 0.249642 0.249642)
							(end 0.2794 0.1778)
						)
						(arc
							(start 0.2794 -0.1778)
							(mid 0.249642 -0.249642)
							(end 0.1778 -0.2794)
						)
					)
					(width 0)
					(fill yes)
				)
			)
		)
		(pad "2" smd custom
			(at 0 0.4445 270)
			(size 0.1397 0.1397)
			(layers "F.Cu" "F.Mask" "F.Paste")
			(net "SAS2X28_B_HDD1_FLT")
			(options
				(clearance outline)
				(anchor circle)
			)
			(primitives
				(gr_poly
					(pts
						(arc
							(start -0.1778 -0.2794)
							(mid -0.249642 -0.249642)
							(end -0.2794 -0.1778)
						)
						(arc
							(start -0.2794 0.1778)
							(mid -0.249642 0.249642)
							(end -0.1778 0.2794)
						)
						(arc
							(start 0.1778 0.2794)
							(mid 0.249642 0.249642)
							(end 0.2794 0.1778)
						)
						(arc
							(start 0.2794 -0.1778)
							(mid 0.249642 -0.249642)
							(end 0.1778 -0.2794)
						)
					)
					(width 0)
					(fill yes)
				)
			)
		)
	)
	(footprint ""
		(layer "F.Cu")
		(at 93.090746 -7.3787 90)
		(property "Reference" "U44"
			(at 0 0 90)
			(layer "F.SilkS")
			(hide yes)
			(effects
				(font
					(size 1.27 1.27)
				)
			)
		)
		(property "Value" "P2003EVG-GP"
			(at 0 -11.1252 90)
			(unlocked yes)
			(layer "F.Fab")
			(hide yes)
			(effects
				(font
					(size 1.016 1.016)
					(thickness 0.1524)
				)
			)
		)
		(property "Device Type" "SOIC8H79"
			(at 0 -12.6492 90)
			(unlocked yes)
			(layer "F.Fab")
			(hide yes)
			(effects
				(font
					(size 1.016 1.016)
					(thickness 0.1524)
				)
			)
		)
		(duplicate_pad_numbers_are_jumpers no)
		(fp_line
			(start 2.1336 -1.4224)
			(end -2.7432 -1.4224)
			(stroke
				(width 0.1524)
				(type default)
			)
			(layer "F.SilkS")
		)
		(fp_line
			(start -2.7432 -1.4224)
			(end -2.7432 1.4224)
			(stroke
				(width 0.1524)
				(type default)
			)
			(layer "F.SilkS")
		)
		(fp_line
			(start -2.7432 -0.508)
			(end -2.2352 0)
			(stroke
				(width 0.1524)
				(type default)
			)
			(layer "F.SilkS")
		)
		(fp_line
			(start -2.2352 0)
			(end -2.7432 0.508)
			(stroke
				(width 0.1524)
				(type default)
			)
			(layer "F.SilkS")
		)
		(fp_line
			(start 2.1336 1.4224)
			(end 2.1336 -1.4224)
			(stroke
				(width 0.1524)
				(type default)
			)
			(layer "F.SilkS")
		)
		(fp_line
			(start -2.7432 1.4224)
			(end 2.1336 1.4224)
			(stroke
				(width 0.1524)
				(type default)
			)
			(layer "F.SilkS")
		)
		(fp_line
			(start -2.6162 3.429)
			(end -2.6162 1.4732)
			(stroke
				(width 0.4064)
				(type default)
			)
			(layer "F.SilkS")
		)
		(fp_poly
			(pts
				(xy 2.2098 -1.4224) (xy 2.2098 1.4224) (xy -2.2225 1.4224) (xy -2.2225 -1.4224)
			)
			(stroke
				(width 0)
				(type default)
			)
			(fill yes)
			(layer "F.SilkS")
		)
		(fp_rect
			(start -2.4511 2.9972)
			(end 2.4511 -2.9972)
			(stroke
				(width 0)
				(type default)
			)
			(fill no)
			(layer "F.CrtYd")
		)
		(fp_poly
			(pts
				(xy -2.8194 3.6322) (xy -2.8194 -3.6322) (xy 2.8194 -3.6322) (xy 2.8194 -2.2987) (xy 2.4511 -2.2987)
				(xy 2.4511 -2.9972) (xy -2.4511 -2.9972) (xy -2.4511 2.9972) (xy 2.4511 2.9972) (xy 2.4511 -2.286)
				(xy 2.8194 -2.286) (xy 2.8194 3.6322)
			)
			(stroke
				(width 0)
				(type default)
			)
			(fill no)
			(layer "F.CrtYd")
		)
		(fp_rect
			(start -2.8194 3.6322)
			(end 2.8194 -3.6322)
			(stroke
				(width 0)
				(type default)
			)
			(fill no)
			(layer "F.Fab")
		)
		(pad "1" smd rect
			(at -1.905 2.54 90)
			(size 0.635 1.651)
			(layers "F.Cu" "F.Mask" "F.Paste")
			(net "P12V")
		)
		(pad "2" smd rect
			(at -0.635 2.54 90)
			(size 0.635 1.651)
			(layers "F.Cu" "F.Mask" "F.Paste")
			(net "P12V")
		)
		(pad "3" smd rect
			(at 0.635 2.54 90)
			(size 0.635 1.651)
			(layers "F.Cu" "F.Mask" "F.Paste")
			(net "P12V")
		)
		(pad "4" smd rect
			(at 1.905 2.54 90)
			(size 0.635 1.651)
			(layers "F.Cu" "F.Mask" "F.Paste")
			(net "SW_HDD14_N")
		)
		(pad "5" smd rect
			(at 1.905 -2.54 90)
			(size 0.635 1.651)
			(layers "F.Cu" "F.Mask" "F.Paste")
			(net "P12V_HDD14")
		)
		(pad "6" smd rect
			(at 0.635 -2.54 90)
			(size 0.635 1.651)
			(layers "F.Cu" "F.Mask" "F.Paste")
			(net "P12V_HDD14")
		)
		(pad "7" smd rect
			(at -0.635 -2.54 90)
			(size 0.635 1.651)
			(layers "F.Cu" "F.Mask" "F.Paste")
			(net "P12V_HDD14")
		)
		(pad "8" smd rect
			(at -1.905 -2.54 90)
			(size 0.635 1.651)
			(layers "F.Cu" "F.Mask" "F.Paste")
			(net "P12V_HDD14")
		)
	)
	(footprint ""
		(layer "F.Cu")
		(at 58.5216 -71.882 90)
		(property "Reference" "R394"
			(at 0 0 90)
			(layer "F.SilkS")
			(hide yes)
			(effects
				(font
					(size 1.27 1.27)
				)
			)
		)
		(property "Value" "0R2J-2-GP"
			(at 0.064008 -3.993896 90)
			(unlocked yes)
			(layer "F.Fab")
			(hide yes)
			(effects
				(font
					(size 1.016 1.016)
					(thickness 0.1524)
				)
			)
		)
		(property "Device Type" "R402H16"
			(at 0.064008 -5.517896 90)
			(unlocked yes)
			(layer "F.Fab")
			(hide yes)
			(effects
				(font
					(size 1.016 1.016)
					(thickness 0.1524)
				)
			)
		)
		(duplicate_pad_numbers_are_jumpers no)
		(fp_line
			(start 0.508 -0.9398)
			(end -0.508 -0.9398)
			(stroke
				(width 0.1524)
				(type default)
			)
			(layer "F.SilkS")
		)
		(fp_line
			(start -0.508 -0.9398)
			(end -0.508 0.9398)
			(stroke
				(width 0.1524)
				(type default)
			)
			(layer "F.SilkS")
		)
		(fp_rect
			(start -0.508 0.9398)
			(end 0.508 -0.9398)
			(stroke
				(width 0)
				(type default)
			)
			(fill no)
			(layer "F.CrtYd")
		)
		(fp_rect
			(start -0.508 0.9398)
			(end 0.508 -0.9398)
			(stroke
				(width 0)
				(type default)
			)
			(fill no)
			(layer "F.Fab")
		)
		(pad "1" smd custom
			(at 0 -0.4445 90)
			(size 0.1397 0.1397)
			(layers "F.Cu" "F.Mask" "F.Paste")
			(net "HDD_PRSNT_NET9")
			(options
				(clearance outline)
				(anchor circle)
			)
			(primitives
				(gr_poly
					(pts
						(arc
							(start -0.1778 -0.2794)
							(mid -0.249642 -0.249642)
							(end -0.2794 -0.1778)
						)
						(arc
							(start -0.2794 0.1778)
							(mid -0.249642 0.249642)
							(end -0.1778 0.2794)
						)
						(arc
							(start 0.1778 0.2794)
							(mid 0.249642 0.249642)
							(end 0.2794 0.1778)
						)
						(arc
							(start 0.2794 -0.1778)
							(mid 0.249642 -0.249642)
							(end 0.1778 -0.2794)
						)
					)
					(width 0)
					(fill yes)
				)
			)
		)
		(pad "2" smd custom
			(at 0 0.4445 90)
			(size 0.1397 0.1397)
			(layers "F.Cu" "F.Mask" "F.Paste")
			(net "HDD9_LED_B")
			(options
				(clearance outline)
				(anchor circle)
			)
			(primitives
				(gr_poly
					(pts
						(arc
							(start -0.1778 -0.2794)
							(mid -0.249642 -0.249642)
							(end -0.2794 -0.1778)
						)
						(arc
							(start -0.2794 0.1778)
							(mid -0.249642 0.249642)
							(end -0.1778 0.2794)
						)
						(arc
							(start 0.1778 0.2794)
							(mid 0.249642 0.249642)
							(end 0.2794 0.1778)
						)
						(arc
							(start 0.2794 -0.1778)
							(mid 0.249642 -0.249642)
							(end 0.1778 -0.2794)
						)
					)
					(width 0)
					(fill yes)
				)
			)
		)
	)
	(footprint ""
		(layer "F.Cu")
		(at 5.079746 -493.7887 90)
		(property "Reference" "PR41"
			(at 0 0 90)
			(layer "F.SilkS")
			(hide yes)
			(effects
				(font
					(size 1.27 1.27)
				)
			)
		)
		(property "Value" "10KR2F-2-GP"
			(at 0.064008 -3.993896 90)
			(unlocked yes)
			(layer "F.Fab")
			(hide yes)
			(effects
				(font
					(size 1.016 1.016)
					(thickness 0.1524)
				)
			)
		)
		(property "Device Type" "R402H16"
			(at 0.064008 -5.517896 90)
			(unlocked yes)
			(layer "F.Fab")
			(hide yes)
			(effects
				(font
					(size 1.016 1.016)
					(thickness 0.1524)
				)
			)
		)
		(duplicate_pad_numbers_are_jumpers no)
		(fp_line
			(start 0.508 -0.9398)
			(end -0.508 -0.9398)
			(stroke
				(width 0.1524)
				(type default)
			)
			(layer "F.SilkS")
		)
		(fp_line
			(start -0.508 -0.9398)
			(end -0.508 0.9398)
			(stroke
				(width 0.1524)
				(type default)
			)
			(layer "F.SilkS")
		)
		(fp_rect
			(start -0.508 0.9398)
			(end 0.508 -0.9398)
			(stroke
				(width 0)
				(type default)
			)
			(fill no)
			(layer "F.CrtYd")
		)
		(fp_rect
			(start -0.508 0.9398)
			(end 0.508 -0.9398)
			(stroke
				(width 0)
				(type default)
			)
			(fill no)
			(layer "F.Fab")
		)
		(pad "1" smd custom
			(at 0 -0.4445 90)
			(size 0.1397 0.1397)
			(layers "F.Cu" "F.Mask" "F.Paste")
			(net "P5VC_12VIN")
			(options
				(clearance outline)
				(anchor circle)
			)
			(primitives
				(gr_poly
					(pts
						(arc
							(start -0.1778 -0.2794)
							(mid -0.249642 -0.249642)
							(end -0.2794 -0.1778)
						)
						(arc
							(start -0.2794 0.1778)
							(mid -0.249642 0.249642)
							(end -0.1778 0.2794)
						)
						(arc
							(start 0.1778 0.2794)
							(mid 0.249642 0.249642)
							(end 0.2794 0.1778)
						)
						(arc
							(start 0.2794 -0.1778)
							(mid 0.249642 -0.249642)
							(end 0.1778 -0.2794)
						)
					)
					(width 0)
					(fill yes)
				)
			)
		)
		(pad "2" smd custom
			(at 0 0.4445 90)
			(size 0.1397 0.1397)
			(layers "F.Cu" "F.Mask" "F.Paste")
			(net "P5VC_EN")
			(options
				(clearance outline)
				(anchor circle)
			)
			(primitives
				(gr_poly
					(pts
						(arc
							(start -0.1778 -0.2794)
							(mid -0.249642 -0.249642)
							(end -0.2794 -0.1778)
						)
						(arc
							(start -0.2794 0.1778)
							(mid -0.249642 0.249642)
							(end -0.1778 0.2794)
						)
						(arc
							(start 0.1778 0.2794)
							(mid 0.249642 0.249642)
							(end 0.2794 0.1778)
						)
						(arc
							(start 0.2794 -0.1778)
							(mid 0.249642 -0.249642)
							(end 0.1778 -0.2794)
						)
					)
					(width 0)
					(fill yes)
				)
			)
		)
	)
	(footprint ""
		(layer "F.Cu")
		(at 7.499858 -261.499858)
		(property "Reference" "H7"
			(at 0 0 0)
			(layer "F.SilkS")
			(hide yes)
			(effects
				(font
					(size 1.27 1.27)
				)
			)
		)
		(property "Value" "HOLE315R140"
			(at 0 -7.5692 0)
			(unlocked yes)
			(layer "F.Fab")
			(hide yes)
			(effects
				(font
					(size 1.016 1.016)
					(thickness 0.1524)
				)
			)
		)
		(property "Device Type" "HOLE315R140"
			(at 0 -9.0932 0)
			(unlocked yes)
			(layer "F.Fab")
			(hide yes)
			(effects
				(font
					(size 1.016 1.016)
					(thickness 0.1524)
				)
			)
		)
		(duplicate_pad_numbers_are_jumpers no)
		(fp_poly
			(pts
				(arc
					(start 4.3053 0)
					(mid -4.3053 0)
					(end 4.3053 0)
				)
			)
			(stroke
				(width 0)
				(type default)
			)
			(fill no)
			(layer "F.CrtYd")
		)
		(fp_poly
			(pts
				(arc
					(start 4.3053 0)
					(mid -4.3053 0)
					(end 4.3053 0)
				)
			)
			(stroke
				(width 0)
				(type default)
			)
			(fill no)
			(layer "F.Fab")
		)
		(pad "1" thru_hole circle
			(at 0.00127 0.00127)
			(size 8.001 8.001)
			(drill 3.556)
			(layers "*.Cu" "*.Mask")
			(remove_unused_layers no)
			(net "GND")
			(clearance -1.7145)
			(thermal_gap 0.3048)
			(padstack
				(mode front_inner_back)
				(layer "Inner"
					(shape circle)
					(size 3.9624 3.9624)
					(clearance 0.3048)
				)
				(layer "B.Cu"
					(shape circle)
					(size 8.001 8.001)
					(clearance -1.7145)
				)
			)
		)
	)
	(footprint ""
		(layer "F.Cu")
		(at 217.762582 -264.005568 -90)
		(property "Reference" "C135"
			(at 0 0 270)
			(layer "F.SilkS")
			(hide yes)
			(effects
				(font
					(size 1.27 1.27)
				)
			)
		)
		(property "Value" "SCD01U50V2KX-1GP"
			(at 1.1811 -2.7051 270)
			(unlocked yes)
			(layer "F.Fab")
			(hide yes)
			(effects
				(font
					(size 1.016 1.016)
					(thickness 0.1524)
				)
			)
		)
		(property "Device Type" "C402H22"
			(at 1.1811 -4.2291 270)
			(unlocked yes)
			(layer "F.Fab")
			(hide yes)
			(effects
				(font
					(size 1.016 1.016)
					(thickness 0.1524)
				)
			)
		)
		(duplicate_pad_numbers_are_jumpers no)
		(fp_rect
			(start -0.4318 0.9525)
			(end 0.4318 -0.9525)
			(stroke
				(width 0)
				(type default)
			)
			(fill no)
			(layer "F.CrtYd")
		)
		(fp_rect
			(start -0.4318 0.9525)
			(end 0.4318 -0.9525)
			(stroke
				(width 0)
				(type default)
			)
			(fill no)
			(layer "F.Fab")
		)
		(pad "1" smd custom
			(at 0 -0.4445 270)
			(size 0.1524 0.1524)
			(layers "F.Cu" "F.Mask" "F.Paste")
			(net "SAS2X28_DRIVE_RX_P_A2")
			(options
				(clearance outline)
				(anchor circle)
			)
			(primitives
				(gr_poly
					(pts
						(arc
							(start 0.3048 -0.2032)
							(mid 0.275042 -0.275042)
							(end 0.2032 -0.3048)
						)
						(arc
							(start -0.2032 -0.3048)
							(mid -0.275042 -0.275042)
							(end -0.3048 -0.2032)
						)
						(arc
							(start -0.3048 0.2032)
							(mid -0.275042 0.275042)
							(end -0.2032 0.3048)
						)
						(arc
							(start 0.2032 0.3048)
							(mid 0.275042 0.275042)
							(end 0.3048 0.2032)
						)
					)
					(width 0)
					(fill yes)
				)
			)
		)
		(pad "2" smd custom
			(at 0 0.4445 270)
			(size 0.1524 0.1524)
			(layers "F.Cu" "F.Mask" "F.Paste")
			(net "SAS2X28_A_HDD2_RX_+")
			(options
				(clearance outline)
				(anchor circle)
			)
			(primitives
				(gr_poly
					(pts
						(arc
							(start 0.3048 -0.2032)
							(mid 0.275042 -0.275042)
							(end 0.2032 -0.3048)
						)
						(arc
							(start -0.2032 -0.3048)
							(mid -0.275042 -0.275042)
							(end -0.3048 -0.2032)
						)
						(arc
							(start -0.3048 0.2032)
							(mid -0.275042 0.275042)
							(end -0.2032 0.3048)
						)
						(arc
							(start 0.2032 0.3048)
							(mid 0.275042 0.275042)
							(end 0.3048 0.2032)
						)
					)
					(width 0)
					(fill yes)
				)
			)
		)
	)
	(footprint ""
		(layer "F.Cu")
		(at 216.492582 -275.435568)
		(property "Reference" "R139"
			(at 0 0 0)
			(layer "F.SilkS")
			(hide yes)
			(effects
				(font
					(size 1.27 1.27)
				)
			)
		)
		(property "Value" "220R3F-1-GP"
			(at -0.0254 -2.5146 0)
			(unlocked yes)
			(layer "F.Fab")
			(hide yes)
			(effects
				(font
					(size 1.016 1.016)
					(thickness 0.1524)
				)
			)
		)
		(property "Device Type" "R603H22"
			(at -0.0254 -4.0386 0)
			(unlocked yes)
			(layer "F.Fab")
			(hide yes)
			(effects
				(font
					(size 1.016 1.016)
					(thickness 0.1524)
				)
			)
		)
		(duplicate_pad_numbers_are_jumpers no)
		(fp_line
			(start -0.4826 0)
			(end -0.2032 0)
			(stroke
				(width 0.2032)
				(type default)
			)
			(layer "F.SilkS")
		)
		(fp_line
			(start 0.2032 0)
			(end 0.4826 0)
			(stroke
				(width 0.2032)
				(type default)
			)
			(layer "F.SilkS")
		)
		(fp_rect
			(start -0.5842 1.3335)
			(end 0.5842 -1.3335)
			(stroke
				(width 0)
				(type default)
			)
			(fill no)
			(layer "F.CrtYd")
		)
		(fp_rect
			(start -0.5842 1.3335)
			(end 0.5842 -1.3335)
			(stroke
				(width 0)
				(type default)
			)
			(fill no)
			(layer "F.Fab")
		)
		(pad "1" smd custom
			(at 0 -0.762)
			(size 0.2159 0.2159)
			(layers "F.Cu" "F.Mask" "F.Paste")
			(net "HDD_PRSNT_NET2")
			(options
				(clearance outline)
				(anchor circle)
			)
			(primitives
				(gr_poly
					(pts
						(arc
							(start -0.3302 -0.4318)
							(mid -0.402042 -0.402042)
							(end -0.4318 -0.3302)
						)
						(arc
							(start -0.4318 0.3302)
							(mid -0.402042 0.402042)
							(end -0.3302 0.4318)
						)
						(arc
							(start 0.3302 0.4318)
							(mid 0.402042 0.402042)
							(end 0.4318 0.3302)
						)
						(arc
							(start 0.4318 -0.3302)
							(mid 0.402042 -0.402042)
							(end 0.3302 -0.4318)
						)
					)
					(width 0)
					(fill yes)
				)
			)
		)
		(pad "2" smd custom
			(at 0 0.762)
			(size 0.2159 0.2159)
			(layers "F.Cu" "F.Mask" "F.Paste")
			(net "HDD_PRSNT2")
			(options
				(clearance outline)
				(anchor circle)
			)
			(primitives
				(gr_poly
					(pts
						(arc
							(start -0.3302 -0.4318)
							(mid -0.402042 -0.402042)
							(end -0.4318 -0.3302)
						)
						(arc
							(start -0.4318 0.3302)
							(mid -0.402042 0.402042)
							(end -0.3302 0.4318)
						)
						(arc
							(start 0.3302 0.4318)
							(mid 0.402042 0.402042)
							(end 0.4318 0.3302)
						)
						(arc
							(start 0.4318 -0.3302)
							(mid 0.402042 -0.402042)
							(end 0.3302 -0.4318)
						)
					)
					(width 0)
					(fill yes)
				)
			)
		)
	)
	(footprint ""
		(layer "F.Cu")
		(at 27.431746 -330.482702 180)
		(property "Reference" "R265"
			(at 0 0 180)
			(layer "F.SilkS")
			(hide yes)
			(effects
				(font
					(size 1.27 1.27)
				)
			)
		)
		(property "Value" "220R3F-1-GP"
			(at -0.0254 -2.5146 180)
			(unlocked yes)
			(layer "F.Fab")
			(hide yes)
			(effects
				(font
					(size 1.016 1.016)
					(thickness 0.1524)
				)
			)
		)
		(property "Device Type" "R603H22"
			(at -0.0254 -4.0386 180)
			(unlocked yes)
			(layer "F.Fab")
			(hide yes)
			(effects
				(font
					(size 1.016 1.016)
					(thickness 0.1524)
				)
			)
		)
		(duplicate_pad_numbers_are_jumpers no)
		(fp_line
			(start 0.2032 0)
			(end 0.4826 0)
			(stroke
				(width 0.2032)
				(type default)
			)
			(layer "F.SilkS")
		)
		(fp_line
			(start -0.4826 0)
			(end -0.2032 0)
			(stroke
				(width 0.2032)
				(type default)
			)
			(layer "F.SilkS")
		)
		(fp_rect
			(start -0.5842 1.3335)
			(end 0.5842 -1.3335)
			(stroke
				(width 0)
				(type default)
			)
			(fill no)
			(layer "F.CrtYd")
		)
		(fp_rect
			(start -0.5842 1.3335)
			(end 0.5842 -1.3335)
			(stroke
				(width 0)
				(type default)
			)
			(fill no)
			(layer "F.Fab")
		)
		(pad "1" smd custom
			(at 0 -0.762 180)
			(size 0.2159 0.2159)
			(layers "F.Cu" "F.Mask" "F.Paste")
			(net "HDD_PRSNT_NET11")
			(options
				(clearance outline)
				(anchor circle)
			)
			(primitives
				(gr_poly
					(pts
						(arc
							(start -0.3302 -0.4318)
							(mid -0.402042 -0.402042)
							(end -0.4318 -0.3302)
						)
						(arc
							(start -0.4318 0.3302)
							(mid -0.402042 0.402042)
							(end -0.3302 0.4318)
						)
						(arc
							(start 0.3302 0.4318)
							(mid 0.402042 0.402042)
							(end 0.4318 0.3302)
						)
						(arc
							(start 0.4318 -0.3302)
							(mid 0.402042 -0.402042)
							(end 0.3302 -0.4318)
						)
					)
					(width 0)
					(fill yes)
				)
			)
		)
		(pad "2" smd custom
			(at 0 0.762 180)
			(size 0.2159 0.2159)
			(layers "F.Cu" "F.Mask" "F.Paste")
			(net "HDD_PRSNT11")
			(options
				(clearance outline)
				(anchor circle)
			)
			(primitives
				(gr_poly
					(pts
						(arc
							(start -0.3302 -0.4318)
							(mid -0.402042 -0.402042)
							(end -0.4318 -0.3302)
						)
						(arc
							(start -0.4318 0.3302)
							(mid -0.402042 0.402042)
							(end -0.3302 0.4318)
						)
						(arc
							(start 0.3302 0.4318)
							(mid 0.402042 0.402042)
							(end 0.4318 0.3302)
						)
						(arc
							(start 0.4318 -0.3302)
							(mid 0.402042 -0.402042)
							(end 0.3302 -0.4318)
						)
					)
					(width 0)
					(fill yes)
				)
			)
		)
	)
	(footprint ""
		(layer "F.Cu")
		(at 29.590746 -430.050702 90)
		(property "Reference" "R245"
			(at 0 0 90)
			(layer "F.SilkS")
			(hide yes)
			(effects
				(font
					(size 1.27 1.27)
				)
			)
		)
		(property "Value" "2R2010J-1-GP"
			(at 0.254 -8.0772 90)
			(unlocked yes)
			(layer "F.Fab")
			(hide yes)
			(effects
				(font
					(size 1.016 1.016)
					(thickness 0.1524)
				)
			)
		)
		(property "Device Type" "R2010H28"
			(at 0.254 -9.6774 90)
			(unlocked yes)
			(layer "F.Fab")
			(hide yes)
			(effects
				(font
					(size 1.016 1.016)
					(thickness 0.1524)
				)
			)
		)
		(duplicate_pad_numbers_are_jumpers no)
		(fp_line
			(start 1.651 -3.302)
			(end -1.651 -3.302)
			(stroke
				(width 0.1524)
				(type default)
			)
			(layer "F.SilkS")
		)
		(fp_line
			(start -1.651 -3.302)
			(end -1.651 3.302)
			(stroke
				(width 0.1524)
				(type default)
			)
			(layer "F.SilkS")
		)
		(fp_line
			(start 1.651 3.302)
			(end 1.651 -3.302)
			(stroke
				(width 0.1524)
				(type default)
			)
			(layer "F.SilkS")
		)
		(fp_line
			(start -1.651 3.302)
			(end 1.651 3.302)
			(stroke
				(width 0.1524)
				(type default)
			)
			(layer "F.SilkS")
		)
		(fp_rect
			(start -1.7272 -3.3782)
			(end 1.7272 3.3782)
			(stroke
				(width 0)
				(type default)
			)
			(fill no)
			(layer "F.CrtYd")
		)
		(fp_poly
			(pts
				(xy 1.7272 3.3782) (xy 1.7272 -3.3782) (xy -1.7272 -3.3782) (xy -1.7272 3.3782)
			)
			(stroke
				(width 0)
				(type default)
			)
			(fill no)
			(layer "F.Fab")
		)
		(pad "1" smd rect
			(at 0 -2.3495 90)
			(size 2.794 1.143)
			(layers "F.Cu" "F.Mask" "F.Paste")
			(net "5V_PRE_10")
		)
		(pad "2" smd rect
			(at 0 2.3495 90)
			(size 2.794 1.143)
			(layers "F.Cu" "F.Mask" "F.Paste")
			(net "P5V_HDD10")
		)
	)
	(footprint ""
		(layer "F.Cu")
		(at 60.3758 -396.9004 180)
		(property "Reference" "C208"
			(at 0 0 180)
			(layer "F.SilkS")
			(hide yes)
			(effects
				(font
					(size 1.27 1.27)
				)
			)
		)
		(property "Value" "SC10U25V6KX-1GP"
			(at -0.0762 -5.1308 180)
			(unlocked yes)
			(layer "F.Fab")
			(hide yes)
			(effects
				(font
					(size 1.016 1.016)
					(thickness 0.1524)
				)
			)
		)
		(property "Device Type" "C1206H71"
			(at -0.127 -6.6548 180)
			(unlocked yes)
			(layer "F.Fab")
			(hide yes)
			(effects
				(font
					(size 1.016 1.016)
					(thickness 0.1524)
				)
			)
		)
		(duplicate_pad_numbers_are_jumpers no)
		(fp_line
			(start 1.016 2.2352)
			(end -1.016 2.2352)
			(stroke
				(width 0.1524)
				(type default)
			)
			(layer "F.SilkS")
		)
		(fp_line
			(start 1.016 0.8382)
			(end 1.016 2.2352)
			(stroke
				(width 0.1524)
				(type default)
			)
			(layer "F.SilkS")
		)
		(fp_line
			(start 1.016 -2.2352)
			(end 1.016 -0.8382)
			(stroke
				(width 0.1524)
				(type default)
			)
			(layer "F.SilkS")
		)
		(fp_line
			(start -1.016 2.2352)
			(end -1.016 0.8382)
			(stroke
				(width 0.1524)
				(type default)
			)
			(layer "F.SilkS")
		)
		(fp_line
			(start -1.016 -0.8382)
			(end -1.016 -2.2352)
			(stroke
				(width 0.1524)
				(type default)
			)
			(layer "F.SilkS")
		)
		(fp_line
			(start -1.016 -2.2352)
			(end 1.016 -2.2352)
			(stroke
				(width 0.1524)
				(type default)
			)
			(layer "F.SilkS")
		)
		(fp_rect
			(start -1.0922 2.3114)
			(end 1.0922 -2.3114)
			(stroke
				(width 0)
				(type default)
			)
			(fill no)
			(layer "F.CrtYd")
		)
		(fp_poly
			(pts
				(xy 1.0922 -2.3114) (xy 1.0922 2.3114) (xy -1.0922 2.3114) (xy -1.0922 -2.3114)
			)
			(stroke
				(width 0)
				(type default)
			)
			(fill no)
			(layer "F.Fab")
		)
		(pad "1" smd rect
			(at 0 -1.397 180)
			(size 1.651 1.27)
			(layers "F.Cu" "F.Mask" "F.Paste")
			(net "P12V_HDD6")
		)
		(pad "2" smd rect
			(at 0 1.397 180)
			(size 1.651 1.27)
			(layers "F.Cu" "F.Mask" "F.Paste")
			(net "GND")
		)
	)
	(footprint ""
		(layer "F.Cu")
		(at 79.628746 -490.2327)
		(property "Reference" "C181"
			(at 0 0 0)
			(layer "F.SilkS")
			(hide yes)
			(effects
				(font
					(size 1.27 1.27)
				)
			)
		)
		(property "Value" "SCD1U10V2KX-5GP"
			(at 1.1811 -2.7051 0)
			(unlocked yes)
			(layer "F.Fab")
			(hide yes)
			(effects
				(font
					(size 1.016 1.016)
					(thickness 0.1524)
				)
			)
		)
		(property "Device Type" "C402H22"
			(at 1.1811 -4.2291 0)
			(unlocked yes)
			(layer "F.Fab")
			(hide yes)
			(effects
				(font
					(size 1.016 1.016)
					(thickness 0.1524)
				)
			)
		)
		(duplicate_pad_numbers_are_jumpers no)
		(fp_rect
			(start -0.4318 0.9525)
			(end 0.4318 -0.9525)
			(stroke
				(width 0)
				(type default)
			)
			(fill no)
			(layer "F.CrtYd")
		)
		(fp_rect
			(start -0.4318 0.9525)
			(end 0.4318 -0.9525)
			(stroke
				(width 0)
				(type default)
			)
			(fill no)
			(layer "F.Fab")
		)
		(pad "1" smd custom
			(at 0 -0.4445)
			(size 0.1524 0.1524)
			(layers "F.Cu" "F.Mask" "F.Paste")
			(net "P3V3")
			(options
				(clearance outline)
				(anchor circle)
			)
			(primitives
				(gr_poly
					(pts
						(arc
							(start 0.3048 -0.2032)
							(mid 0.275042 -0.275042)
							(end 0.2032 -0.3048)
						)
						(arc
							(start -0.2032 -0.3048)
							(mid -0.275042 -0.275042)
							(end -0.3048 -0.2032)
						)
						(arc
							(start -0.3048 0.2032)
							(mid -0.275042 0.275042)
							(end -0.2032 0.3048)
						)
						(arc
							(start 0.2032 0.3048)
							(mid 0.275042 0.275042)
							(end 0.3048 0.2032)
						)
					)
					(width 0)
					(fill yes)
				)
			)
		)
		(pad "2" smd custom
			(at 0 0.4445)
			(size 0.1524 0.1524)
			(layers "F.Cu" "F.Mask" "F.Paste")
			(net "GND")
			(options
				(clearance outline)
				(anchor circle)
			)
			(primitives
				(gr_poly
					(pts
						(arc
							(start 0.3048 -0.2032)
							(mid 0.275042 -0.275042)
							(end 0.2032 -0.3048)
						)
						(arc
							(start -0.2032 -0.3048)
							(mid -0.275042 -0.275042)
							(end -0.3048 -0.2032)
						)
						(arc
							(start -0.3048 0.2032)
							(mid -0.275042 0.275042)
							(end -0.2032 0.3048)
						)
						(arc
							(start 0.2032 0.3048)
							(mid 0.275042 0.275042)
							(end 0.3048 0.2032)
						)
					)
					(width 0)
					(fill yes)
				)
			)
		)
	)
	(footprint ""
		(layer "F.Cu")
		(at 75.209146 -7.013702)
		(property "Reference" "C336"
			(at 0 0 0)
			(layer "F.SilkS")
			(hide yes)
			(effects
				(font
					(size 1.27 1.27)
				)
			)
		)
		(property "Value" "SC10U25V6KX-1GP"
			(at -0.0762 -5.1308 0)
			(unlocked yes)
			(layer "F.Fab")
			(hide yes)
			(effects
				(font
					(size 1.016 1.016)
					(thickness 0.1524)
				)
			)
		)
		(property "Device Type" "C1206H71"
			(at -0.127 -6.6548 0)
			(unlocked yes)
			(layer "F.Fab")
			(hide yes)
			(effects
				(font
					(size 1.016 1.016)
					(thickness 0.1524)
				)
			)
		)
		(duplicate_pad_numbers_are_jumpers no)
		(fp_line
			(start -1.016 -2.2352)
			(end 1.016 -2.2352)
			(stroke
				(width 0.1524)
				(type default)
			)
			(layer "F.SilkS")
		)
		(fp_line
			(start -1.016 -0.8382)
			(end -1.016 -2.2352)
			(stroke
				(width 0.1524)
				(type default)
			)
			(layer "F.SilkS")
		)
		(fp_line
			(start -1.016 2.2352)
			(end -1.016 0.8382)
			(stroke
				(width 0.1524)
				(type default)
			)
			(layer "F.SilkS")
		)
		(fp_line
			(start 1.016 -2.2352)
			(end 1.016 -0.8382)
			(stroke
				(width 0.1524)
				(type default)
			)
			(layer "F.SilkS")
		)
		(fp_line
			(start 1.016 0.8382)
			(end 1.016 2.2352)
			(stroke
				(width 0.1524)
				(type default)
			)
			(layer "F.SilkS")
		)
		(fp_line
			(start 1.016 2.2352)
			(end -1.016 2.2352)
			(stroke
				(width 0.1524)
				(type default)
			)
			(layer "F.SilkS")
		)
		(fp_rect
			(start -1.0922 2.3114)
			(end 1.0922 -2.3114)
			(stroke
				(width 0)
				(type default)
			)
			(fill no)
			(layer "F.CrtYd")
		)
		(fp_poly
			(pts
				(xy 1.0922 -2.3114) (xy 1.0922 2.3114) (xy -1.0922 2.3114) (xy -1.0922 -2.3114)
			)
			(stroke
				(width 0)
				(type default)
			)
			(fill no)
			(layer "F.Fab")
		)
		(pad "1" smd rect
			(at 0 -1.397)
			(size 1.651 1.27)
			(layers "F.Cu" "F.Mask" "F.Paste")
			(net "P12V_HDD14")
		)
		(pad "2" smd rect
			(at 0 1.397)
			(size 1.651 1.27)
			(layers "F.Cu" "F.Mask" "F.Paste")
			(net "GND")
		)
	)
	(footprint ""
		(layer "F.Cu")
		(at 218.947746 -32.2707 180)
		(property "Reference" "PTC2"
			(at 0 0 180)
			(layer "F.SilkS")
			(hide yes)
			(effects
				(font
					(size 1.27 1.27)
				)
			)
		)
		(property "Value" "ST330U10VDM-2GP"
			(at 0 -9.6012 180)
			(unlocked yes)
			(layer "F.Fab")
			(hide yes)
			(effects
				(font
					(size 1.016 1.016)
					(thickness 0.1524)
				)
			)
		)
		(property "Device Type" "CT7343H150"
			(at 0 -11.1252 180)
			(unlocked yes)
			(layer "F.Fab")
			(hide yes)
			(effects
				(font
					(size 1.016 1.016)
					(thickness 0.1524)
				)
			)
		)
		(duplicate_pad_numbers_are_jumpers no)
		(fp_line
			(start 2.286 4.8768)
			(end -2.286 4.8768)
			(stroke
				(width 0.1524)
				(type default)
			)
			(layer "F.SilkS")
		)
		(fp_line
			(start 2.286 2.032)
			(end 2.286 4.8768)
			(stroke
				(width 0.1524)
				(type default)
			)
			(layer "F.SilkS")
		)
		(fp_line
			(start 2.286 -2.032)
			(end 2.286 -4.8768)
			(stroke
				(width 0.1524)
				(type default)
			)
			(layer "F.SilkS")
		)
		(fp_line
			(start 2.286 -4.8768)
			(end -2.286 -4.8768)
			(stroke
				(width 0.1524)
				(type default)
			)
			(layer "F.SilkS")
		)
		(fp_line
			(start 2.1082 -4.699)
			(end -2.1082 -4.699)
			(stroke
				(width 0.508)
				(type default)
			)
			(layer "F.SilkS")
		)
		(fp_line
			(start -2.286 4.8768)
			(end -2.286 2.032)
			(stroke
				(width 0.1524)
				(type default)
			)
			(layer "F.SilkS")
		)
		(fp_line
			(start -2.286 -4.8768)
			(end -2.286 -2.032)
			(stroke
				(width 0.1524)
				(type default)
			)
			(layer "F.SilkS")
		)
		(fp_rect
			(start -2.1463 3.6449)
			(end 2.1463 -3.6449)
			(stroke
				(width 0)
				(type default)
			)
			(fill no)
			(layer "F.CrtYd")
		)
		(fp_poly
			(pts
				(xy -2.54 4.953) (xy -2.54 4.2926) (xy -3.81 4.2926) (xy -3.81 -4.2926) (xy -2.54 -4.2926) (xy -2.54 -4.953)
				(xy 2.54 -4.953) (xy 2.54 -4.2926) (xy 3.81 -4.2926) (xy 3.81 -1.6256) (xy 2.1463 -1.6256) (xy 2.1463 -3.6449)
				(xy -2.1463 -3.6449) (xy -2.1463 3.6449) (xy 2.1463 3.6449) (xy 2.1463 -1.6129) (xy 3.81 -1.6129)
				(xy 3.81 4.2926) (xy 2.54 4.2926) (xy 2.54 4.953)
			)
			(stroke
				(width 0)
				(type default)
			)
			(fill no)
			(layer "F.CrtYd")
		)
		(fp_rect
			(start 2.54 4.2926)
			(end 3.81 -4.2926)
			(stroke
				(width 0)
				(type default)
			)
			(fill no)
			(layer "F.Fab")
		)
		(fp_rect
			(start -2.54 4.953)
			(end 2.54 -4.953)
			(stroke
				(width 0)
				(type default)
			)
			(fill no)
			(layer "F.Fab")
		)
		(fp_rect
			(start -3.81 4.2926)
			(end -2.54 -4.2926)
			(stroke
				(width 0)
				(type default)
			)
			(fill no)
			(layer "F.Fab")
		)
		(pad "1" smd rect
			(at 0 -3.1496 180)
			(size 2.413 2.286)
			(layers "F.Cu" "F.Mask" "F.Paste")
			(net "P5VA")
		)
		(pad "2" smd rect
			(at 0 3.1496 180)
			(size 2.413 2.286)
			(layers "F.Cu" "F.Mask" "F.Paste")
			(net "GND")
		)
		(zone
			(layer "F.Cu")
			(hatch none 0.5)
			(connect_pads
				(clearance 0)
			)
			(min_thickness 0.25)
			(keepout
				(tracks allowed)
				(vias not_allowed)
				(pads allowed)
				(copperpour not_allowed)
				(footprints allowed)
			)
			(placement
				(enabled no)
				(sheetname "")
			)
			(fill
				(thermal_gap 0.5)
				(thermal_bridge_width 0.5)
				(island_removal_mode 0)
			)
			(polygon
				(pts
					(xy 217.436446 -30.5816) (xy 217.436446 -27.6733) (xy 220.459046 -27.6733) (xy 220.459046 -30.5689)
					(xy 220.459046 -30.8991) (xy 217.436446 -30.8991)
				)
			)
		)
		(zone
			(layer "F.Cu")
			(hatch none 0.5)
			(connect_pads
				(clearance 0)
			)
			(min_thickness 0.25)
			(keepout
				(tracks allowed)
				(vias not_allowed)
				(pads allowed)
				(copperpour not_allowed)
				(footprints allowed)
			)
			(placement
				(enabled no)
				(sheetname "")
			)
			(fill
				(thermal_gap 0.5)
				(thermal_bridge_width 0.5)
				(island_removal_mode 0)
			)
			(polygon
				(pts
					(xy 220.459046 -36.8681) (xy 217.436446 -36.8681) (xy 217.436446 -33.9725) (xy 217.436446 -33.6423)
					(xy 220.459046 -33.6423) (xy 220.459046 -33.9725)
				)
			)
		)
	)
	(footprint ""
		(layer "F.Cu")
		(at 48.640746 -223.167702 180)
		(property "Reference" "C302"
			(at 0 0 180)
			(layer "F.SilkS")
			(hide yes)
			(effects
				(font
					(size 1.27 1.27)
				)
			)
		)
		(property "Value" "SC10U25V6KX-1GP"
			(at -0.0762 -5.1308 180)
			(unlocked yes)
			(layer "F.Fab")
			(hide yes)
			(effects
				(font
					(size 1.016 1.016)
					(thickness 0.1524)
				)
			)
		)
		(property "Device Type" "C1206H71"
			(at -0.127 -6.6548 180)
			(unlocked yes)
			(layer "F.Fab")
			(hide yes)
			(effects
				(font
					(size 1.016 1.016)
					(thickness 0.1524)
				)
			)
		)
		(duplicate_pad_numbers_are_jumpers no)
		(fp_line
			(start 1.016 2.2352)
			(end -1.016 2.2352)
			(stroke
				(width 0.1524)
				(type default)
			)
			(layer "F.SilkS")
		)
		(fp_line
			(start 1.016 0.8382)
			(end 1.016 2.2352)
			(stroke
				(width 0.1524)
				(type default)
			)
			(layer "F.SilkS")
		)
		(fp_line
			(start 1.016 -2.2352)
			(end 1.016 -0.8382)
			(stroke
				(width 0.1524)
				(type default)
			)
			(layer "F.SilkS")
		)
		(fp_line
			(start -1.016 2.2352)
			(end -1.016 0.8382)
			(stroke
				(width 0.1524)
				(type default)
			)
			(layer "F.SilkS")
		)
		(fp_line
			(start -1.016 -0.8382)
			(end -1.016 -2.2352)
			(stroke
				(width 0.1524)
				(type default)
			)
			(layer "F.SilkS")
		)
		(fp_line
			(start -1.016 -2.2352)
			(end 1.016 -2.2352)
			(stroke
				(width 0.1524)
				(type default)
			)
			(layer "F.SilkS")
		)
		(fp_rect
			(start -1.0922 2.3114)
			(end 1.0922 -2.3114)
			(stroke
				(width 0)
				(type default)
			)
			(fill no)
			(layer "F.CrtYd")
		)
		(fp_poly
			(pts
				(xy 1.0922 -2.3114) (xy 1.0922 2.3114) (xy -1.0922 2.3114) (xy -1.0922 -2.3114)
			)
			(stroke
				(width 0)
				(type default)
			)
			(fill no)
			(layer "F.Fab")
		)
		(pad "1" smd rect
			(at 0 -1.397 180)
			(size 1.651 1.27)
			(layers "F.Cu" "F.Mask" "F.Paste")
			(net "P12V_HDD12")
		)
		(pad "2" smd rect
			(at 0 1.397 180)
			(size 1.651 1.27)
			(layers "F.Cu" "F.Mask" "F.Paste")
			(net "GND")
		)
	)
	(footprint ""
		(layer "F.Cu")
		(at 61.3918 -171.9834 -90)
		(property "Reference" "R385"
			(at 0 0 270)
			(layer "F.SilkS")
			(hide yes)
			(effects
				(font
					(size 1.27 1.27)
				)
			)
		)
		(property "Value" "10KR2F-2-GP"
			(at 0.064008 -3.993896 270)
			(unlocked yes)
			(layer "F.Fab")
			(hide yes)
			(effects
				(font
					(size 1.016 1.016)
					(thickness 0.1524)
				)
			)
		)
		(property "Device Type" "R402H16"
			(at 0.064008 -5.517896 270)
			(unlocked yes)
			(layer "F.Fab")
			(hide yes)
			(effects
				(font
					(size 1.016 1.016)
					(thickness 0.1524)
				)
			)
		)
		(duplicate_pad_numbers_are_jumpers no)
		(fp_line
			(start -0.508 -0.9398)
			(end -0.508 0.9398)
			(stroke
				(width 0.1524)
				(type default)
			)
			(layer "F.SilkS")
		)
		(fp_line
			(start 0.508 -0.9398)
			(end -0.508 -0.9398)
			(stroke
				(width 0.1524)
				(type default)
			)
			(layer "F.SilkS")
		)
		(fp_rect
			(start -0.508 0.9398)
			(end 0.508 -0.9398)
			(stroke
				(width 0)
				(type default)
			)
			(fill no)
			(layer "F.CrtYd")
		)
		(fp_rect
			(start -0.508 0.9398)
			(end 0.508 -0.9398)
			(stroke
				(width 0)
				(type default)
			)
			(fill no)
			(layer "F.Fab")
		)
		(pad "1" smd custom
			(at 0 -0.4445 270)
			(size 0.1397 0.1397)
			(layers "F.Cu" "F.Mask" "F.Paste")
			(net "P12V")
			(options
				(clearance outline)
				(anchor circle)
			)
			(primitives
				(gr_poly
					(pts
						(arc
							(start -0.1778 -0.2794)
							(mid -0.249642 -0.249642)
							(end -0.2794 -0.1778)
						)
						(arc
							(start -0.2794 0.1778)
							(mid -0.249642 0.249642)
							(end -0.1778 0.2794)
						)
						(arc
							(start 0.1778 0.2794)
							(mid 0.249642 0.249642)
							(end 0.2794 0.1778)
						)
						(arc
							(start 0.2794 -0.1778)
							(mid 0.249642 -0.249642)
							(end 0.1778 -0.2794)
						)
					)
					(width 0)
					(fill yes)
				)
			)
		)
		(pad "2" smd custom
			(at 0 0.4445 270)
			(size 0.1397 0.1397)
			(layers "F.Cu" "F.Mask" "F.Paste")
			(net "HDD8_LED_G")
			(options
				(clearance outline)
				(anchor circle)
			)
			(primitives
				(gr_poly
					(pts
						(arc
							(start -0.1778 -0.2794)
							(mid -0.249642 -0.249642)
							(end -0.2794 -0.1778)
						)
						(arc
							(start -0.2794 0.1778)
							(mid -0.249642 0.249642)
							(end -0.1778 0.2794)
						)
						(arc
							(start 0.1778 0.2794)
							(mid 0.249642 0.249642)
							(end 0.2794 0.1778)
						)
						(arc
							(start 0.2794 -0.1778)
							(mid 0.249642 -0.249642)
							(end 0.1778 -0.2794)
						)
					)
					(width 0)
					(fill yes)
				)
			)
		)
	)
	(footprint ""
		(layer "F.Cu")
		(at 57.149746 -388.6327 180)
		(property "Reference" "C206"
			(at 0 0 180)
			(layer "F.SilkS")
			(hide yes)
			(effects
				(font
					(size 1.27 1.27)
				)
			)
		)
		(property "Value" "SC10U16V6KX-2GP"
			(at -0.0762 -5.1308 180)
			(unlocked yes)
			(layer "F.Fab")
			(hide yes)
			(effects
				(font
					(size 1.016 1.016)
					(thickness 0.1524)
				)
			)
		)
		(property "Device Type" "C1206H71"
			(at -0.127 -6.6548 180)
			(unlocked yes)
			(layer "F.Fab")
			(hide yes)
			(effects
				(font
					(size 1.016 1.016)
					(thickness 0.1524)
				)
			)
		)
		(duplicate_pad_numbers_are_jumpers no)
		(fp_line
			(start 1.016 2.2352)
			(end -1.016 2.2352)
			(stroke
				(width 0.1524)
				(type default)
			)
			(layer "F.SilkS")
		)
		(fp_line
			(start 1.016 0.8382)
			(end 1.016 2.2352)
			(stroke
				(width 0.1524)
				(type default)
			)
			(layer "F.SilkS")
		)
		(fp_line
			(start 1.016 -2.2352)
			(end 1.016 -0.8382)
			(stroke
				(width 0.1524)
				(type default)
			)
			(layer "F.SilkS")
		)
		(fp_line
			(start -1.016 2.2352)
			(end -1.016 0.8382)
			(stroke
				(width 0.1524)
				(type default)
			)
			(layer "F.SilkS")
		)
		(fp_line
			(start -1.016 -0.8382)
			(end -1.016 -2.2352)
			(stroke
				(width 0.1524)
				(type default)
			)
			(layer "F.SilkS")
		)
		(fp_line
			(start -1.016 -2.2352)
			(end 1.016 -2.2352)
			(stroke
				(width 0.1524)
				(type default)
			)
			(layer "F.SilkS")
		)
		(fp_rect
			(start -1.0922 2.3114)
			(end 1.0922 -2.3114)
			(stroke
				(width 0)
				(type default)
			)
			(fill no)
			(layer "F.CrtYd")
		)
		(fp_poly
			(pts
				(xy 1.0922 -2.3114) (xy 1.0922 2.3114) (xy -1.0922 2.3114) (xy -1.0922 -2.3114)
			)
			(stroke
				(width 0)
				(type default)
			)
			(fill no)
			(layer "F.Fab")
		)
		(pad "1" smd rect
			(at 0 -1.397 180)
			(size 1.651 1.27)
			(layers "F.Cu" "F.Mask" "F.Paste")
			(net "P5V_HDD6")
		)
		(pad "2" smd rect
			(at 0 1.397 180)
			(size 1.651 1.27)
			(layers "F.Cu" "F.Mask" "F.Paste")
			(net "GND")
		)
	)
	(footprint ""
		(layer "F.Cu")
		(at 71.500746 -83.9597)
		(property "Reference" "U28"
			(at 0 0 0)
			(layer "F.SilkS")
			(hide yes)
			(effects
				(font
					(size 1.27 1.27)
				)
			)
		)
		(property "Value" "74LVC1G08GW-1-GP"
			(at -2.3368 -8.6868 0)
			(unlocked yes)
			(layer "F.Fab")
			(hide yes)
			(effects
				(font
					(size 1.016 1.016)
					(thickness 0.1524)
				)
			)
		)
		(property "Device Type" "SC70-5H44"
			(at -2.3114 -10.414 0)
			(unlocked yes)
			(layer "F.Fab")
			(hide yes)
			(effects
				(font
					(size 1.016 1.016)
					(thickness 0.1524)
				)
			)
		)
		(duplicate_pad_numbers_are_jumpers no)
		(fp_line
			(start -1.27 -1.7018)
			(end 1.27 -1.7018)
			(stroke
				(width 0.1524)
				(type default)
			)
			(layer "F.SilkS")
		)
		(fp_line
			(start -1.27 1.7018)
			(end -1.27 -1.7018)
			(stroke
				(width 0.1524)
				(type default)
			)
			(layer "F.SilkS")
		)
		(fp_line
			(start 0.6604 -1.8034)
			(end 1.3843 -1.8034)
			(stroke
				(width 0.3302)
				(type default)
			)
			(layer "F.SilkS")
		)
		(fp_line
			(start 1.27 -1.7018)
			(end 1.27 1.7018)
			(stroke
				(width 0.1524)
				(type default)
			)
			(layer "F.SilkS")
		)
		(fp_line
			(start 1.27 1.7018)
			(end -1.27 1.7018)
			(stroke
				(width 0.1524)
				(type default)
			)
			(layer "F.SilkS")
		)
		(fp_line
			(start 1.3843 -1.8034)
			(end 1.3843 -1.1176)
			(stroke
				(width 0.3302)
				(type default)
			)
			(layer "F.SilkS")
		)
		(fp_rect
			(start -1.524 1.9558)
			(end 1.524 -1.9558)
			(stroke
				(width 0)
				(type default)
			)
			(fill no)
			(layer "F.CrtYd")
		)
		(fp_poly
			(pts
				(xy -1.524 -1.9558) (xy 1.524 -1.9558) (xy 1.524 1.9558) (xy -1.524 1.9558)
			)
			(stroke
				(width 0)
				(type default)
			)
			(fill no)
			(layer "F.Fab")
		)
		(pad "1" smd rect
			(at 0.65024 -0.8255)
			(size 0.4064 1.2192)
			(layers "F.Cu" "F.Mask" "F.Paste")
			(net "SAS2X28_B_HDD9_FLT")
		)
		(pad "2" smd rect
			(at 0 -0.8255)
			(size 0.4064 1.2192)
			(layers "F.Cu" "F.Mask" "F.Paste")
			(net "SAS2X28_A_HDD9_FLT")
		)
		(pad "3" smd rect
			(at -0.65024 -0.8255)
			(size 0.4064 1.2192)
			(layers "F.Cu" "F.Mask" "F.Paste")
			(net "GND")
		)
		(pad "4" smd rect
			(at -0.65024 0.8255)
			(size 0.4064 1.2192)
			(layers "F.Cu" "F.Mask" "F.Paste")
			(net "FLT_HDD9_DRIVE")
		)
		(pad "5" smd rect
			(at 0.65024 0.8255)
			(size 0.4064 1.2192)
			(layers "F.Cu" "F.Mask" "F.Paste")
			(net "P3V3")
		)
	)
	(footprint ""
		(layer "F.Cu")
		(at 58.801 -69.3674 180)
		(property "Reference" "Q65"
			(at 0 0 180)
			(layer "F.SilkS")
			(hide yes)
			(effects
				(font
					(size 1.27 1.27)
				)
			)
		)
		(property "Value" "2N7002-11-GP"
			(at 0.127 -8.9662 180)
			(unlocked yes)
			(layer "F.Fab")
			(hide yes)
			(effects
				(font
					(size 1.016 1.016)
					(thickness 0.1524)
				)
			)
		)
		(property "Device Type" "SOT23DGS2D4H44"
			(at 0.127 -10.4902 180)
			(unlocked yes)
			(layer "F.Fab")
			(hide yes)
			(effects
				(font
					(size 1.016 1.016)
					(thickness 0.1524)
				)
			)
		)
		(duplicate_pad_numbers_are_jumpers no)
		(fp_line
			(start 1.651 1.778)
			(end 1.651 -1.778)
			(stroke
				(width 0.1524)
				(type default)
			)
			(layer "F.SilkS")
		)
		(fp_line
			(start 1.651 -1.778)
			(end -1.651 -1.778)
			(stroke
				(width 0.1524)
				(type default)
			)
			(layer "F.SilkS")
		)
		(fp_line
			(start -1.651 1.778)
			(end 1.651 1.778)
			(stroke
				(width 0.1524)
				(type default)
			)
			(layer "F.SilkS")
		)
		(fp_line
			(start -1.651 -1.778)
			(end -1.651 1.778)
			(stroke
				(width 0.1524)
				(type default)
			)
			(layer "F.SilkS")
		)
		(fp_poly
			(pts
				(xy -1.778 1.8796) (xy -1.778 -1.8796) (xy 1.778 -1.8796) (xy 1.778 1.8796)
			)
			(stroke
				(width 0)
				(type default)
			)
			(fill no)
			(layer "F.CrtYd")
		)
		(fp_poly
			(pts
				(xy -1.778 1.8796) (xy -1.778 -1.8796) (xy 1.778 -1.8796) (xy 1.778 1.8796)
			)
			(stroke
				(width 0)
				(type default)
			)
			(fill no)
			(layer "F.Fab")
		)
		(pad "D" smd custom
			(at 0 -0.9525 180)
			(size 0.1905 0.1905)
			(layers "F.Cu" "F.Mask" "F.Paste")
			(net "HDD9_LED_G")
			(options
				(clearance outline)
				(anchor circle)
			)
			(primitives
				(gr_poly
					(pts
						(arc
							(start -0.1778 0.5715)
							(mid -0.321484 0.511984)
							(end -0.381 0.3683)
						)
						(arc
							(start -0.381 -0.3683)
							(mid -0.321484 -0.511984)
							(end -0.1778 -0.5715)
						)
						(arc
							(start 0.1778 -0.5715)
							(mid 0.321484 -0.511984)
							(end 0.381 -0.3683)
						)
						(arc
							(start 0.381 0.3683)
							(mid 0.321484 0.511984)
							(end 0.1778 0.5715)
						)
					)
					(width 0)
					(fill yes)
				)
			)
		)
		(pad "G" smd custom
			(at -0.98425 0.9525 180)
			(size 0.1905 0.1905)
			(layers "F.Cu" "F.Mask" "F.Paste")
			(net "HDD9_LED_B")
			(options
				(clearance outline)
				(anchor circle)
			)
			(primitives
				(gr_poly
					(pts
						(arc
							(start -0.1778 0.5715)
							(mid -0.321484 0.511984)
							(end -0.381 0.3683)
						)
						(arc
							(start -0.381 -0.3683)
							(mid -0.321484 -0.511984)
							(end -0.1778 -0.5715)
						)
						(arc
							(start 0.1778 -0.5715)
							(mid 0.321484 -0.511984)
							(end 0.381 -0.3683)
						)
						(arc
							(start 0.381 0.3683)
							(mid 0.321484 0.511984)
							(end 0.1778 0.5715)
						)
					)
					(width 0)
					(fill yes)
				)
			)
		)
		(pad "S" smd custom
			(at 0.98425 0.9525 180)
			(size 0.1905 0.1905)
			(layers "F.Cu" "F.Mask" "F.Paste")
			(net "GND")
			(options
				(clearance outline)
				(anchor circle)
			)
			(primitives
				(gr_poly
					(pts
						(arc
							(start -0.1778 0.5715)
							(mid -0.321484 0.511984)
							(end -0.381 0.3683)
						)
						(arc
							(start -0.381 -0.3683)
							(mid -0.321484 -0.511984)
							(end -0.1778 -0.5715)
						)
						(arc
							(start 0.1778 -0.5715)
							(mid 0.321484 -0.511984)
							(end 0.381 -0.3683)
						)
						(arc
							(start 0.381 0.3683)
							(mid 0.321484 0.511984)
							(end 0.1778 0.5715)
						)
					)
					(width 0)
					(fill yes)
				)
			)
		)
	)
	(footprint ""
		(layer "F.Cu")
		(at 77.215746 -21.999702 -90)
		(property "Reference" "R301"
			(at 0 0 270)
			(layer "F.SilkS")
			(hide yes)
			(effects
				(font
					(size 1.27 1.27)
				)
			)
		)
		(property "Value" "4K7R2J-2-GP"
			(at 0.064008 -3.993896 270)
			(unlocked yes)
			(layer "F.Fab")
			(hide yes)
			(effects
				(font
					(size 1.016 1.016)
					(thickness 0.1524)
				)
			)
		)
		(property "Device Type" "R402H16"
			(at 0.064008 -5.517896 270)
			(unlocked yes)
			(layer "F.Fab")
			(hide yes)
			(effects
				(font
					(size 1.016 1.016)
					(thickness 0.1524)
				)
			)
		)
		(duplicate_pad_numbers_are_jumpers no)
		(fp_line
			(start -0.508 -0.9398)
			(end -0.508 0.9398)
			(stroke
				(width 0.1524)
				(type default)
			)
			(layer "F.SilkS")
		)
		(fp_line
			(start 0.508 -0.9398)
			(end -0.508 -0.9398)
			(stroke
				(width 0.1524)
				(type default)
			)
			(layer "F.SilkS")
		)
		(fp_rect
			(start -0.508 0.9398)
			(end 0.508 -0.9398)
			(stroke
				(width 0)
				(type default)
			)
			(fill no)
			(layer "F.CrtYd")
		)
		(fp_rect
			(start -0.508 0.9398)
			(end 0.508 -0.9398)
			(stroke
				(width 0)
				(type default)
			)
			(fill no)
			(layer "F.Fab")
		)
		(pad "1" smd custom
			(at 0 -0.4445 270)
			(size 0.1397 0.1397)
			(layers "F.Cu" "F.Mask" "F.Paste")
			(net "P3V3")
			(options
				(clearance outline)
				(anchor circle)
			)
			(primitives
				(gr_poly
					(pts
						(arc
							(start -0.1778 -0.2794)
							(mid -0.249642 -0.249642)
							(end -0.2794 -0.1778)
						)
						(arc
							(start -0.2794 0.1778)
							(mid -0.249642 0.249642)
							(end -0.1778 0.2794)
						)
						(arc
							(start 0.1778 0.2794)
							(mid 0.249642 0.249642)
							(end 0.2794 0.1778)
						)
						(arc
							(start 0.2794 -0.1778)
							(mid 0.249642 -0.249642)
							(end 0.1778 -0.2794)
						)
					)
					(width 0)
					(fill yes)
				)
			)
		)
		(pad "2" smd custom
			(at 0 0.4445 270)
			(size 0.1397 0.1397)
			(layers "F.Cu" "F.Mask" "F.Paste")
			(net "HDD_PRSNT_NET14")
			(options
				(clearance outline)
				(anchor circle)
			)
			(primitives
				(gr_poly
					(pts
						(arc
							(start -0.1778 -0.2794)
							(mid -0.249642 -0.249642)
							(end -0.2794 -0.1778)
						)
						(arc
							(start -0.2794 0.1778)
							(mid -0.249642 0.249642)
							(end -0.1778 0.2794)
						)
						(arc
							(start 0.1778 0.2794)
							(mid 0.249642 0.249642)
							(end 0.2794 0.1778)
						)
						(arc
							(start 0.2794 -0.1778)
							(mid 0.249642 -0.249642)
							(end 0.1778 -0.2794)
						)
					)
					(width 0)
					(fill yes)
				)
			)
		)
	)
	(footprint ""
		(layer "F.Cu")
		(at 28.447746 -298.9707 180)
		(property "Reference" "C225"
			(at 0 0 180)
			(layer "F.SilkS")
			(hide yes)
			(effects
				(font
					(size 1.27 1.27)
				)
			)
		)
		(property "Value" "SC10U25V6KX-1GP"
			(at -0.0762 -5.1308 180)
			(unlocked yes)
			(layer "F.Fab")
			(hide yes)
			(effects
				(font
					(size 1.016 1.016)
					(thickness 0.1524)
				)
			)
		)
		(property "Device Type" "C1206H71"
			(at -0.127 -6.6548 180)
			(unlocked yes)
			(layer "F.Fab")
			(hide yes)
			(effects
				(font
					(size 1.016 1.016)
					(thickness 0.1524)
				)
			)
		)
		(duplicate_pad_numbers_are_jumpers no)
		(fp_line
			(start 1.016 2.2352)
			(end -1.016 2.2352)
			(stroke
				(width 0.1524)
				(type default)
			)
			(layer "F.SilkS")
		)
		(fp_line
			(start 1.016 0.8382)
			(end 1.016 2.2352)
			(stroke
				(width 0.1524)
				(type default)
			)
			(layer "F.SilkS")
		)
		(fp_line
			(start 1.016 -2.2352)
			(end 1.016 -0.8382)
			(stroke
				(width 0.1524)
				(type default)
			)
			(layer "F.SilkS")
		)
		(fp_line
			(start -1.016 2.2352)
			(end -1.016 0.8382)
			(stroke
				(width 0.1524)
				(type default)
			)
			(layer "F.SilkS")
		)
		(fp_line
			(start -1.016 -0.8382)
			(end -1.016 -2.2352)
			(stroke
				(width 0.1524)
				(type default)
			)
			(layer "F.SilkS")
		)
		(fp_line
			(start -1.016 -2.2352)
			(end 1.016 -2.2352)
			(stroke
				(width 0.1524)
				(type default)
			)
			(layer "F.SilkS")
		)
		(fp_rect
			(start -1.0922 2.3114)
			(end 1.0922 -2.3114)
			(stroke
				(width 0)
				(type default)
			)
			(fill no)
			(layer "F.CrtYd")
		)
		(fp_poly
			(pts
				(xy 1.0922 -2.3114) (xy 1.0922 2.3114) (xy -1.0922 2.3114) (xy -1.0922 -2.3114)
			)
			(stroke
				(width 0)
				(type default)
			)
			(fill no)
			(layer "F.Fab")
		)
		(pad "1" smd rect
			(at 0 -1.397 180)
			(size 1.651 1.27)
			(layers "F.Cu" "F.Mask" "F.Paste")
			(net "P12V_HDD7")
		)
		(pad "2" smd rect
			(at 0 1.397 180)
			(size 1.651 1.27)
			(layers "F.Cu" "F.Mask" "F.Paste")
			(net "GND")
		)
	)
	(footprint ""
		(layer "F.Cu")
		(at 33.782 -306.324 90)
		(property "Reference" "R419"
			(at 0 0 90)
			(layer "F.SilkS")
			(hide yes)
			(effects
				(font
					(size 1.27 1.27)
				)
			)
		)
		(property "Value" "0R2J-2-GP"
			(at 0.064008 -3.993896 90)
			(unlocked yes)
			(layer "F.Fab")
			(hide yes)
			(effects
				(font
					(size 1.016 1.016)
					(thickness 0.1524)
				)
			)
		)
		(property "Device Type" "R402H16"
			(at 0.064008 -5.517896 90)
			(unlocked yes)
			(layer "F.Fab")
			(hide yes)
			(effects
				(font
					(size 1.016 1.016)
					(thickness 0.1524)
				)
			)
		)
		(duplicate_pad_numbers_are_jumpers no)
		(fp_line
			(start 0.508 -0.9398)
			(end -0.508 -0.9398)
			(stroke
				(width 0.1524)
				(type default)
			)
			(layer "F.SilkS")
		)
		(fp_line
			(start -0.508 -0.9398)
			(end -0.508 0.9398)
			(stroke
				(width 0.1524)
				(type default)
			)
			(layer "F.SilkS")
		)
		(fp_rect
			(start -0.508 0.9398)
			(end 0.508 -0.9398)
			(stroke
				(width 0)
				(type default)
			)
			(fill no)
			(layer "F.CrtYd")
		)
		(fp_rect
			(start -0.508 0.9398)
			(end 0.508 -0.9398)
			(stroke
				(width 0)
				(type default)
			)
			(fill no)
			(layer "F.Fab")
		)
		(pad "1" smd custom
			(at 0 -0.4445 90)
			(size 0.1397 0.1397)
			(layers "F.Cu" "F.Mask" "F.Paste")
			(net "SW_HDD11_G")
			(options
				(clearance outline)
				(anchor circle)
			)
			(primitives
				(gr_poly
					(pts
						(arc
							(start -0.1778 -0.2794)
							(mid -0.249642 -0.249642)
							(end -0.2794 -0.1778)
						)
						(arc
							(start -0.2794 0.1778)
							(mid -0.249642 0.249642)
							(end -0.1778 0.2794)
						)
						(arc
							(start 0.1778 0.2794)
							(mid 0.249642 0.249642)
							(end 0.2794 0.1778)
						)
						(arc
							(start 0.2794 -0.1778)
							(mid 0.249642 -0.249642)
							(end 0.1778 -0.2794)
						)
					)
					(width 0)
					(fill yes)
				)
			)
		)
		(pad "2" smd custom
			(at 0 0.4445 90)
			(size 0.1397 0.1397)
			(layers "F.Cu" "F.Mask" "F.Paste")
			(net "SW_HDD11_R")
			(options
				(clearance outline)
				(anchor circle)
			)
			(primitives
				(gr_poly
					(pts
						(arc
							(start -0.1778 -0.2794)
							(mid -0.249642 -0.249642)
							(end -0.2794 -0.1778)
						)
						(arc
							(start -0.2794 0.1778)
							(mid -0.249642 0.249642)
							(end -0.1778 0.2794)
						)
						(arc
							(start 0.1778 0.2794)
							(mid 0.249642 0.249642)
							(end 0.2794 0.1778)
						)
						(arc
							(start 0.2794 -0.1778)
							(mid 0.249642 -0.249642)
							(end 0.1778 -0.2794)
						)
					)
					(width 0)
					(fill yes)
				)
			)
		)
	)
	(footprint ""
		(layer "F.Cu")
		(at 234.822746 -27.9527 180)
		(property "Reference" "PR14"
			(at 0 0 180)
			(layer "F.SilkS")
			(hide yes)
			(effects
				(font
					(size 1.27 1.27)
				)
			)
		)
		(property "Value" "10KR2D-GP"
			(at 0.064008 -3.993896 180)
			(unlocked yes)
			(layer "F.Fab")
			(hide yes)
			(effects
				(font
					(size 1.016 1.016)
					(thickness 0.1524)
				)
			)
		)
		(property "Device Type" "R402H16"
			(at 0.064008 -5.517896 180)
			(unlocked yes)
			(layer "F.Fab")
			(hide yes)
			(effects
				(font
					(size 1.016 1.016)
					(thickness 0.1524)
				)
			)
		)
		(duplicate_pad_numbers_are_jumpers no)
		(fp_line
			(start 0.508 -0.9398)
			(end -0.508 -0.9398)
			(stroke
				(width 0.1524)
				(type default)
			)
			(layer "F.SilkS")
		)
		(fp_line
			(start -0.508 -0.9398)
			(end -0.508 0.9398)
			(stroke
				(width 0.1524)
				(type default)
			)
			(layer "F.SilkS")
		)
		(fp_rect
			(start -0.508 0.9398)
			(end 0.508 -0.9398)
			(stroke
				(width 0)
				(type default)
			)
			(fill no)
			(layer "F.CrtYd")
		)
		(fp_rect
			(start -0.508 0.9398)
			(end 0.508 -0.9398)
			(stroke
				(width 0)
				(type default)
			)
			(fill no)
			(layer "F.Fab")
		)
		(pad "1" smd custom
			(at 0 -0.4445 180)
			(size 0.1397 0.1397)
			(layers "F.Cu" "F.Mask" "F.Paste")
			(net "P5VA_VFB")
			(options
				(clearance outline)
				(anchor circle)
			)
			(primitives
				(gr_poly
					(pts
						(arc
							(start -0.1778 -0.2794)
							(mid -0.249642 -0.249642)
							(end -0.2794 -0.1778)
						)
						(arc
							(start -0.2794 0.1778)
							(mid -0.249642 0.249642)
							(end -0.1778 0.2794)
						)
						(arc
							(start 0.1778 0.2794)
							(mid 0.249642 0.249642)
							(end 0.2794 0.1778)
						)
						(arc
							(start 0.2794 -0.1778)
							(mid 0.249642 -0.249642)
							(end 0.1778 -0.2794)
						)
					)
					(width 0)
					(fill yes)
				)
			)
		)
		(pad "2" smd custom
			(at 0 0.4445 180)
			(size 0.1397 0.1397)
			(layers "F.Cu" "F.Mask" "F.Paste")
			(net "P5VA_AGND")
			(options
				(clearance outline)
				(anchor circle)
			)
			(primitives
				(gr_poly
					(pts
						(arc
							(start -0.1778 -0.2794)
							(mid -0.249642 -0.249642)
							(end -0.2794 -0.1778)
						)
						(arc
							(start -0.2794 0.1778)
							(mid -0.249642 0.249642)
							(end -0.1778 0.2794)
						)
						(arc
							(start 0.1778 0.2794)
							(mid 0.249642 0.249642)
							(end 0.2794 0.1778)
						)
						(arc
							(start 0.2794 -0.1778)
							(mid 0.249642 -0.249642)
							(end 0.1778 -0.2794)
						)
					)
					(width 0)
					(fill yes)
				)
			)
		)
	)
	(footprint ""
		(layer "F.Cu")
		(at 227.499926 -376.670062 90)
		(property "Reference" "SKT2"
			(at 0 0 90)
			(layer "F.SilkS")
			(hide yes)
			(effects
				(font
					(size 1.27 1.27)
				)
			)
		)
		(property "Value" "SKT-SATA14P-15P-12-GP"
			(at -22.6187 8.1788 90)
			(unlocked yes)
			(layer "F.Fab")
			(hide yes)
			(effects
				(font
					(size 1.016 1.016)
					(thickness 0.1524)
				)
			)
		)
		(property "Device Type" "87945-1001"
			(at -22.6187 6.6548 90)
			(unlocked yes)
			(layer "F.Fab")
			(hide yes)
			(effects
				(font
					(size 1.016 1.016)
					(thickness 0.1524)
				)
			)
		)
		(duplicate_pad_numbers_are_jumpers no)
		(fp_line
			(start -15.3924 -5.8547)
			(end -16.3576 -5.8547)
			(stroke
				(width 0.3302)
				(type default)
			)
			(layer "F.SilkS")
		)
		(fp_line
			(start 20.4724 -5.7658)
			(end 20.4724 -2.3114)
			(stroke
				(width 0.1524)
				(type default)
			)
			(layer "F.SilkS")
		)
		(fp_line
			(start -20.4724 -5.7658)
			(end 20.4724 -5.7658)
			(stroke
				(width 0.1524)
				(type default)
			)
			(layer "F.SilkS")
		)
		(fp_line
			(start 23.7617 -2.3114)
			(end 23.7617 2.3114)
			(stroke
				(width 0.1524)
				(type default)
			)
			(layer "F.SilkS")
		)
		(fp_line
			(start 20.4724 -2.3114)
			(end 23.7617 -2.3114)
			(stroke
				(width 0.1524)
				(type default)
			)
			(layer "F.SilkS")
		)
		(fp_line
			(start -20.4724 -2.3114)
			(end -20.4724 -5.7658)
			(stroke
				(width 0.1524)
				(type default)
			)
			(layer "F.SilkS")
		)
		(fp_line
			(start -23.7617 -2.3114)
			(end -20.4724 -2.3114)
			(stroke
				(width 0.1524)
				(type default)
			)
			(layer "F.SilkS")
		)
		(fp_line
			(start 23.117556 -0.5461)
			(end 23.117556 0.5461)
			(stroke
				(width 0.3048)
				(type default)
			)
			(layer "F.SilkS")
		)
		(fp_line
			(start -20.882356 -0.5461)
			(end -20.882356 0.5461)
			(stroke
				(width 0.3048)
				(type default)
			)
			(layer "F.SilkS")
		)
		(fp_line
			(start 20.882356 0.5461)
			(end 20.882356 -0.5461)
			(stroke
				(width 0.3048)
				(type default)
			)
			(layer "F.SilkS")
		)
		(fp_line
			(start -23.117556 0.5461)
			(end -23.117556 -0.5461)
			(stroke
				(width 0.3048)
				(type default)
			)
			(layer "F.SilkS")
		)
		(fp_line
			(start 23.7617 2.3114)
			(end 20.4724 2.3114)
			(stroke
				(width 0.1524)
				(type default)
			)
			(layer "F.SilkS")
		)
		(fp_line
			(start 20.4724 2.3114)
			(end 20.4724 9.652)
			(stroke
				(width 0.1524)
				(type default)
			)
			(layer "F.SilkS")
		)
		(fp_line
			(start -20.4724 2.3114)
			(end -23.7617 2.3114)
			(stroke
				(width 0.1524)
				(type default)
			)
			(layer "F.SilkS")
		)
		(fp_line
			(start -23.7617 2.3114)
			(end -23.7617 -2.3114)
			(stroke
				(width 0.1524)
				(type default)
			)
			(layer "F.SilkS")
		)
		(fp_line
			(start 17.8435 7.9502)
			(end -17.8435 7.9502)
			(stroke
				(width 0.1524)
				(type default)
			)
			(layer "F.SilkS")
		)
		(fp_line
			(start -17.8435 7.9502)
			(end -17.8435 9.652)
			(stroke
				(width 0.1524)
				(type default)
			)
			(layer "F.SilkS")
		)
		(fp_line
			(start 20.4724 9.652)
			(end 17.8435 9.652)
			(stroke
				(width 0.1524)
				(type default)
			)
			(layer "F.SilkS")
		)
		(fp_line
			(start 17.8435 9.652)
			(end 17.8435 7.9502)
			(stroke
				(width 0.1524)
				(type default)
			)
			(layer "F.SilkS")
		)
		(fp_line
			(start -17.8435 9.652)
			(end -20.4724 9.652)
			(stroke
				(width 0.1524)
				(type default)
			)
			(layer "F.SilkS")
		)
		(fp_line
			(start -20.4724 9.652)
			(end -20.4724 2.3114)
			(stroke
				(width 0.1524)
				(type default)
			)
			(layer "F.SilkS")
		)
		(fp_arc
			(start 20.882356 -0.5461)
			(mid 21.999956 -1.6637)
			(end 23.117556 -0.5461)
			(stroke
				(width 0.3048)
				(type default)
			)
			(layer "F.SilkS")
		)
		(fp_arc
			(start -23.117556 -0.5461)
			(mid -21.999956 -1.6637)
			(end -20.882356 -0.5461)
			(stroke
				(width 0.3048)
				(type default)
			)
			(layer "F.SilkS")
		)
		(fp_arc
			(start 23.117556 0.5461)
			(mid 21.999956 1.6637)
			(end 20.882356 0.5461)
			(stroke
				(width 0.3048)
				(type default)
			)
			(layer "F.SilkS")
		)
		(fp_arc
			(start -20.882356 0.5461)
			(mid -21.999956 1.6637)
			(end -23.117556 0.5461)
			(stroke
				(width 0.3048)
				(type default)
			)
			(layer "F.SilkS")
		)
		(fp_poly
			(pts
				(xy -15.87119 -5.838698) (xy -15.23619 -6.473698) (xy -16.50619 -6.473698)
			)
			(stroke
				(width 0)
				(type default)
			)
			(fill yes)
			(layer "F.SilkS")
		)
		(fp_poly
			(pts
				(xy -20.2184 -5.5118) (xy 20.2184 -5.5118) (xy 20.2184 -2.0574) (xy 23.5077 -2.0574) (xy 23.5077 2.0574)
				(xy 20.2184 2.0574) (xy 20.2184 9.398) (xy 18.0975 9.398) (xy 18.0975 7.6962) (xy -18.0975 7.6962)
				(xy -18.0975 9.398) (xy -20.2184 9.398) (xy -20.2184 2.0574) (xy -23.5077 2.0574) (xy -23.5077 -2.0574)
				(xy -20.2184 -2.0574)
			)
			(stroke
				(width 0)
				(type default)
			)
			(fill no)
			(layer "F.CrtYd")
		)
		(fp_poly
			(pts
				(xy -20.2184 -5.5118) (xy -20.2184 -6.0198) (xy -20.7264 -6.0198) (xy -20.7264 -2.5654) (xy -24.0157 -2.5654)
				(xy -24.0157 2.5654) (xy -20.7264 2.5654) (xy -20.7264 9.906) (xy -17.5895 9.906) (xy -17.5895 8.2042)
				(xy 17.5895 8.2042) (xy 17.5895 9.906) (xy 20.7264 9.906) (xy 20.7264 2.5654) (xy 24.0157 2.5654)
				(xy 24.0157 -2.5654) (xy 20.7264 -2.5654) (xy 20.7264 -6.0198) (xy -20.21586 -6.0198) (xy -20.21586 -5.5118)
				(xy 20.2184 -5.5118) (xy 20.2184 -2.0574) (xy 23.5077 -2.0574) (xy 23.5077 2.0574) (xy 20.2184 2.0574)
				(xy 20.2184 9.398) (xy 18.0975 9.398) (xy 18.0975 7.6962) (xy -18.0975 7.6962) (xy -18.0975 9.398)
				(xy -20.2184 9.398) (xy -20.2184 2.0574) (xy -23.5077 2.0574) (xy -23.5077 -2.0574) (xy -20.2184 -2.0574)
			)
			(stroke
				(width 0)
				(type default)
			)
			(fill no)
			(layer "F.CrtYd")
		)
		(fp_poly
			(pts
				(xy -20.7264 -6.0198) (xy -20.7264 -2.5654) (xy -24.0157 -2.5654) (xy -24.0157 2.5654) (xy -20.7264 2.5654)
				(xy -20.7264 9.906) (xy -17.5895 9.906) (xy -17.5895 8.2042) (xy 17.5895 8.2042) (xy 17.5895 9.906)
				(xy 20.7264 9.906) (xy 20.7264 2.5654) (xy 24.0157 2.5654) (xy 24.0157 -2.5654) (xy 20.7264 -2.5654)
				(xy 20.7264 -6.0198)
			)
			(stroke
				(width 0)
				(type default)
			)
			(fill no)
			(layer "F.Fab")
		)
		(pad "" np_thru_hole circle
			(at -18.999962 -2.350008 90)
			(size 0.254 0.254)
			(drill 1.8542)
			(layers "*.Cu" "*.Mask")
			(clearance 1.1557)
			(thermal_gap 1.1557)
		)
		(pad "" np_thru_hole circle
			(at 18.999962 -2.350008 90)
			(size 0.254 0.254)
			(drill 1.8542)
			(layers "*.Cu" "*.Mask")
			(clearance 1.1557)
			(thermal_gap 1.1557)
		)
		(pad "H1" thru_hole oval
			(at -21.999956 0 90)
			(size 1.524 2.6162)
			(drill oval 0.8128 1.905)
			(layers "*.Cu" "*.Mask")
			(remove_unused_layers no)
			(net "GND")
			(clearance 0.1524)
			(thermal_gap 0.1524)
		)
		(pad "H2" thru_hole oval
			(at 21.999956 0 90)
			(size 1.524 2.6162)
			(drill oval 0.8128 1.905)
			(layers "*.Cu" "*.Mask")
			(remove_unused_layers no)
			(net "GND")
			(clearance 0.1524)
			(thermal_gap 0.1524)
		)
		(pad "P1" smd rect
			(at -1.89992 -4.249928 90)
			(size 0.6604 2.3876)
			(layers "F.Cu" "F.Mask" "F.Paste")
			(net "Net_40")
		)
		(pad "P2" smd rect
			(at -0.62992 -4.249928 90)
			(size 0.6604 2.3876)
			(layers "F.Cu" "F.Mask" "F.Paste")
			(net "Net_39")
		)
		(pad "P3" smd rect
			(at 0.64008 -4.249928 90)
			(size 0.6604 2.3876)
			(layers "F.Cu" "F.Mask" "F.Paste")
			(net "Net_38")
		)
		(pad "P4" smd rect
			(at 1.91008 -4.249928 90)
			(size 0.6604 2.3876)
			(layers "F.Cu" "F.Mask" "F.Paste")
			(net "GND")
		)
		(pad "P5" smd rect
			(at 3.18008 -4.249928 90)
			(size 0.6604 2.3876)
			(layers "F.Cu" "F.Mask" "F.Paste")
			(net "HDD_PRSNT_NET1")
		)
		(pad "P6" smd rect
			(at 4.45008 -4.249928 90)
			(size 0.6604 2.3876)
			(layers "F.Cu" "F.Mask" "F.Paste")
			(net "GND")
		)
		(pad "P7" smd rect
			(at 5.72008 -4.249928 90)
			(size 0.6604 2.3876)
			(layers "F.Cu" "F.Mask" "F.Paste")
			(net "5V_PRE_1")
		)
		(pad "P8" smd rect
			(at 6.99008 -4.249928 90)
			(size 0.6604 2.3876)
			(layers "F.Cu" "F.Mask" "F.Paste")
			(net "P5V_HDD1")
		)
		(pad "P9" smd rect
			(at 8.26008 -4.249928 90)
			(size 0.6604 2.3876)
			(layers "F.Cu" "F.Mask" "F.Paste")
			(net "P5V_HDD1")
		)
		(pad "P10" smd rect
			(at 9.53008 -4.249928 90)
			(size 0.6604 2.3876)
			(layers "F.Cu" "F.Mask" "F.Paste")
			(net "GND")
		)
		(pad "P11" smd rect
			(at 10.80008 -4.249928 90)
			(size 0.6604 2.3876)
			(layers "F.Cu" "F.Mask" "F.Paste")
			(net "ACT_HDD1")
		)
		(pad "P12" smd rect
			(at 12.07008 -4.249928 90)
			(size 0.6604 2.3876)
			(layers "F.Cu" "F.Mask" "F.Paste")
			(net "GND")
		)
		(pad "P13" smd rect
			(at 13.34008 -4.249928 90)
			(size 0.6604 2.3876)
			(layers "F.Cu" "F.Mask" "F.Paste")
			(net "12V_PRE_1")
		)
		(pad "P14" smd rect
			(at 14.61008 -4.249928 90)
			(size 0.6604 2.3876)
			(layers "F.Cu" "F.Mask" "F.Paste")
			(net "P12V_HDD1")
		)
		(pad "P15" smd rect
			(at 15.88008 -4.249928 90)
			(size 0.6604 2.3876)
			(layers "F.Cu" "F.Mask" "F.Paste")
			(net "P12V_HDD1")
		)
		(pad "S1" smd rect
			(at -15.86992 -4.249928 90)
			(size 0.6604 2.3876)
			(layers "F.Cu" "F.Mask" "F.Paste")
			(net "GND")
		)
		(pad "S2" smd rect
			(at -14.59992 -4.249928 90)
			(size 0.6604 2.3876)
			(layers "F.Cu" "F.Mask" "F.Paste")
			(net "SAS2X28_A_HDD1_TX_+")
		)
		(pad "S3" smd rect
			(at -13.32992 -4.249928 90)
			(size 0.6604 2.3876)
			(layers "F.Cu" "F.Mask" "F.Paste")
			(net "SAS2X28_A_HDD1_TX_-")
		)
		(pad "S4" smd rect
			(at -12.05992 -4.249928 90)
			(size 0.6604 2.3876)
			(layers "F.Cu" "F.Mask" "F.Paste")
			(net "GND")
		)
		(pad "S5" smd rect
			(at -10.78992 -4.249928 90)
			(size 0.6604 2.3876)
			(layers "F.Cu" "F.Mask" "F.Paste")
			(net "SAS2X28_DRIVE_RX_N_A1")
		)
		(pad "S6" smd rect
			(at -9.51992 -4.249928 90)
			(size 0.6604 2.3876)
			(layers "F.Cu" "F.Mask" "F.Paste")
			(net "SAS2X28_DRIVE_RX_P_A1")
		)
		(pad "S7" smd rect
			(at -8.24992 -4.249928 90)
			(size 0.6604 2.3876)
			(layers "F.Cu" "F.Mask" "F.Paste")
			(net "GND")
		)
		(pad "S8" smd rect
			(at -7.480046 -2.100072 90)
			(size 0.508 1.905)
			(layers "F.Cu" "F.Mask" "F.Paste")
			(net "GND")
		)
		(pad "S9" smd rect
			(at -6.679946 -2.100072 90)
			(size 0.508 1.905)
			(layers "F.Cu" "F.Mask" "F.Paste")
			(net "SAS2X28_B_HDD1_TX_+")
		)
		(pad "S10" smd rect
			(at -5.8801 -2.100072 90)
			(size 0.508 1.905)
			(layers "F.Cu" "F.Mask" "F.Paste")
			(net "SAS2X28_B_HDD1_TX_-")
		)
		(pad "S11" smd rect
			(at -5.08 -2.100072 90)
			(size 0.508 1.905)
			(layers "F.Cu" "F.Mask" "F.Paste")
			(net "GND")
		)
		(pad "S12" smd rect
			(at -4.2799 -2.100072 90)
			(size 0.508 1.905)
			(layers "F.Cu" "F.Mask" "F.Paste")
			(net "SAS2X28_DRIVE_RX_N_B1")
		)
		(pad "S13" smd rect
			(at -3.480054 -2.100072 90)
			(size 0.508 1.905)
			(layers "F.Cu" "F.Mask" "F.Paste")
			(net "SAS2X28_DRIVE_RX_P_B1")
		)
		(pad "S14" smd rect
			(at -2.679954 -2.100072 90)
			(size 0.508 1.905)
			(layers "F.Cu" "F.Mask" "F.Paste")
			(net "GND")
		)
		(zone
			(layers "F.Cu" "B.Cu" "In1.Cu" "In2.Cu" "In3.Cu" "In4.Cu" "In5.Cu" "In6.Cu")
			(hatch none 0.5)
			(connect_pads
				(clearance 0)
			)
			(min_thickness 0.25)
			(keepout
				(tracks not_allowed)
				(vias allowed)
				(pads allowed)
				(copperpour not_allowed)
				(footprints allowed)
			)
			(placement
				(enabled no)
				(sheetname "")
			)
			(fill
				(thermal_gap 0.5)
				(thermal_bridge_width 0.5)
				(island_removal_mode 0)
			)
			(polygon
				(pts
					(arc
						(start 226.381818 -395.670024)
						(mid 223.918018 -395.670024)
						(end 226.381818 -395.670024)
					)
				)
			)
		)
		(zone
			(layers "F.Cu" "B.Cu" "In1.Cu" "In2.Cu" "In3.Cu" "In4.Cu" "In5.Cu" "In6.Cu")
			(hatch none 0.5)
			(connect_pads
				(clearance 0)
			)
			(min_thickness 0.25)
			(keepout
				(tracks not_allowed)
				(vias allowed)
				(pads allowed)
				(copperpour not_allowed)
				(footprints allowed)
			)
			(placement
				(enabled no)
				(sheetname "")
			)
			(fill
				(thermal_gap 0.5)
				(thermal_bridge_width 0.5)
				(island_removal_mode 0)
			)
			(polygon
				(pts
					(arc
						(start 226.381818 -357.6701)
						(mid 223.918018 -357.6701)
						(end 226.381818 -357.6701)
					)
				)
			)
		)
	)
	(footprint ""
		(layer "F.Cu")
		(at 50.546 -416.433 180)
		(property "Reference" "C389"
			(at 0 0 180)
			(layer "F.SilkS")
			(hide yes)
			(effects
				(font
					(size 1.27 1.27)
				)
			)
		)
		(property "Value" "SCD033U25V2KX-GP"
			(at 1.1811 -2.7051 180)
			(unlocked yes)
			(layer "F.Fab")
			(hide yes)
			(effects
				(font
					(size 1.016 1.016)
					(thickness 0.1524)
				)
			)
		)
		(property "Device Type" "C402H22"
			(at 1.1811 -4.2291 180)
			(unlocked yes)
			(layer "F.Fab")
			(hide yes)
			(effects
				(font
					(size 1.016 1.016)
					(thickness 0.1524)
				)
			)
		)
		(duplicate_pad_numbers_are_jumpers no)
		(fp_rect
			(start -0.4318 0.9525)
			(end 0.4318 -0.9525)
			(stroke
				(width 0)
				(type default)
			)
			(fill no)
			(layer "F.CrtYd")
		)
		(fp_rect
			(start -0.4318 0.9525)
			(end 0.4318 -0.9525)
			(stroke
				(width 0)
				(type default)
			)
			(fill no)
			(layer "F.Fab")
		)
		(pad "1" smd custom
			(at 0 -0.4445 180)
			(size 0.1524 0.1524)
			(layers "F.Cu" "F.Mask" "F.Paste")
			(net "P12V")
			(options
				(clearance outline)
				(anchor circle)
			)
			(primitives
				(gr_poly
					(pts
						(arc
							(start 0.3048 -0.2032)
							(mid 0.275042 -0.275042)
							(end 0.2032 -0.3048)
						)
						(arc
							(start -0.2032 -0.3048)
							(mid -0.275042 -0.275042)
							(end -0.3048 -0.2032)
						)
						(arc
							(start -0.3048 0.2032)
							(mid -0.275042 0.275042)
							(end -0.2032 0.3048)
						)
						(arc
							(start 0.2032 0.3048)
							(mid 0.275042 0.275042)
							(end 0.3048 0.2032)
						)
					)
					(width 0)
					(fill yes)
				)
			)
		)
		(pad "2" smd custom
			(at 0 0.4445 180)
			(size 0.1524 0.1524)
			(layers "F.Cu" "F.Mask" "F.Paste")
			(net "SW_HDD10_N")
			(options
				(clearance outline)
				(anchor circle)
			)
			(primitives
				(gr_poly
					(pts
						(arc
							(start 0.3048 -0.2032)
							(mid 0.275042 -0.275042)
							(end 0.2032 -0.3048)
						)
						(arc
							(start -0.2032 -0.3048)
							(mid -0.275042 -0.275042)
							(end -0.3048 -0.2032)
						)
						(arc
							(start -0.3048 0.2032)
							(mid -0.275042 0.275042)
							(end -0.2032 0.3048)
						)
						(arc
							(start 0.2032 0.3048)
							(mid 0.275042 0.275042)
							(end 0.3048 0.2032)
						)
					)
					(width 0)
					(fill yes)
				)
			)
		)
	)
	(footprint ""
		(layer "F.Cu")
		(at 59.816746 -21.0947)
		(property "Reference" "PC17"
			(at 0 0 0)
			(layer "F.SilkS")
			(hide yes)
			(effects
				(font
					(size 1.27 1.27)
				)
			)
		)
		(property "Value" "SC1U10V2KX-1GP"
			(at 1.1811 -2.7051 0)
			(unlocked yes)
			(layer "F.Fab")
			(hide yes)
			(effects
				(font
					(size 1.016 1.016)
					(thickness 0.1524)
				)
			)
		)
		(property "Device Type" "C402H22"
			(at 1.1811 -4.2291 0)
			(unlocked yes)
			(layer "F.Fab")
			(hide yes)
			(effects
				(font
					(size 1.016 1.016)
					(thickness 0.1524)
				)
			)
		)
		(duplicate_pad_numbers_are_jumpers no)
		(fp_rect
			(start -0.4318 0.9525)
			(end 0.4318 -0.9525)
			(stroke
				(width 0)
				(type default)
			)
			(fill no)
			(layer "F.CrtYd")
		)
		(fp_rect
			(start -0.4318 0.9525)
			(end 0.4318 -0.9525)
			(stroke
				(width 0)
				(type default)
			)
			(fill no)
			(layer "F.Fab")
		)
		(pad "1" smd custom
			(at 0 -0.4445)
			(size 0.1524 0.1524)
			(layers "F.Cu" "F.Mask" "F.Paste")
			(net "P5VB_VREG")
			(options
				(clearance outline)
				(anchor circle)
			)
			(primitives
				(gr_poly
					(pts
						(arc
							(start 0.3048 -0.2032)
							(mid 0.275042 -0.275042)
							(end 0.2032 -0.3048)
						)
						(arc
							(start -0.2032 -0.3048)
							(mid -0.275042 -0.275042)
							(end -0.3048 -0.2032)
						)
						(arc
							(start -0.3048 0.2032)
							(mid -0.275042 0.275042)
							(end -0.2032 0.3048)
						)
						(arc
							(start 0.2032 0.3048)
							(mid 0.275042 0.275042)
							(end 0.3048 0.2032)
						)
					)
					(width 0)
					(fill yes)
				)
			)
		)
		(pad "2" smd custom
			(at 0 0.4445)
			(size 0.1524 0.1524)
			(layers "F.Cu" "F.Mask" "F.Paste")
			(net "GND")
			(options
				(clearance outline)
				(anchor circle)
			)
			(primitives
				(gr_poly
					(pts
						(arc
							(start 0.3048 -0.2032)
							(mid 0.275042 -0.275042)
							(end 0.2032 -0.3048)
						)
						(arc
							(start -0.2032 -0.3048)
							(mid -0.275042 -0.275042)
							(end -0.3048 -0.2032)
						)
						(arc
							(start -0.3048 0.2032)
							(mid -0.275042 0.275042)
							(end -0.2032 0.3048)
						)
						(arc
							(start 0.2032 0.3048)
							(mid 0.275042 0.275042)
							(end 0.3048 0.2032)
						)
					)
					(width 0)
					(fill yes)
				)
			)
		)
	)
	(footprint ""
		(layer "F.Cu")
		(at 47.091346 -244.6274 -90)
		(property "Reference" "R497"
			(at 0 0 270)
			(layer "F.SilkS")
			(hide yes)
			(effects
				(font
					(size 1.27 1.27)
				)
			)
		)
		(property "Value" "1KR2F-3-GP"
			(at 0.064008 -3.993896 270)
			(unlocked yes)
			(layer "F.Fab")
			(hide yes)
			(effects
				(font
					(size 1.016 1.016)
					(thickness 0.1524)
				)
			)
		)
		(property "Device Type" "R402H16"
			(at 0.064008 -5.517896 270)
			(unlocked yes)
			(layer "F.Fab")
			(hide yes)
			(effects
				(font
					(size 1.016 1.016)
					(thickness 0.1524)
				)
			)
		)
		(duplicate_pad_numbers_are_jumpers no)
		(fp_line
			(start -0.508 -0.9398)
			(end -0.508 0.9398)
			(stroke
				(width 0.1524)
				(type default)
			)
			(layer "F.SilkS")
		)
		(fp_line
			(start 0.508 -0.9398)
			(end -0.508 -0.9398)
			(stroke
				(width 0.1524)
				(type default)
			)
			(layer "F.SilkS")
		)
		(fp_rect
			(start -0.508 0.9398)
			(end 0.508 -0.9398)
			(stroke
				(width 0)
				(type default)
			)
			(fill no)
			(layer "F.CrtYd")
		)
		(fp_rect
			(start -0.508 0.9398)
			(end 0.508 -0.9398)
			(stroke
				(width 0)
				(type default)
			)
			(fill no)
			(layer "F.Fab")
		)
		(pad "1" smd custom
			(at 0 -0.4445 270)
			(size 0.1397 0.1397)
			(layers "F.Cu" "F.Mask" "F.Paste")
			(net "FLT_HDD7_B")
			(options
				(clearance outline)
				(anchor circle)
			)
			(primitives
				(gr_poly
					(pts
						(arc
							(start -0.1778 -0.2794)
							(mid -0.249642 -0.249642)
							(end -0.2794 -0.1778)
						)
						(arc
							(start -0.2794 0.1778)
							(mid -0.249642 0.249642)
							(end -0.1778 0.2794)
						)
						(arc
							(start 0.1778 0.2794)
							(mid 0.249642 0.249642)
							(end 0.2794 0.1778)
						)
						(arc
							(start 0.2794 -0.1778)
							(mid 0.249642 -0.249642)
							(end 0.1778 -0.2794)
						)
					)
					(width 0)
					(fill yes)
				)
			)
		)
		(pad "2" smd custom
			(at 0 0.4445 270)
			(size 0.1397 0.1397)
			(layers "F.Cu" "F.Mask" "F.Paste")
			(net "FLT_HDD7_DRIVE")
			(options
				(clearance outline)
				(anchor circle)
			)
			(primitives
				(gr_poly
					(pts
						(arc
							(start -0.1778 -0.2794)
							(mid -0.249642 -0.249642)
							(end -0.2794 -0.1778)
						)
						(arc
							(start -0.2794 0.1778)
							(mid -0.249642 0.249642)
							(end -0.1778 0.2794)
						)
						(arc
							(start 0.1778 0.2794)
							(mid 0.249642 0.249642)
							(end 0.2794 0.1778)
						)
						(arc
							(start 0.2794 -0.1778)
							(mid 0.249642 -0.249642)
							(end 0.1778 -0.2794)
						)
					)
					(width 0)
					(fill yes)
				)
			)
		)
	)
	(footprint ""
		(layer "F.Cu")
		(at 191.897 -179.832)
		(property "Reference" "C158"
			(at 0 0 0)
			(layer "F.SilkS")
			(hide yes)
			(effects
				(font
					(size 1.27 1.27)
				)
			)
		)
		(property "Value" "SCD1U10V2KX-5GP"
			(at 1.1811 -2.7051 0)
			(unlocked yes)
			(layer "F.Fab")
			(hide yes)
			(effects
				(font
					(size 1.016 1.016)
					(thickness 0.1524)
				)
			)
		)
		(property "Device Type" "C402H22"
			(at 1.1811 -4.2291 0)
			(unlocked yes)
			(layer "F.Fab")
			(hide yes)
			(effects
				(font
					(size 1.016 1.016)
					(thickness 0.1524)
				)
			)
		)
		(duplicate_pad_numbers_are_jumpers no)
		(fp_rect
			(start -0.4318 0.9525)
			(end 0.4318 -0.9525)
			(stroke
				(width 0)
				(type default)
			)
			(fill no)
			(layer "F.CrtYd")
		)
		(fp_rect
			(start -0.4318 0.9525)
			(end 0.4318 -0.9525)
			(stroke
				(width 0)
				(type default)
			)
			(fill no)
			(layer "F.Fab")
		)
		(pad "1" smd custom
			(at 0 -0.4445)
			(size 0.1524 0.1524)
			(layers "F.Cu" "F.Mask" "F.Paste")
			(net "P3V3")
			(options
				(clearance outline)
				(anchor circle)
			)
			(primitives
				(gr_poly
					(pts
						(arc
							(start 0.3048 -0.2032)
							(mid 0.275042 -0.275042)
							(end 0.2032 -0.3048)
						)
						(arc
							(start -0.2032 -0.3048)
							(mid -0.275042 -0.275042)
							(end -0.3048 -0.2032)
						)
						(arc
							(start -0.3048 0.2032)
							(mid -0.275042 0.275042)
							(end -0.2032 0.3048)
						)
						(arc
							(start 0.2032 0.3048)
							(mid 0.275042 0.275042)
							(end 0.3048 0.2032)
						)
					)
					(width 0)
					(fill yes)
				)
			)
		)
		(pad "2" smd custom
			(at 0 0.4445)
			(size 0.1524 0.1524)
			(layers "F.Cu" "F.Mask" "F.Paste")
			(net "GND")
			(options
				(clearance outline)
				(anchor circle)
			)
			(primitives
				(gr_poly
					(pts
						(arc
							(start 0.3048 -0.2032)
							(mid 0.275042 -0.275042)
							(end 0.2032 -0.3048)
						)
						(arc
							(start -0.2032 -0.3048)
							(mid -0.275042 -0.275042)
							(end -0.3048 -0.2032)
						)
						(arc
							(start -0.3048 0.2032)
							(mid -0.275042 0.275042)
							(end -0.2032 0.3048)
						)
						(arc
							(start 0.2032 0.3048)
							(mid 0.275042 0.275042)
							(end 0.3048 0.2032)
						)
					)
					(width 0)
					(fill yes)
				)
			)
		)
	)
	(footprint ""
		(layer "F.Cu")
		(at 33.7058 -320.0146 180)
		(property "Reference" "C287"
			(at 0 0 180)
			(layer "F.SilkS")
			(hide yes)
			(effects
				(font
					(size 1.27 1.27)
				)
			)
		)
		(property "Value" "SC10U25V6KX-1GP"
			(at -0.0762 -5.1308 180)
			(unlocked yes)
			(layer "F.Fab")
			(hide yes)
			(effects
				(font
					(size 1.016 1.016)
					(thickness 0.1524)
				)
			)
		)
		(property "Device Type" "C1206H71"
			(at -0.127 -6.6548 180)
			(unlocked yes)
			(layer "F.Fab")
			(hide yes)
			(effects
				(font
					(size 1.016 1.016)
					(thickness 0.1524)
				)
			)
		)
		(duplicate_pad_numbers_are_jumpers no)
		(fp_line
			(start 1.016 2.2352)
			(end -1.016 2.2352)
			(stroke
				(width 0.1524)
				(type default)
			)
			(layer "F.SilkS")
		)
		(fp_line
			(start 1.016 0.8382)
			(end 1.016 2.2352)
			(stroke
				(width 0.1524)
				(type default)
			)
			(layer "F.SilkS")
		)
		(fp_line
			(start 1.016 -2.2352)
			(end 1.016 -0.8382)
			(stroke
				(width 0.1524)
				(type default)
			)
			(layer "F.SilkS")
		)
		(fp_line
			(start -1.016 2.2352)
			(end -1.016 0.8382)
			(stroke
				(width 0.1524)
				(type default)
			)
			(layer "F.SilkS")
		)
		(fp_line
			(start -1.016 -0.8382)
			(end -1.016 -2.2352)
			(stroke
				(width 0.1524)
				(type default)
			)
			(layer "F.SilkS")
		)
		(fp_line
			(start -1.016 -2.2352)
			(end 1.016 -2.2352)
			(stroke
				(width 0.1524)
				(type default)
			)
			(layer "F.SilkS")
		)
		(fp_rect
			(start -1.0922 2.3114)
			(end 1.0922 -2.3114)
			(stroke
				(width 0)
				(type default)
			)
			(fill no)
			(layer "F.CrtYd")
		)
		(fp_poly
			(pts
				(xy 1.0922 -2.3114) (xy 1.0922 2.3114) (xy -1.0922 2.3114) (xy -1.0922 -2.3114)
			)
			(stroke
				(width 0)
				(type default)
			)
			(fill no)
			(layer "F.Fab")
		)
		(pad "1" smd rect
			(at 0 -1.397 180)
			(size 1.651 1.27)
			(layers "F.Cu" "F.Mask" "F.Paste")
			(net "P12V_HDD11")
		)
		(pad "2" smd rect
			(at 0 1.397 180)
			(size 1.651 1.27)
			(layers "F.Cu" "F.Mask" "F.Paste")
			(net "GND")
		)
	)
	(footprint ""
		(layer "F.Cu")
		(at 55.117746 -381.5207)
		(property "Reference" "C204"
			(at 0 0 0)
			(layer "F.SilkS")
			(hide yes)
			(effects
				(font
					(size 1.27 1.27)
				)
			)
		)
		(property "Value" "SCD01U50V2KX-1GP"
			(at 1.1811 -2.7051 0)
			(unlocked yes)
			(layer "F.Fab")
			(hide yes)
			(effects
				(font
					(size 1.016 1.016)
					(thickness 0.1524)
				)
			)
		)
		(property "Device Type" "C402H22"
			(at 1.1811 -4.2291 0)
			(unlocked yes)
			(layer "F.Fab")
			(hide yes)
			(effects
				(font
					(size 1.016 1.016)
					(thickness 0.1524)
				)
			)
		)
		(duplicate_pad_numbers_are_jumpers no)
		(fp_rect
			(start -0.4318 0.9525)
			(end 0.4318 -0.9525)
			(stroke
				(width 0)
				(type default)
			)
			(fill no)
			(layer "F.CrtYd")
		)
		(fp_rect
			(start -0.4318 0.9525)
			(end 0.4318 -0.9525)
			(stroke
				(width 0)
				(type default)
			)
			(fill no)
			(layer "F.Fab")
		)
		(pad "1" smd custom
			(at 0 -0.4445)
			(size 0.1524 0.1524)
			(layers "F.Cu" "F.Mask" "F.Paste")
			(net "HDD_PRSNT_NET6")
			(options
				(clearance outline)
				(anchor circle)
			)
			(primitives
				(gr_poly
					(pts
						(arc
							(start 0.3048 -0.2032)
							(mid 0.275042 -0.275042)
							(end 0.2032 -0.3048)
						)
						(arc
							(start -0.2032 -0.3048)
							(mid -0.275042 -0.275042)
							(end -0.3048 -0.2032)
						)
						(arc
							(start -0.3048 0.2032)
							(mid -0.275042 0.275042)
							(end -0.2032 0.3048)
						)
						(arc
							(start 0.2032 0.3048)
							(mid 0.275042 0.275042)
							(end 0.3048 0.2032)
						)
					)
					(width 0)
					(fill yes)
				)
			)
		)
		(pad "2" smd custom
			(at 0 0.4445)
			(size 0.1524 0.1524)
			(layers "F.Cu" "F.Mask" "F.Paste")
			(net "GND")
			(options
				(clearance outline)
				(anchor circle)
			)
			(primitives
				(gr_poly
					(pts
						(arc
							(start 0.3048 -0.2032)
							(mid 0.275042 -0.275042)
							(end 0.2032 -0.3048)
						)
						(arc
							(start -0.2032 -0.3048)
							(mid -0.275042 -0.275042)
							(end -0.3048 -0.2032)
						)
						(arc
							(start -0.3048 0.2032)
							(mid -0.275042 0.275042)
							(end -0.2032 0.3048)
						)
						(arc
							(start 0.2032 0.3048)
							(mid 0.275042 0.275042)
							(end 0.3048 0.2032)
						)
					)
					(width 0)
					(fill yes)
				)
			)
		)
	)
	(footprint ""
		(layer "F.Cu")
		(at 252.499622 -479.996754)
		(property "Reference" "H11"
			(at 0 0 0)
			(layer "F.SilkS")
			(hide yes)
			(effects
				(font
					(size 1.27 1.27)
				)
			)
		)
		(property "Value" "HOLE315R157"
			(at -0.116332 -8.41375 0)
			(unlocked yes)
			(layer "F.Fab")
			(hide yes)
			(effects
				(font
					(size 1.016 1.016)
					(thickness 0.1524)
				)
			)
		)
		(property "Device Type" "HOLE315R157"
			(at -0.116332 -6.88975 0)
			(unlocked yes)
			(layer "F.Fab")
			(hide yes)
			(effects
				(font
					(size 1.016 1.016)
					(thickness 0.1524)
				)
			)
		)
		(duplicate_pad_numbers_are_jumpers no)
		(fp_poly
			(pts
				(arc
					(start 4.3053 0)
					(mid -4.3053 0)
					(end 4.3053 0)
				)
			)
			(stroke
				(width 0)
				(type default)
			)
			(fill no)
			(layer "F.CrtYd")
		)
		(fp_poly
			(pts
				(arc
					(start 4.3053 0)
					(mid -4.3053 0)
					(end 4.3053 0)
				)
			)
			(stroke
				(width 0)
				(type default)
			)
			(fill no)
			(layer "F.Fab")
		)
		(pad "1" thru_hole circle
			(at 0 0)
			(size 8.001 8.001)
			(drill 3.9878)
			(layers "*.Cu" "*.Mask")
			(remove_unused_layers no)
			(net "GND")
			(clearance -1.4986)
			(thermal_gap 0.3048)
			(padstack
				(mode front_inner_back)
				(layer "Inner"
					(shape circle)
					(size 4.3942 4.3942)
					(clearance 0.3048)
				)
				(layer "B.Cu"
					(shape circle)
					(size 8.001 8.001)
					(clearance -1.4986)
				)
			)
		)
	)
	(footprint ""
		(layer "F.Cu")
		(at 77.469746 -394.8557 -90)
		(property "Reference" "R192"
			(at 0 0 270)
			(layer "F.SilkS")
			(hide yes)
			(effects
				(font
					(size 1.27 1.27)
				)
			)
		)
		(property "Value" "1KR2F-3-GP"
			(at 0.064008 -3.993896 270)
			(unlocked yes)
			(layer "F.Fab")
			(hide yes)
			(effects
				(font
					(size 1.016 1.016)
					(thickness 0.1524)
				)
			)
		)
		(property "Device Type" "R402H16"
			(at 0.064008 -5.517896 270)
			(unlocked yes)
			(layer "F.Fab")
			(hide yes)
			(effects
				(font
					(size 1.016 1.016)
					(thickness 0.1524)
				)
			)
		)
		(duplicate_pad_numbers_are_jumpers no)
		(fp_line
			(start -0.508 -0.9398)
			(end -0.508 0.9398)
			(stroke
				(width 0.1524)
				(type default)
			)
			(layer "F.SilkS")
		)
		(fp_line
			(start 0.508 -0.9398)
			(end -0.508 -0.9398)
			(stroke
				(width 0.1524)
				(type default)
			)
			(layer "F.SilkS")
		)
		(fp_rect
			(start -0.508 0.9398)
			(end 0.508 -0.9398)
			(stroke
				(width 0)
				(type default)
			)
			(fill no)
			(layer "F.CrtYd")
		)
		(fp_rect
			(start -0.508 0.9398)
			(end 0.508 -0.9398)
			(stroke
				(width 0)
				(type default)
			)
			(fill no)
			(layer "F.Fab")
		)
		(pad "1" smd custom
			(at 0 -0.4445 270)
			(size 0.1397 0.1397)
			(layers "F.Cu" "F.Mask" "F.Paste")
			(net "P3V3")
			(options
				(clearance outline)
				(anchor circle)
			)
			(primitives
				(gr_poly
					(pts
						(arc
							(start -0.1778 -0.2794)
							(mid -0.249642 -0.249642)
							(end -0.2794 -0.1778)
						)
						(arc
							(start -0.2794 0.1778)
							(mid -0.249642 0.249642)
							(end -0.1778 0.2794)
						)
						(arc
							(start 0.1778 0.2794)
							(mid 0.249642 0.249642)
							(end 0.2794 0.1778)
						)
						(arc
							(start 0.2794 -0.1778)
							(mid 0.249642 -0.249642)
							(end 0.1778 -0.2794)
						)
					)
					(width 0)
					(fill yes)
				)
			)
		)
		(pad "2" smd custom
			(at 0 0.4445 270)
			(size 0.1397 0.1397)
			(layers "F.Cu" "F.Mask" "F.Paste")
			(net "SW_PWR_HDD6")
			(options
				(clearance outline)
				(anchor circle)
			)
			(primitives
				(gr_poly
					(pts
						(arc
							(start -0.1778 -0.2794)
							(mid -0.249642 -0.249642)
							(end -0.2794 -0.1778)
						)
						(arc
							(start -0.2794 0.1778)
							(mid -0.249642 0.249642)
							(end -0.1778 0.2794)
						)
						(arc
							(start 0.1778 0.2794)
							(mid 0.249642 0.249642)
							(end 0.2794 0.1778)
						)
						(arc
							(start 0.2794 -0.1778)
							(mid 0.249642 -0.249642)
							(end 0.1778 -0.2794)
						)
					)
					(width 0)
					(fill yes)
				)
			)
		)
	)
	(footprint ""
		(layer "F.Cu")
		(at 42.468546 -131.7879 180)
		(property "Reference" "R316"
			(at 0 0 180)
			(layer "F.SilkS")
			(hide yes)
			(effects
				(font
					(size 1.27 1.27)
				)
			)
		)
		(property "Value" "4K7R2J-2-GP"
			(at 0.064008 -3.993896 180)
			(unlocked yes)
			(layer "F.Fab")
			(hide yes)
			(effects
				(font
					(size 1.016 1.016)
					(thickness 0.1524)
				)
			)
		)
		(property "Device Type" "R402H16"
			(at 0.064008 -5.517896 180)
			(unlocked yes)
			(layer "F.Fab")
			(hide yes)
			(effects
				(font
					(size 1.016 1.016)
					(thickness 0.1524)
				)
			)
		)
		(duplicate_pad_numbers_are_jumpers no)
		(fp_line
			(start 0.508 -0.9398)
			(end -0.508 -0.9398)
			(stroke
				(width 0.1524)
				(type default)
			)
			(layer "F.SilkS")
		)
		(fp_line
			(start -0.508 -0.9398)
			(end -0.508 0.9398)
			(stroke
				(width 0.1524)
				(type default)
			)
			(layer "F.SilkS")
		)
		(fp_rect
			(start -0.508 0.9398)
			(end 0.508 -0.9398)
			(stroke
				(width 0)
				(type default)
			)
			(fill no)
			(layer "F.CrtYd")
		)
		(fp_rect
			(start -0.508 0.9398)
			(end 0.508 -0.9398)
			(stroke
				(width 0)
				(type default)
			)
			(fill no)
			(layer "F.Fab")
		)
		(pad "1" smd custom
			(at 0 -0.4445 180)
			(size 0.1397 0.1397)
			(layers "F.Cu" "F.Mask" "F.Paste")
			(net "P3V3")
			(options
				(clearance outline)
				(anchor circle)
			)
			(primitives
				(gr_poly
					(pts
						(arc
							(start -0.1778 -0.2794)
							(mid -0.249642 -0.249642)
							(end -0.2794 -0.1778)
						)
						(arc
							(start -0.2794 0.1778)
							(mid -0.249642 0.249642)
							(end -0.1778 0.2794)
						)
						(arc
							(start 0.1778 0.2794)
							(mid 0.249642 0.249642)
							(end 0.2794 0.1778)
						)
						(arc
							(start 0.2794 -0.1778)
							(mid 0.249642 -0.249642)
							(end 0.1778 -0.2794)
						)
					)
					(width 0)
					(fill yes)
				)
			)
		)
		(pad "2" smd custom
			(at 0 0.4445 180)
			(size 0.1397 0.1397)
			(layers "F.Cu" "F.Mask" "F.Paste")
			(net "I2C_B_TMP2_A1")
			(options
				(clearance outline)
				(anchor circle)
			)
			(primitives
				(gr_poly
					(pts
						(arc
							(start -0.1778 -0.2794)
							(mid -0.249642 -0.249642)
							(end -0.2794 -0.1778)
						)
						(arc
							(start -0.2794 0.1778)
							(mid -0.249642 0.249642)
							(end -0.1778 0.2794)
						)
						(arc
							(start 0.1778 0.2794)
							(mid 0.249642 0.249642)
							(end 0.2794 0.1778)
						)
						(arc
							(start 0.2794 -0.1778)
							(mid 0.249642 -0.249642)
							(end 0.1778 -0.2794)
						)
					)
					(width 0)
					(fill yes)
				)
			)
		)
	)
	(footprint ""
		(layer "F.Cu")
		(at 70.231 -81.153)
		(property "Reference" "TP34"
			(at 0 0 0)
			(layer "F.SilkS")
			(hide yes)
			(effects
				(font
					(size 1.27 1.27)
				)
			)
		)
		(property "Value" "TPAD32-GP"
			(at 0 -3.166364 0)
			(unlocked yes)
			(layer "F.Fab")
			(hide yes)
			(effects
				(font
					(size 1.016 1.016)
					(thickness 0.1524)
				)
			)
		)
		(property "Device Type" "TPAD32"
			(at 0 -4.690618 0)
			(unlocked yes)
			(layer "F.Fab")
			(hide yes)
			(effects
				(font
					(size 1.016 1.016)
					(thickness 0.1524)
				)
			)
		)
		(duplicate_pad_numbers_are_jumpers no)
		(fp_poly
			(pts
				(arc
					(start 0.4064 0)
					(mid -0.4064 0)
					(end 0.4064 0)
				)
			)
			(stroke
				(width 0)
				(type default)
			)
			(fill no)
			(layer "F.CrtYd")
		)
		(fp_poly
			(pts
				(arc
					(start 0.7112 0)
					(mid -0.7112 0)
					(end 0.7112 0)
				)
			)
			(stroke
				(width 0)
				(type default)
			)
			(fill no)
			(layer "F.Fab")
		)
		(pad "1" smd circle
			(at 0 0)
			(size 0.8128 0.8128)
			(layers "F.Cu" "F.Mask" "F.Paste")
			(net "ACT_HDD9")
		)
	)
	(footprint ""
		(layer "F.Cu")
		(at 32.86506 -366.075214 -90)
		(property "Reference" "C198"
			(at 0 0 270)
			(layer "F.SilkS")
			(hide yes)
			(effects
				(font
					(size 1.27 1.27)
				)
			)
		)
		(property "Value" "SCD01U50V2KX-1GP"
			(at 1.1811 -2.7051 270)
			(unlocked yes)
			(layer "F.Fab")
			(hide yes)
			(effects
				(font
					(size 1.016 1.016)
					(thickness 0.1524)
				)
			)
		)
		(property "Device Type" "C402H22"
			(at 1.1811 -4.2291 270)
			(unlocked yes)
			(layer "F.Fab")
			(hide yes)
			(effects
				(font
					(size 1.016 1.016)
					(thickness 0.1524)
				)
			)
		)
		(duplicate_pad_numbers_are_jumpers no)
		(fp_rect
			(start -0.4318 0.9525)
			(end 0.4318 -0.9525)
			(stroke
				(width 0)
				(type default)
			)
			(fill no)
			(layer "F.CrtYd")
		)
		(fp_rect
			(start -0.4318 0.9525)
			(end 0.4318 -0.9525)
			(stroke
				(width 0)
				(type default)
			)
			(fill no)
			(layer "F.Fab")
		)
		(pad "1" smd custom
			(at 0 -0.4445 270)
			(size 0.1524 0.1524)
			(layers "F.Cu" "F.Mask" "F.Paste")
			(net "SAS2X28_DRIVE_RX_N_A6")
			(options
				(clearance outline)
				(anchor circle)
			)
			(primitives
				(gr_poly
					(pts
						(arc
							(start 0.3048 -0.2032)
							(mid 0.275042 -0.275042)
							(end 0.2032 -0.3048)
						)
						(arc
							(start -0.2032 -0.3048)
							(mid -0.275042 -0.275042)
							(end -0.3048 -0.2032)
						)
						(arc
							(start -0.3048 0.2032)
							(mid -0.275042 0.275042)
							(end -0.2032 0.3048)
						)
						(arc
							(start 0.2032 0.3048)
							(mid 0.275042 0.275042)
							(end 0.3048 0.2032)
						)
					)
					(width 0)
					(fill yes)
				)
			)
		)
		(pad "2" smd custom
			(at 0 0.4445 270)
			(size 0.1524 0.1524)
			(layers "F.Cu" "F.Mask" "F.Paste")
			(net "SAS2X28_A_HDD6_RX_-")
			(options
				(clearance outline)
				(anchor circle)
			)
			(primitives
				(gr_poly
					(pts
						(arc
							(start 0.3048 -0.2032)
							(mid 0.275042 -0.275042)
							(end 0.2032 -0.3048)
						)
						(arc
							(start -0.2032 -0.3048)
							(mid -0.275042 -0.275042)
							(end -0.3048 -0.2032)
						)
						(arc
							(start -0.3048 0.2032)
							(mid -0.275042 0.275042)
							(end -0.2032 0.3048)
						)
						(arc
							(start 0.2032 0.3048)
							(mid 0.275042 0.275042)
							(end 0.3048 0.2032)
						)
					)
					(width 0)
					(fill yes)
				)
			)
		)
	)
	(footprint ""
		(layer "F.Cu")
		(at 234.695746 -43.8277 90)
		(property "Reference" "R156"
			(at 0 0 90)
			(layer "F.SilkS")
			(hide yes)
			(effects
				(font
					(size 1.27 1.27)
				)
			)
		)
		(property "Value" "10KR2F-2-GP"
			(at 0.064008 -3.993896 90)
			(unlocked yes)
			(layer "F.Fab")
			(hide yes)
			(effects
				(font
					(size 1.016 1.016)
					(thickness 0.1524)
				)
			)
		)
		(property "Device Type" "R402H16"
			(at 0.064008 -5.517896 90)
			(unlocked yes)
			(layer "F.Fab")
			(hide yes)
			(effects
				(font
					(size 1.016 1.016)
					(thickness 0.1524)
				)
			)
		)
		(duplicate_pad_numbers_are_jumpers no)
		(fp_line
			(start 0.508 -0.9398)
			(end -0.508 -0.9398)
			(stroke
				(width 0.1524)
				(type default)
			)
			(layer "F.SilkS")
		)
		(fp_line
			(start -0.508 -0.9398)
			(end -0.508 0.9398)
			(stroke
				(width 0.1524)
				(type default)
			)
			(layer "F.SilkS")
		)
		(fp_rect
			(start -0.508 0.9398)
			(end 0.508 -0.9398)
			(stroke
				(width 0)
				(type default)
			)
			(fill no)
			(layer "F.CrtYd")
		)
		(fp_rect
			(start -0.508 0.9398)
			(end 0.508 -0.9398)
			(stroke
				(width 0)
				(type default)
			)
			(fill no)
			(layer "F.Fab")
		)
		(pad "1" smd custom
			(at 0 -0.4445 90)
			(size 0.1397 0.1397)
			(layers "F.Cu" "F.Mask" "F.Paste")
			(net "P5VA")
			(options
				(clearance outline)
				(anchor circle)
			)
			(primitives
				(gr_poly
					(pts
						(arc
							(start -0.1778 -0.2794)
							(mid -0.249642 -0.249642)
							(end -0.2794 -0.1778)
						)
						(arc
							(start -0.2794 0.1778)
							(mid -0.249642 0.249642)
							(end -0.1778 0.2794)
						)
						(arc
							(start 0.1778 0.2794)
							(mid 0.249642 0.249642)
							(end 0.2794 0.1778)
						)
						(arc
							(start 0.2794 -0.1778)
							(mid 0.249642 -0.249642)
							(end 0.1778 -0.2794)
						)
					)
					(width 0)
					(fill yes)
				)
			)
		)
		(pad "2" smd custom
			(at 0 0.4445 90)
			(size 0.1397 0.1397)
			(layers "F.Cu" "F.Mask" "F.Paste")
			(net "DRIVE_ACT_4")
			(options
				(clearance outline)
				(anchor circle)
			)
			(primitives
				(gr_poly
					(pts
						(arc
							(start -0.1778 -0.2794)
							(mid -0.249642 -0.249642)
							(end -0.2794 -0.1778)
						)
						(arc
							(start -0.2794 0.1778)
							(mid -0.249642 0.249642)
							(end -0.1778 0.2794)
						)
						(arc
							(start 0.1778 0.2794)
							(mid 0.249642 0.249642)
							(end 0.2794 0.1778)
						)
						(arc
							(start 0.2794 -0.1778)
							(mid 0.249642 -0.249642)
							(end 0.1778 -0.2794)
						)
					)
					(width 0)
					(fill yes)
				)
			)
		)
	)
	(footprint ""
		(layer "F.Cu")
		(at 242.061746 -24.3967 90)
		(property "Reference" "PC10"
			(at 0 0 90)
			(layer "F.SilkS")
			(hide yes)
			(effects
				(font
					(size 1.27 1.27)
				)
			)
		)
		(property "Value" "SC1U10V2KX-1GP"
			(at 1.1811 -2.7051 90)
			(unlocked yes)
			(layer "F.Fab")
			(hide yes)
			(effects
				(font
					(size 1.016 1.016)
					(thickness 0.1524)
				)
			)
		)
		(property "Device Type" "C402H22"
			(at 1.1811 -4.2291 90)
			(unlocked yes)
			(layer "F.Fab")
			(hide yes)
			(effects
				(font
					(size 1.016 1.016)
					(thickness 0.1524)
				)
			)
		)
		(duplicate_pad_numbers_are_jumpers no)
		(fp_rect
			(start -0.4318 0.9525)
			(end 0.4318 -0.9525)
			(stroke
				(width 0)
				(type default)
			)
			(fill no)
			(layer "F.CrtYd")
		)
		(fp_rect
			(start -0.4318 0.9525)
			(end 0.4318 -0.9525)
			(stroke
				(width 0)
				(type default)
			)
			(fill no)
			(layer "F.Fab")
		)
		(pad "1" smd custom
			(at 0 -0.4445 90)
			(size 0.1524 0.1524)
			(layers "F.Cu" "F.Mask" "F.Paste")
			(net "P5VA_VREG")
			(options
				(clearance outline)
				(anchor circle)
			)
			(primitives
				(gr_poly
					(pts
						(arc
							(start 0.3048 -0.2032)
							(mid 0.275042 -0.275042)
							(end 0.2032 -0.3048)
						)
						(arc
							(start -0.2032 -0.3048)
							(mid -0.275042 -0.275042)
							(end -0.3048 -0.2032)
						)
						(arc
							(start -0.3048 0.2032)
							(mid -0.275042 0.275042)
							(end -0.2032 0.3048)
						)
						(arc
							(start 0.2032 0.3048)
							(mid 0.275042 0.275042)
							(end 0.3048 0.2032)
						)
					)
					(width 0)
					(fill yes)
				)
			)
		)
		(pad "2" smd custom
			(at 0 0.4445 90)
			(size 0.1524 0.1524)
			(layers "F.Cu" "F.Mask" "F.Paste")
			(net "GND")
			(options
				(clearance outline)
				(anchor circle)
			)
			(primitives
				(gr_poly
					(pts
						(arc
							(start 0.3048 -0.2032)
							(mid 0.275042 -0.275042)
							(end 0.2032 -0.3048)
						)
						(arc
							(start -0.2032 -0.3048)
							(mid -0.275042 -0.275042)
							(end -0.3048 -0.2032)
						)
						(arc
							(start -0.3048 0.2032)
							(mid -0.275042 0.275042)
							(end -0.2032 0.3048)
						)
						(arc
							(start 0.2032 0.3048)
							(mid 0.275042 0.275042)
							(end 0.3048 0.2032)
						)
					)
					(width 0)
					(fill yes)
				)
			)
		)
	)
	(footprint ""
		(layer "F.Cu")
		(at 42.6466 -116.4844)
		(property "Reference" "C321"
			(at 0 0 0)
			(layer "F.SilkS")
			(hide yes)
			(effects
				(font
					(size 1.27 1.27)
				)
			)
		)
		(property "Value" "SC10U25V6KX-1GP"
			(at -0.0762 -5.1308 0)
			(unlocked yes)
			(layer "F.Fab")
			(hide yes)
			(effects
				(font
					(size 1.016 1.016)
					(thickness 0.1524)
				)
			)
		)
		(property "Device Type" "C1206H71"
			(at -0.127 -6.6548 0)
			(unlocked yes)
			(layer "F.Fab")
			(hide yes)
			(effects
				(font
					(size 1.016 1.016)
					(thickness 0.1524)
				)
			)
		)
		(duplicate_pad_numbers_are_jumpers no)
		(fp_line
			(start -1.016 -2.2352)
			(end 1.016 -2.2352)
			(stroke
				(width 0.1524)
				(type default)
			)
			(layer "F.SilkS")
		)
		(fp_line
			(start -1.016 -0.8382)
			(end -1.016 -2.2352)
			(stroke
				(width 0.1524)
				(type default)
			)
			(layer "F.SilkS")
		)
		(fp_line
			(start -1.016 2.2352)
			(end -1.016 0.8382)
			(stroke
				(width 0.1524)
				(type default)
			)
			(layer "F.SilkS")
		)
		(fp_line
			(start 1.016 -2.2352)
			(end 1.016 -0.8382)
			(stroke
				(width 0.1524)
				(type default)
			)
			(layer "F.SilkS")
		)
		(fp_line
			(start 1.016 0.8382)
			(end 1.016 2.2352)
			(stroke
				(width 0.1524)
				(type default)
			)
			(layer "F.SilkS")
		)
		(fp_line
			(start 1.016 2.2352)
			(end -1.016 2.2352)
			(stroke
				(width 0.1524)
				(type default)
			)
			(layer "F.SilkS")
		)
		(fp_rect
			(start -1.0922 2.3114)
			(end 1.0922 -2.3114)
			(stroke
				(width 0)
				(type default)
			)
			(fill no)
			(layer "F.CrtYd")
		)
		(fp_poly
			(pts
				(xy 1.0922 -2.3114) (xy 1.0922 2.3114) (xy -1.0922 2.3114) (xy -1.0922 -2.3114)
			)
			(stroke
				(width 0)
				(type default)
			)
			(fill no)
			(layer "F.Fab")
		)
		(pad "1" smd rect
			(at 0 -1.397)
			(size 1.651 1.27)
			(layers "F.Cu" "F.Mask" "F.Paste")
			(net "P12V_HDD13")
		)
		(pad "2" smd rect
			(at 0 1.397)
			(size 1.651 1.27)
			(layers "F.Cu" "F.Mask" "F.Paste")
			(net "GND")
		)
	)
	(footprint ""
		(layer "F.Cu")
		(at 26.796746 -448.0687 90)
		(property "Reference" "C263"
			(at 0 0 90)
			(layer "F.SilkS")
			(hide yes)
			(effects
				(font
					(size 1.27 1.27)
				)
			)
		)
		(property "Value" "SCD01U50V2KX-1GP"
			(at 1.1811 -2.7051 90)
			(unlocked yes)
			(layer "F.Fab")
			(hide yes)
			(effects
				(font
					(size 1.016 1.016)
					(thickness 0.1524)
				)
			)
		)
		(property "Device Type" "C402H22"
			(at 1.1811 -4.2291 90)
			(unlocked yes)
			(layer "F.Fab")
			(hide yes)
			(effects
				(font
					(size 1.016 1.016)
					(thickness 0.1524)
				)
			)
		)
		(duplicate_pad_numbers_are_jumpers no)
		(fp_rect
			(start -0.4318 0.9525)
			(end 0.4318 -0.9525)
			(stroke
				(width 0)
				(type default)
			)
			(fill no)
			(layer "F.CrtYd")
		)
		(fp_rect
			(start -0.4318 0.9525)
			(end 0.4318 -0.9525)
			(stroke
				(width 0)
				(type default)
			)
			(fill no)
			(layer "F.Fab")
		)
		(pad "1" smd custom
			(at 0 -0.4445 90)
			(size 0.1524 0.1524)
			(layers "F.Cu" "F.Mask" "F.Paste")
			(net "SAS2X28_DRIVE_RX_P_A10")
			(options
				(clearance outline)
				(anchor circle)
			)
			(primitives
				(gr_poly
					(pts
						(arc
							(start 0.3048 -0.2032)
							(mid 0.275042 -0.275042)
							(end 0.2032 -0.3048)
						)
						(arc
							(start -0.2032 -0.3048)
							(mid -0.275042 -0.275042)
							(end -0.3048 -0.2032)
						)
						(arc
							(start -0.3048 0.2032)
							(mid -0.275042 0.275042)
							(end -0.2032 0.3048)
						)
						(arc
							(start 0.2032 0.3048)
							(mid 0.275042 0.275042)
							(end 0.3048 0.2032)
						)
					)
					(width 0)
					(fill yes)
				)
			)
		)
		(pad "2" smd custom
			(at 0 0.4445 90)
			(size 0.1524 0.1524)
			(layers "F.Cu" "F.Mask" "F.Paste")
			(net "SAS2X28_A_HDD10_RX_+")
			(options
				(clearance outline)
				(anchor circle)
			)
			(primitives
				(gr_poly
					(pts
						(arc
							(start 0.3048 -0.2032)
							(mid 0.275042 -0.275042)
							(end 0.2032 -0.3048)
						)
						(arc
							(start -0.2032 -0.3048)
							(mid -0.275042 -0.275042)
							(end -0.3048 -0.2032)
						)
						(arc
							(start -0.3048 0.2032)
							(mid -0.275042 0.275042)
							(end -0.2032 0.3048)
						)
						(arc
							(start 0.2032 0.3048)
							(mid 0.275042 0.275042)
							(end 0.3048 0.2032)
						)
					)
					(width 0)
					(fill yes)
				)
			)
		)
	)
	(footprint ""
		(layer "F.Cu")
		(at 41.401746 -113.185702)
		(property "Reference" "R288"
			(at 0 0 0)
			(layer "F.SilkS")
			(hide yes)
			(effects
				(font
					(size 1.27 1.27)
				)
			)
		)
		(property "Value" "200KR2F-L-GP"
			(at 0.064008 -3.993896 0)
			(unlocked yes)
			(layer "F.Fab")
			(hide yes)
			(effects
				(font
					(size 1.016 1.016)
					(thickness 0.1524)
				)
			)
		)
		(property "Device Type" "R402H16"
			(at 0.064008 -5.517896 0)
			(unlocked yes)
			(layer "F.Fab")
			(hide yes)
			(effects
				(font
					(size 1.016 1.016)
					(thickness 0.1524)
				)
			)
		)
		(duplicate_pad_numbers_are_jumpers no)
		(fp_line
			(start -0.508 -0.9398)
			(end -0.508 0.9398)
			(stroke
				(width 0.1524)
				(type default)
			)
			(layer "F.SilkS")
		)
		(fp_line
			(start 0.508 -0.9398)
			(end -0.508 -0.9398)
			(stroke
				(width 0.1524)
				(type default)
			)
			(layer "F.SilkS")
		)
		(fp_rect
			(start -0.508 0.9398)
			(end 0.508 -0.9398)
			(stroke
				(width 0)
				(type default)
			)
			(fill no)
			(layer "F.CrtYd")
		)
		(fp_rect
			(start -0.508 0.9398)
			(end 0.508 -0.9398)
			(stroke
				(width 0)
				(type default)
			)
			(fill no)
			(layer "F.Fab")
		)
		(pad "1" smd custom
			(at 0 -0.4445)
			(size 0.1397 0.1397)
			(layers "F.Cu" "F.Mask" "F.Paste")
			(net "P12V")
			(options
				(clearance outline)
				(anchor circle)
			)
			(primitives
				(gr_poly
					(pts
						(arc
							(start -0.1778 -0.2794)
							(mid -0.249642 -0.249642)
							(end -0.2794 -0.1778)
						)
						(arc
							(start -0.2794 0.1778)
							(mid -0.249642 0.249642)
							(end -0.1778 0.2794)
						)
						(arc
							(start 0.1778 0.2794)
							(mid 0.249642 0.249642)
							(end 0.2794 0.1778)
						)
						(arc
							(start 0.2794 -0.1778)
							(mid 0.249642 -0.249642)
							(end 0.1778 -0.2794)
						)
					)
					(width 0)
					(fill yes)
				)
			)
		)
		(pad "2" smd custom
			(at 0 0.4445)
			(size 0.1397 0.1397)
			(layers "F.Cu" "F.Mask" "F.Paste")
			(net "SW_HDD13_P")
			(options
				(clearance outline)
				(anchor circle)
			)
			(primitives
				(gr_poly
					(pts
						(arc
							(start -0.1778 -0.2794)
							(mid -0.249642 -0.249642)
							(end -0.2794 -0.1778)
						)
						(arc
							(start -0.2794 0.1778)
							(mid -0.249642 0.249642)
							(end -0.1778 0.2794)
						)
						(arc
							(start 0.1778 0.2794)
							(mid 0.249642 0.249642)
							(end 0.2794 0.1778)
						)
						(arc
							(start 0.2794 -0.1778)
							(mid 0.249642 -0.249642)
							(end 0.1778 -0.2794)
						)
					)
					(width 0)
					(fill yes)
				)
			)
		)
	)
	(footprint ""
		(layer "F.Cu")
		(at 197.230746 -492.5187 -90)
		(property "Reference" "R425"
			(at 0 0 270)
			(layer "F.SilkS")
			(hide yes)
			(effects
				(font
					(size 1.27 1.27)
				)
			)
		)
		(property "Value" "4K7R2J-2-GP"
			(at 0.064008 -3.993896 270)
			(unlocked yes)
			(layer "F.Fab")
			(hide yes)
			(effects
				(font
					(size 1.016 1.016)
					(thickness 0.1524)
				)
			)
		)
		(property "Device Type" "R402H16"
			(at 0.064008 -5.517896 270)
			(unlocked yes)
			(layer "F.Fab")
			(hide yes)
			(effects
				(font
					(size 1.016 1.016)
					(thickness 0.1524)
				)
			)
		)
		(duplicate_pad_numbers_are_jumpers no)
		(fp_line
			(start -0.508 -0.9398)
			(end -0.508 0.9398)
			(stroke
				(width 0.1524)
				(type default)
			)
			(layer "F.SilkS")
		)
		(fp_line
			(start 0.508 -0.9398)
			(end -0.508 -0.9398)
			(stroke
				(width 0.1524)
				(type default)
			)
			(layer "F.SilkS")
		)
		(fp_rect
			(start -0.508 0.9398)
			(end 0.508 -0.9398)
			(stroke
				(width 0)
				(type default)
			)
			(fill no)
			(layer "F.CrtYd")
		)
		(fp_rect
			(start -0.508 0.9398)
			(end 0.508 -0.9398)
			(stroke
				(width 0)
				(type default)
			)
			(fill no)
			(layer "F.Fab")
		)
		(pad "1" smd custom
			(at 0 -0.4445 270)
			(size 0.1397 0.1397)
			(layers "F.Cu" "F.Mask" "F.Paste")
			(net "P3V3")
			(options
				(clearance outline)
				(anchor circle)
			)
			(primitives
				(gr_poly
					(pts
						(arc
							(start -0.1778 -0.2794)
							(mid -0.249642 -0.249642)
							(end -0.2794 -0.1778)
						)
						(arc
							(start -0.2794 0.1778)
							(mid -0.249642 0.249642)
							(end -0.1778 0.2794)
						)
						(arc
							(start 0.1778 0.2794)
							(mid 0.249642 0.249642)
							(end 0.2794 0.1778)
						)
						(arc
							(start 0.2794 -0.1778)
							(mid 0.249642 -0.249642)
							(end 0.1778 -0.2794)
						)
					)
					(width 0)
					(fill yes)
				)
			)
		)
		(pad "2" smd custom
			(at 0 0.4445 270)
			(size 0.1397 0.1397)
			(layers "F.Cu" "F.Mask" "F.Paste")
			(net "SAS_EXP_A_PWR0")
			(options
				(clearance outline)
				(anchor circle)
			)
			(primitives
				(gr_poly
					(pts
						(arc
							(start -0.1778 -0.2794)
							(mid -0.249642 -0.249642)
							(end -0.2794 -0.1778)
						)
						(arc
							(start -0.2794 0.1778)
							(mid -0.249642 0.249642)
							(end -0.1778 0.2794)
						)
						(arc
							(start 0.1778 0.2794)
							(mid 0.249642 0.249642)
							(end 0.2794 0.1778)
						)
						(arc
							(start 0.2794 -0.1778)
							(mid 0.249642 -0.249642)
							(end 0.1778 -0.2794)
						)
					)
					(width 0)
					(fill yes)
				)
			)
		)
	)
	(footprint ""
		(layer "F.Cu")
		(at 236.854746 -27.9527 180)
		(property "Reference" "PR11"
			(at 0 0 180)
			(layer "F.SilkS")
			(hide yes)
			(effects
				(font
					(size 1.27 1.27)
				)
			)
		)
		(property "Value" "73K2R2F-GP"
			(at 0.064008 -3.993896 180)
			(unlocked yes)
			(layer "F.Fab")
			(hide yes)
			(effects
				(font
					(size 1.016 1.016)
					(thickness 0.1524)
				)
			)
		)
		(property "Device Type" "R402H16"
			(at 0.064008 -5.517896 180)
			(unlocked yes)
			(layer "F.Fab")
			(hide yes)
			(effects
				(font
					(size 1.016 1.016)
					(thickness 0.1524)
				)
			)
		)
		(duplicate_pad_numbers_are_jumpers no)
		(fp_line
			(start 0.508 -0.9398)
			(end -0.508 -0.9398)
			(stroke
				(width 0.1524)
				(type default)
			)
			(layer "F.SilkS")
		)
		(fp_line
			(start -0.508 -0.9398)
			(end -0.508 0.9398)
			(stroke
				(width 0.1524)
				(type default)
			)
			(layer "F.SilkS")
		)
		(fp_rect
			(start -0.508 0.9398)
			(end 0.508 -0.9398)
			(stroke
				(width 0)
				(type default)
			)
			(fill no)
			(layer "F.CrtYd")
		)
		(fp_rect
			(start -0.508 0.9398)
			(end 0.508 -0.9398)
			(stroke
				(width 0)
				(type default)
			)
			(fill no)
			(layer "F.Fab")
		)
		(pad "1" smd custom
			(at 0 -0.4445 180)
			(size 0.1397 0.1397)
			(layers "F.Cu" "F.Mask" "F.Paste")
			(net "P5VA_VFB")
			(options
				(clearance outline)
				(anchor circle)
			)
			(primitives
				(gr_poly
					(pts
						(arc
							(start -0.1778 -0.2794)
							(mid -0.249642 -0.249642)
							(end -0.2794 -0.1778)
						)
						(arc
							(start -0.2794 0.1778)
							(mid -0.249642 0.249642)
							(end -0.1778 0.2794)
						)
						(arc
							(start 0.1778 0.2794)
							(mid 0.249642 0.249642)
							(end 0.2794 0.1778)
						)
						(arc
							(start 0.2794 -0.1778)
							(mid 0.249642 -0.249642)
							(end 0.1778 -0.2794)
						)
					)
					(width 0)
					(fill yes)
				)
			)
		)
		(pad "2" smd custom
			(at 0 0.4445 180)
			(size 0.1397 0.1397)
			(layers "F.Cu" "F.Mask" "F.Paste")
			(net "P5VA_VFB_NET")
			(options
				(clearance outline)
				(anchor circle)
			)
			(primitives
				(gr_poly
					(pts
						(arc
							(start -0.1778 -0.2794)
							(mid -0.249642 -0.249642)
							(end -0.2794 -0.1778)
						)
						(arc
							(start -0.2794 0.1778)
							(mid -0.249642 0.249642)
							(end -0.1778 0.2794)
						)
						(arc
							(start 0.1778 0.2794)
							(mid 0.249642 0.249642)
							(end 0.2794 0.1778)
						)
						(arc
							(start 0.2794 -0.1778)
							(mid 0.249642 -0.249642)
							(end 0.1778 -0.2794)
						)
					)
					(width 0)
					(fill yes)
				)
			)
		)
	)
	(footprint ""
		(layer "F.Cu")
		(at 8.381746 -155.3337 -90)
		(property "Reference" "R356"
			(at 0 0 270)
			(layer "F.SilkS")
			(hide yes)
			(effects
				(font
					(size 1.27 1.27)
				)
			)
		)
		(property "Value" "10KR2F-2-GP"
			(at 0.064008 -3.993896 270)
			(unlocked yes)
			(layer "F.Fab")
			(hide yes)
			(effects
				(font
					(size 1.016 1.016)
					(thickness 0.1524)
				)
			)
		)
		(property "Device Type" "R402H16"
			(at 0.064008 -5.517896 270)
			(unlocked yes)
			(layer "F.Fab")
			(hide yes)
			(effects
				(font
					(size 1.016 1.016)
					(thickness 0.1524)
				)
			)
		)
		(duplicate_pad_numbers_are_jumpers no)
		(fp_line
			(start -0.508 -0.9398)
			(end -0.508 0.9398)
			(stroke
				(width 0.1524)
				(type default)
			)
			(layer "F.SilkS")
		)
		(fp_line
			(start 0.508 -0.9398)
			(end -0.508 -0.9398)
			(stroke
				(width 0.1524)
				(type default)
			)
			(layer "F.SilkS")
		)
		(fp_rect
			(start -0.508 0.9398)
			(end 0.508 -0.9398)
			(stroke
				(width 0)
				(type default)
			)
			(fill no)
			(layer "F.CrtYd")
		)
		(fp_rect
			(start -0.508 0.9398)
			(end 0.508 -0.9398)
			(stroke
				(width 0)
				(type default)
			)
			(fill no)
			(layer "F.Fab")
		)
		(pad "1" smd custom
			(at 0 -0.4445 270)
			(size 0.1397 0.1397)
			(layers "F.Cu" "F.Mask" "F.Paste")
			(net "P3V3")
			(options
				(clearance outline)
				(anchor circle)
			)
			(primitives
				(gr_poly
					(pts
						(arc
							(start -0.1778 -0.2794)
							(mid -0.249642 -0.249642)
							(end -0.2794 -0.1778)
						)
						(arc
							(start -0.2794 0.1778)
							(mid -0.249642 0.249642)
							(end -0.1778 0.2794)
						)
						(arc
							(start 0.1778 0.2794)
							(mid 0.249642 0.249642)
							(end 0.2794 0.1778)
						)
						(arc
							(start 0.2794 -0.1778)
							(mid 0.249642 -0.249642)
							(end 0.1778 -0.2794)
						)
					)
					(width 0)
					(fill yes)
				)
			)
		)
		(pad "2" smd custom
			(at 0 0.4445 270)
			(size 0.1397 0.1397)
			(layers "F.Cu" "F.Mask" "F.Paste")
			(net "TEMP_SENSOR_B_ADDR0&ID")
			(options
				(clearance outline)
				(anchor circle)
			)
			(primitives
				(gr_poly
					(pts
						(arc
							(start -0.1778 -0.2794)
							(mid -0.249642 -0.249642)
							(end -0.2794 -0.1778)
						)
						(arc
							(start -0.2794 0.1778)
							(mid -0.249642 0.249642)
							(end -0.1778 0.2794)
						)
						(arc
							(start 0.1778 0.2794)
							(mid 0.249642 0.249642)
							(end 0.2794 0.1778)
						)
						(arc
							(start 0.2794 -0.1778)
							(mid 0.249642 -0.249642)
							(end 0.1778 -0.2794)
						)
					)
					(width 0)
					(fill yes)
				)
			)
		)
	)
	(footprint ""
		(layer "F.Cu")
		(at 33.043368 -476.060516 -90)
		(property "Reference" "C185"
			(at 0 0 270)
			(layer "F.SilkS")
			(hide yes)
			(effects
				(font
					(size 1.27 1.27)
				)
			)
		)
		(property "Value" "SCD01U50V2KX-1GP"
			(at 1.1811 -2.7051 270)
			(unlocked yes)
			(layer "F.Fab")
			(hide yes)
			(effects
				(font
					(size 1.016 1.016)
					(thickness 0.1524)
				)
			)
		)
		(property "Device Type" "C402H22"
			(at 1.1811 -4.2291 270)
			(unlocked yes)
			(layer "F.Fab")
			(hide yes)
			(effects
				(font
					(size 1.016 1.016)
					(thickness 0.1524)
				)
			)
		)
		(duplicate_pad_numbers_are_jumpers no)
		(fp_rect
			(start -0.4318 0.9525)
			(end 0.4318 -0.9525)
			(stroke
				(width 0)
				(type default)
			)
			(fill no)
			(layer "F.CrtYd")
		)
		(fp_rect
			(start -0.4318 0.9525)
			(end 0.4318 -0.9525)
			(stroke
				(width 0)
				(type default)
			)
			(fill no)
			(layer "F.Fab")
		)
		(pad "1" smd custom
			(at 0 -0.4445 270)
			(size 0.1524 0.1524)
			(layers "F.Cu" "F.Mask" "F.Paste")
			(net "SAS2X28_DRIVE_RX_P_B5")
			(options
				(clearance outline)
				(anchor circle)
			)
			(primitives
				(gr_poly
					(pts
						(arc
							(start 0.3048 -0.2032)
							(mid 0.275042 -0.275042)
							(end 0.2032 -0.3048)
						)
						(arc
							(start -0.2032 -0.3048)
							(mid -0.275042 -0.275042)
							(end -0.3048 -0.2032)
						)
						(arc
							(start -0.3048 0.2032)
							(mid -0.275042 0.275042)
							(end -0.2032 0.3048)
						)
						(arc
							(start 0.2032 0.3048)
							(mid 0.275042 0.275042)
							(end 0.3048 0.2032)
						)
					)
					(width 0)
					(fill yes)
				)
			)
		)
		(pad "2" smd custom
			(at 0 0.4445 270)
			(size 0.1524 0.1524)
			(layers "F.Cu" "F.Mask" "F.Paste")
			(net "SAS2X28_B_HDD5_RX_+")
			(options
				(clearance outline)
				(anchor circle)
			)
			(primitives
				(gr_poly
					(pts
						(arc
							(start 0.3048 -0.2032)
							(mid 0.275042 -0.275042)
							(end 0.2032 -0.3048)
						)
						(arc
							(start -0.2032 -0.3048)
							(mid -0.275042 -0.275042)
							(end -0.3048 -0.2032)
						)
						(arc
							(start -0.3048 0.2032)
							(mid -0.275042 0.275042)
							(end -0.2032 0.3048)
						)
						(arc
							(start 0.2032 0.3048)
							(mid 0.275042 0.275042)
							(end 0.3048 0.2032)
						)
					)
					(width 0)
					(fill yes)
				)
			)
		)
	)
	(footprint ""
		(layer "F.Cu")
		(at 206.882746 -459.4987 -90)
		(property "Reference" "TP3"
			(at 0 0 270)
			(layer "F.SilkS")
			(hide yes)
			(effects
				(font
					(size 1.27 1.27)
				)
			)
		)
		(property "Value" "TPAD32-GP"
			(at 0 -3.166364 270)
			(unlocked yes)
			(layer "F.Fab")
			(hide yes)
			(effects
				(font
					(size 1.016 1.016)
					(thickness 0.1524)
				)
			)
		)
		(property "Device Type" "TPAD32"
			(at 0 -4.690618 270)
			(unlocked yes)
			(layer "F.Fab")
			(hide yes)
			(effects
				(font
					(size 1.016 1.016)
					(thickness 0.1524)
				)
			)
		)
		(duplicate_pad_numbers_are_jumpers no)
		(fp_poly
			(pts
				(arc
					(start 0 -0.4064)
					(mid 0 0.4064)
					(end 0 -0.4064)
				)
			)
			(stroke
				(width 0)
				(type default)
			)
			(fill no)
			(layer "F.CrtYd")
		)
		(fp_poly
			(pts
				(arc
					(start 0 -0.7112)
					(mid 0 0.7112)
					(end 0 -0.7112)
				)
			)
			(stroke
				(width 0)
				(type default)
			)
			(fill no)
			(layer "F.Fab")
		)
		(pad "1" smd circle
			(at 0 0 270)
			(size 0.8128 0.8128)
			(layers "F.Cu" "F.Mask" "F.Paste")
			(net "I2C_B_TMP3_ALERT")
		)
	)
	(footprint ""
		(layer "F.Cu")
		(at 58.6486 -172.72 180)
		(property "Reference" "Q63"
			(at 0 0 180)
			(layer "F.SilkS")
			(hide yes)
			(effects
				(font
					(size 1.27 1.27)
				)
			)
		)
		(property "Value" "2N7002-11-GP"
			(at 0.127 -8.9662 180)
			(unlocked yes)
			(layer "F.Fab")
			(hide yes)
			(effects
				(font
					(size 1.016 1.016)
					(thickness 0.1524)
				)
			)
		)
		(property "Device Type" "SOT23DGS2D4H44"
			(at 0.127 -10.4902 180)
			(unlocked yes)
			(layer "F.Fab")
			(hide yes)
			(effects
				(font
					(size 1.016 1.016)
					(thickness 0.1524)
				)
			)
		)
		(duplicate_pad_numbers_are_jumpers no)
		(fp_line
			(start 1.651 1.778)
			(end 1.651 -1.778)
			(stroke
				(width 0.1524)
				(type default)
			)
			(layer "F.SilkS")
		)
		(fp_line
			(start 1.651 -1.778)
			(end -1.651 -1.778)
			(stroke
				(width 0.1524)
				(type default)
			)
			(layer "F.SilkS")
		)
		(fp_line
			(start -1.651 1.778)
			(end 1.651 1.778)
			(stroke
				(width 0.1524)
				(type default)
			)
			(layer "F.SilkS")
		)
		(fp_line
			(start -1.651 -1.778)
			(end -1.651 1.778)
			(stroke
				(width 0.1524)
				(type default)
			)
			(layer "F.SilkS")
		)
		(fp_poly
			(pts
				(xy -1.778 1.8796) (xy -1.778 -1.8796) (xy 1.778 -1.8796) (xy 1.778 1.8796)
			)
			(stroke
				(width 0)
				(type default)
			)
			(fill no)
			(layer "F.CrtYd")
		)
		(fp_poly
			(pts
				(xy -1.778 1.8796) (xy -1.778 -1.8796) (xy 1.778 -1.8796) (xy 1.778 1.8796)
			)
			(stroke
				(width 0)
				(type default)
			)
			(fill no)
			(layer "F.Fab")
		)
		(pad "D" smd custom
			(at 0 -0.9525 180)
			(size 0.1905 0.1905)
			(layers "F.Cu" "F.Mask" "F.Paste")
			(net "HDD8_LED_G")
			(options
				(clearance outline)
				(anchor circle)
			)
			(primitives
				(gr_poly
					(pts
						(arc
							(start -0.1778 0.5715)
							(mid -0.321484 0.511984)
							(end -0.381 0.3683)
						)
						(arc
							(start -0.381 -0.3683)
							(mid -0.321484 -0.511984)
							(end -0.1778 -0.5715)
						)
						(arc
							(start 0.1778 -0.5715)
							(mid 0.321484 -0.511984)
							(end 0.381 -0.3683)
						)
						(arc
							(start 0.381 0.3683)
							(mid 0.321484 0.511984)
							(end 0.1778 0.5715)
						)
					)
					(width 0)
					(fill yes)
				)
			)
		)
		(pad "G" smd custom
			(at -0.98425 0.9525 180)
			(size 0.1905 0.1905)
			(layers "F.Cu" "F.Mask" "F.Paste")
			(net "HDD8_LED_B")
			(options
				(clearance outline)
				(anchor circle)
			)
			(primitives
				(gr_poly
					(pts
						(arc
							(start -0.1778 0.5715)
							(mid -0.321484 0.511984)
							(end -0.381 0.3683)
						)
						(arc
							(start -0.381 -0.3683)
							(mid -0.321484 -0.511984)
							(end -0.1778 -0.5715)
						)
						(arc
							(start 0.1778 -0.5715)
							(mid 0.321484 -0.511984)
							(end 0.381 -0.3683)
						)
						(arc
							(start 0.381 0.3683)
							(mid 0.321484 0.511984)
							(end 0.1778 0.5715)
						)
					)
					(width 0)
					(fill yes)
				)
			)
		)
		(pad "S" smd custom
			(at 0.98425 0.9525 180)
			(size 0.1905 0.1905)
			(layers "F.Cu" "F.Mask" "F.Paste")
			(net "GND")
			(options
				(clearance outline)
				(anchor circle)
			)
			(primitives
				(gr_poly
					(pts
						(arc
							(start -0.1778 0.5715)
							(mid -0.321484 0.511984)
							(end -0.381 0.3683)
						)
						(arc
							(start -0.381 -0.3683)
							(mid -0.321484 -0.511984)
							(end -0.1778 -0.5715)
						)
						(arc
							(start 0.1778 -0.5715)
							(mid 0.321484 -0.511984)
							(end 0.381 -0.3683)
						)
						(arc
							(start 0.381 0.3683)
							(mid 0.321484 0.511984)
							(end 0.1778 0.5715)
						)
					)
					(width 0)
					(fill yes)
				)
			)
		)
	)
	(footprint ""
		(layer "F.Cu")
		(at 224.747582 -246.860568 90)
		(property "Reference" "R131"
			(at 0 0 90)
			(layer "F.SilkS")
			(hide yes)
			(effects
				(font
					(size 1.27 1.27)
				)
			)
		)
		(property "Value" "330R2F-GP"
			(at 0.064008 -3.993896 90)
			(unlocked yes)
			(layer "F.Fab")
			(hide yes)
			(effects
				(font
					(size 1.016 1.016)
					(thickness 0.1524)
				)
			)
		)
		(property "Device Type" "R402H16"
			(at 0.064008 -5.517896 90)
			(unlocked yes)
			(layer "F.Fab")
			(hide yes)
			(effects
				(font
					(size 1.016 1.016)
					(thickness 0.1524)
				)
			)
		)
		(duplicate_pad_numbers_are_jumpers no)
		(fp_line
			(start 0.508 -0.9398)
			(end -0.508 -0.9398)
			(stroke
				(width 0.1524)
				(type default)
			)
			(layer "F.SilkS")
		)
		(fp_line
			(start -0.508 -0.9398)
			(end -0.508 0.9398)
			(stroke
				(width 0.1524)
				(type default)
			)
			(layer "F.SilkS")
		)
		(fp_rect
			(start -0.508 0.9398)
			(end 0.508 -0.9398)
			(stroke
				(width 0)
				(type default)
			)
			(fill no)
			(layer "F.CrtYd")
		)
		(fp_rect
			(start -0.508 0.9398)
			(end 0.508 -0.9398)
			(stroke
				(width 0)
				(type default)
			)
			(fill no)
			(layer "F.Fab")
		)
		(pad "1" smd custom
			(at 0 -0.4445 90)
			(size 0.1397 0.1397)
			(layers "F.Cu" "F.Mask" "F.Paste")
			(net "P3V3_HDD2_LED")
			(options
				(clearance outline)
				(anchor circle)
			)
			(primitives
				(gr_poly
					(pts
						(arc
							(start -0.1778 -0.2794)
							(mid -0.249642 -0.249642)
							(end -0.2794 -0.1778)
						)
						(arc
							(start -0.2794 0.1778)
							(mid -0.249642 0.249642)
							(end -0.1778 0.2794)
						)
						(arc
							(start 0.1778 0.2794)
							(mid 0.249642 0.249642)
							(end 0.2794 0.1778)
						)
						(arc
							(start 0.2794 -0.1778)
							(mid 0.249642 -0.249642)
							(end 0.1778 -0.2794)
						)
					)
					(width 0)
					(fill yes)
				)
			)
		)
		(pad "2" smd custom
			(at 0 0.4445 90)
			(size 0.1397 0.1397)
			(layers "F.Cu" "F.Mask" "F.Paste")
			(net "FLT_HDD2")
			(options
				(clearance outline)
				(anchor circle)
			)
			(primitives
				(gr_poly
					(pts
						(arc
							(start -0.1778 -0.2794)
							(mid -0.249642 -0.249642)
							(end -0.2794 -0.1778)
						)
						(arc
							(start -0.2794 0.1778)
							(mid -0.249642 0.249642)
							(end -0.1778 0.2794)
						)
						(arc
							(start 0.1778 0.2794)
							(mid 0.249642 0.249642)
							(end 0.2794 0.1778)
						)
						(arc
							(start 0.2794 -0.1778)
							(mid 0.249642 -0.249642)
							(end 0.1778 -0.2794)
						)
					)
					(width 0)
					(fill yes)
				)
			)
		)
	)
	(footprint ""
		(layer "F.Cu")
		(at 78.994 -192.151)
		(property "Reference" "C372"
			(at 0 0 0)
			(layer "F.SilkS")
			(hide yes)
			(effects
				(font
					(size 1.27 1.27)
				)
			)
		)
		(property "Value" "SCD033U25V2KX-GP"
			(at 1.1811 -2.7051 0)
			(unlocked yes)
			(layer "F.Fab")
			(hide yes)
			(effects
				(font
					(size 1.016 1.016)
					(thickness 0.1524)
				)
			)
		)
		(property "Device Type" "C402H22"
			(at 1.1811 -4.2291 0)
			(unlocked yes)
			(layer "F.Fab")
			(hide yes)
			(effects
				(font
					(size 1.016 1.016)
					(thickness 0.1524)
				)
			)
		)
		(duplicate_pad_numbers_are_jumpers no)
		(fp_rect
			(start -0.4318 0.9525)
			(end 0.4318 -0.9525)
			(stroke
				(width 0)
				(type default)
			)
			(fill no)
			(layer "F.CrtYd")
		)
		(fp_rect
			(start -0.4318 0.9525)
			(end 0.4318 -0.9525)
			(stroke
				(width 0)
				(type default)
			)
			(fill no)
			(layer "F.Fab")
		)
		(pad "1" smd custom
			(at 0 -0.4445)
			(size 0.1524 0.1524)
			(layers "F.Cu" "F.Mask" "F.Paste")
			(net "SW_HDD8_P")
			(options
				(clearance outline)
				(anchor circle)
			)
			(primitives
				(gr_poly
					(pts
						(arc
							(start 0.3048 -0.2032)
							(mid 0.275042 -0.275042)
							(end 0.2032 -0.3048)
						)
						(arc
							(start -0.2032 -0.3048)
							(mid -0.275042 -0.275042)
							(end -0.3048 -0.2032)
						)
						(arc
							(start -0.3048 0.2032)
							(mid -0.275042 0.275042)
							(end -0.2032 0.3048)
						)
						(arc
							(start 0.2032 0.3048)
							(mid 0.275042 0.275042)
							(end 0.3048 0.2032)
						)
					)
					(width 0)
					(fill yes)
				)
			)
		)
		(pad "2" smd custom
			(at 0 0.4445)
			(size 0.1524 0.1524)
			(layers "F.Cu" "F.Mask" "F.Paste")
			(net "GND")
			(options
				(clearance outline)
				(anchor circle)
			)
			(primitives
				(gr_poly
					(pts
						(arc
							(start 0.3048 -0.2032)
							(mid 0.275042 -0.275042)
							(end 0.2032 -0.3048)
						)
						(arc
							(start -0.2032 -0.3048)
							(mid -0.275042 -0.275042)
							(end -0.3048 -0.2032)
						)
						(arc
							(start -0.3048 0.2032)
							(mid -0.275042 0.275042)
							(end -0.2032 0.3048)
						)
						(arc
							(start 0.2032 0.3048)
							(mid 0.275042 0.275042)
							(end 0.3048 0.2032)
						)
					)
					(width 0)
					(fill yes)
				)
			)
		)
	)
	(footprint ""
		(layer "F.Cu")
		(at 62.610492 -82.451956)
		(property "Reference" "C255"
			(at 0 0 0)
			(layer "F.SilkS")
			(hide yes)
			(effects
				(font
					(size 1.27 1.27)
				)
			)
		)
		(property "Value" "SC10U25V6KX-1GP"
			(at -0.0762 -5.1308 0)
			(unlocked yes)
			(layer "F.Fab")
			(hide yes)
			(effects
				(font
					(size 1.016 1.016)
					(thickness 0.1524)
				)
			)
		)
		(property "Device Type" "C1206H71"
			(at -0.127 -6.6548 0)
			(unlocked yes)
			(layer "F.Fab")
			(hide yes)
			(effects
				(font
					(size 1.016 1.016)
					(thickness 0.1524)
				)
			)
		)
		(duplicate_pad_numbers_are_jumpers no)
		(fp_line
			(start -1.016 -2.2352)
			(end 1.016 -2.2352)
			(stroke
				(width 0.1524)
				(type default)
			)
			(layer "F.SilkS")
		)
		(fp_line
			(start -1.016 -0.8382)
			(end -1.016 -2.2352)
			(stroke
				(width 0.1524)
				(type default)
			)
			(layer "F.SilkS")
		)
		(fp_line
			(start -1.016 2.2352)
			(end -1.016 0.8382)
			(stroke
				(width 0.1524)
				(type default)
			)
			(layer "F.SilkS")
		)
		(fp_line
			(start 1.016 -2.2352)
			(end 1.016 -0.8382)
			(stroke
				(width 0.1524)
				(type default)
			)
			(layer "F.SilkS")
		)
		(fp_line
			(start 1.016 0.8382)
			(end 1.016 2.2352)
			(stroke
				(width 0.1524)
				(type default)
			)
			(layer "F.SilkS")
		)
		(fp_line
			(start 1.016 2.2352)
			(end -1.016 2.2352)
			(stroke
				(width 0.1524)
				(type default)
			)
			(layer "F.SilkS")
		)
		(fp_rect
			(start -1.0922 2.3114)
			(end 1.0922 -2.3114)
			(stroke
				(width 0)
				(type default)
			)
			(fill no)
			(layer "F.CrtYd")
		)
		(fp_poly
			(pts
				(xy 1.0922 -2.3114) (xy 1.0922 2.3114) (xy -1.0922 2.3114) (xy -1.0922 -2.3114)
			)
			(stroke
				(width 0)
				(type default)
			)
			(fill no)
			(layer "F.Fab")
		)
		(pad "1" smd rect
			(at 0 -1.397)
			(size 1.651 1.27)
			(layers "F.Cu" "F.Mask" "F.Paste")
			(net "P12V_HDD9")
		)
		(pad "2" smd rect
			(at 0 1.397)
			(size 1.651 1.27)
			(layers "F.Cu" "F.Mask" "F.Paste")
			(net "GND")
		)
	)
	(footprint ""
		(layer "F.Cu")
		(at 31.190946 -376.8217)
		(property "Reference" "C340"
			(at 0 0 0)
			(layer "F.SilkS")
			(hide yes)
			(effects
				(font
					(size 1.27 1.27)
				)
			)
		)
		(property "Value" "SCD1U10V2KX-5GP"
			(at 1.1811 -2.7051 0)
			(unlocked yes)
			(layer "F.Fab")
			(hide yes)
			(effects
				(font
					(size 1.016 1.016)
					(thickness 0.1524)
				)
			)
		)
		(property "Device Type" "C402H22"
			(at 1.1811 -4.2291 0)
			(unlocked yes)
			(layer "F.Fab")
			(hide yes)
			(effects
				(font
					(size 1.016 1.016)
					(thickness 0.1524)
				)
			)
		)
		(duplicate_pad_numbers_are_jumpers no)
		(fp_rect
			(start -0.4318 0.9525)
			(end 0.4318 -0.9525)
			(stroke
				(width 0)
				(type default)
			)
			(fill no)
			(layer "F.CrtYd")
		)
		(fp_rect
			(start -0.4318 0.9525)
			(end 0.4318 -0.9525)
			(stroke
				(width 0)
				(type default)
			)
			(fill no)
			(layer "F.Fab")
		)
		(pad "1" smd custom
			(at 0 -0.4445)
			(size 0.1524 0.1524)
			(layers "F.Cu" "F.Mask" "F.Paste")
			(net "P3V3")
			(options
				(clearance outline)
				(anchor circle)
			)
			(primitives
				(gr_poly
					(pts
						(arc
							(start 0.3048 -0.2032)
							(mid 0.275042 -0.275042)
							(end 0.2032 -0.3048)
						)
						(arc
							(start -0.2032 -0.3048)
							(mid -0.275042 -0.275042)
							(end -0.3048 -0.2032)
						)
						(arc
							(start -0.3048 0.2032)
							(mid -0.275042 0.275042)
							(end -0.2032 0.3048)
						)
						(arc
							(start 0.2032 0.3048)
							(mid 0.275042 0.275042)
							(end 0.3048 0.2032)
						)
					)
					(width 0)
					(fill yes)
				)
			)
		)
		(pad "2" smd custom
			(at 0 0.4445)
			(size 0.1524 0.1524)
			(layers "F.Cu" "F.Mask" "F.Paste")
			(net "GND")
			(options
				(clearance outline)
				(anchor circle)
			)
			(primitives
				(gr_poly
					(pts
						(arc
							(start 0.3048 -0.2032)
							(mid 0.275042 -0.275042)
							(end 0.2032 -0.3048)
						)
						(arc
							(start -0.2032 -0.3048)
							(mid -0.275042 -0.275042)
							(end -0.3048 -0.2032)
						)
						(arc
							(start -0.3048 0.2032)
							(mid -0.275042 0.275042)
							(end -0.2032 0.3048)
						)
						(arc
							(start 0.2032 0.3048)
							(mid 0.275042 0.275042)
							(end 0.3048 0.2032)
						)
					)
					(width 0)
					(fill yes)
				)
			)
		)
	)
	(footprint ""
		(layer "F.Cu")
		(at 82.225134 -494.514886 -90)
		(property "Reference" "U18"
			(at 0 0 270)
			(layer "F.SilkS")
			(hide yes)
			(effects
				(font
					(size 1.27 1.27)
				)
			)
		)
		(property "Value" "74LVC1G08GW-1-GP"
			(at -2.3368 -8.6868 270)
			(unlocked yes)
			(layer "F.Fab")
			(hide yes)
			(effects
				(font
					(size 1.016 1.016)
					(thickness 0.1524)
				)
			)
		)
		(property "Device Type" "SC70-5H44"
			(at -2.3114 -10.414 270)
			(unlocked yes)
			(layer "F.Fab")
			(hide yes)
			(effects
				(font
					(size 1.016 1.016)
					(thickness 0.1524)
				)
			)
		)
		(duplicate_pad_numbers_are_jumpers no)
		(fp_line
			(start -1.27 1.7018)
			(end -1.27 -1.7018)
			(stroke
				(width 0.1524)
				(type default)
			)
			(layer "F.SilkS")
		)
		(fp_line
			(start 1.27 1.7018)
			(end -1.27 1.7018)
			(stroke
				(width 0.1524)
				(type default)
			)
			(layer "F.SilkS")
		)
		(fp_line
			(start -1.27 -1.7018)
			(end 1.27 -1.7018)
			(stroke
				(width 0.1524)
				(type default)
			)
			(layer "F.SilkS")
		)
		(fp_line
			(start 1.27 -1.7018)
			(end 1.27 1.7018)
			(stroke
				(width 0.1524)
				(type default)
			)
			(layer "F.SilkS")
		)
		(fp_line
			(start 0.6604 -1.8034)
			(end 1.3843 -1.8034)
			(stroke
				(width 0.3302)
				(type default)
			)
			(layer "F.SilkS")
		)
		(fp_line
			(start 1.3843 -1.8034)
			(end 1.3843 -1.1176)
			(stroke
				(width 0.3302)
				(type default)
			)
			(layer "F.SilkS")
		)
		(fp_rect
			(start -1.524 1.9558)
			(end 1.524 -1.9558)
			(stroke
				(width 0)
				(type default)
			)
			(fill no)
			(layer "F.CrtYd")
		)
		(fp_poly
			(pts
				(xy -1.524 -1.9558) (xy 1.524 -1.9558) (xy 1.524 1.9558) (xy -1.524 1.9558)
			)
			(stroke
				(width 0)
				(type default)
			)
			(fill no)
			(layer "F.Fab")
		)
		(pad "1" smd rect
			(at 0.65024 -0.8255 270)
			(size 0.4064 1.2192)
			(layers "F.Cu" "F.Mask" "F.Paste")
			(net "SAS_EXP_B_PWR5")
		)
		(pad "2" smd rect
			(at 0 -0.8255 270)
			(size 0.4064 1.2192)
			(layers "F.Cu" "F.Mask" "F.Paste")
			(net "SAS_EXP_A_PWR5")
		)
		(pad "3" smd rect
			(at -0.65024 -0.8255 270)
			(size 0.4064 1.2192)
			(layers "F.Cu" "F.Mask" "F.Paste")
			(net "GND")
		)
		(pad "4" smd rect
			(at -0.65024 0.8255 270)
			(size 0.4064 1.2192)
			(layers "F.Cu" "F.Mask" "F.Paste")
			(net "DRIVE_PWR5")
		)
		(pad "5" smd rect
			(at 0.65024 0.8255 270)
			(size 0.4064 1.2192)
			(layers "F.Cu" "F.Mask" "F.Paste")
			(net "P3V3")
		)
	)
	(footprint ""
		(layer "F.Cu")
		(at 50.545746 -133.124702)
		(property "Reference" "Q27"
			(at 0 0 0)
			(layer "F.SilkS")
			(hide yes)
			(effects
				(font
					(size 1.27 1.27)
				)
			)
		)
		(property "Value" "AO4406AL-GP"
			(at -3.707384 -1.5367 0)
			(unlocked yes)
			(layer "F.Fab")
			(hide yes)
			(effects
				(font
					(size 1.016 1.016)
					(thickness 0.1524)
				)
			)
		)
		(property "Device Type" "SOIC8H69"
			(at -3.707384 -3.0607 0)
			(unlocked yes)
			(layer "F.Fab")
			(hide yes)
			(effects
				(font
					(size 1.016 1.016)
					(thickness 0.1524)
				)
			)
		)
		(duplicate_pad_numbers_are_jumpers no)
		(fp_line
			(start -2.7432 -1.4224)
			(end -2.7432 1.4224)
			(stroke
				(width 0.1524)
				(type default)
			)
			(layer "F.SilkS")
		)
		(fp_line
			(start -2.7432 1.4224)
			(end -2.6416 1.4224)
			(stroke
				(width 0.1524)
				(type default)
			)
			(layer "F.SilkS")
		)
		(fp_line
			(start -2.7432 1.4224)
			(end 2.1336 1.4224)
			(stroke
				(width 0.1524)
				(type default)
			)
			(layer "F.SilkS")
		)
		(fp_line
			(start -2.7178 -0.508)
			(end -2.1844 -0.0508)
			(stroke
				(width 0.1524)
				(type default)
			)
			(layer "F.SilkS")
		)
		(fp_line
			(start -2.6289 3.4417)
			(end -2.6289 1.4732)
			(stroke
				(width 0.381)
				(type default)
			)
			(layer "F.SilkS")
		)
		(fp_line
			(start -2.1844 -0.0508)
			(end -2.7178 0.508)
			(stroke
				(width 0.1524)
				(type default)
			)
			(layer "F.SilkS")
		)
		(fp_line
			(start 2.1336 -1.4224)
			(end -2.7432 -1.4224)
			(stroke
				(width 0.1524)
				(type default)
			)
			(layer "F.SilkS")
		)
		(fp_line
			(start 2.1336 1.4224)
			(end 2.1336 -1.4224)
			(stroke
				(width 0.1524)
				(type default)
			)
			(layer "F.SilkS")
		)
		(fp_poly
			(pts
				(xy -2.2098 -1.4224) (xy -2.2098 1.4224) (xy 2.2098 1.4224) (xy 2.2098 -1.4224)
			)
			(stroke
				(width 0)
				(type default)
			)
			(fill yes)
			(layer "F.SilkS")
		)
		(fp_rect
			(start -2.450084 2.999994)
			(end 2.450084 -2.999994)
			(stroke
				(width 0)
				(type default)
			)
			(fill no)
			(layer "F.CrtYd")
		)
		(fp_poly
			(pts
				(xy -2.8194 3.6322) (xy -2.8194 -3.6322) (xy 2.8194 -3.6322) (xy 2.8194 1.18364) (xy 2.450084 1.18364)
				(xy 2.450084 -2.999994) (xy -2.450084 -2.999994) (xy -2.450084 2.999994) (xy 2.450084 2.999994)
				(xy 2.450084 1.18618) (xy 2.8194 1.18618) (xy 2.8194 3.6322)
			)
			(stroke
				(width 0)
				(type default)
			)
			(fill no)
			(layer "F.CrtYd")
		)
		(fp_rect
			(start -2.8194 3.6322)
			(end 2.8194 -3.6322)
			(stroke
				(width 0)
				(type default)
			)
			(fill no)
			(layer "F.Fab")
		)
		(pad "1" smd rect
			(at -1.905 2.54)
			(size 0.635 1.651)
			(layers "F.Cu" "F.Mask" "F.Paste")
			(net "P5V_HDD13")
		)
		(pad "2" smd rect
			(at -0.635 2.54)
			(size 0.635 1.651)
			(layers "F.Cu" "F.Mask" "F.Paste")
			(net "P5V_HDD13")
		)
		(pad "3" smd rect
			(at 0.635 2.54)
			(size 0.635 1.651)
			(layers "F.Cu" "F.Mask" "F.Paste")
			(net "P5V_HDD13")
		)
		(pad "4" smd rect
			(at 1.905 2.54)
			(size 0.635 1.651)
			(layers "F.Cu" "F.Mask" "F.Paste")
			(net "SW_HDD13_P")
		)
		(pad "5" smd rect
			(at 1.905 -2.54)
			(size 0.635 1.651)
			(layers "F.Cu" "F.Mask" "F.Paste")
			(net "P5VC")
		)
		(pad "6" smd rect
			(at 0.635 -2.54)
			(size 0.635 1.651)
			(layers "F.Cu" "F.Mask" "F.Paste")
			(net "P5VC")
		)
		(pad "7" smd rect
			(at -0.635 -2.54)
			(size 0.635 1.651)
			(layers "F.Cu" "F.Mask" "F.Paste")
			(net "P5VC")
		)
		(pad "8" smd rect
			(at -1.905 -2.54)
			(size 0.635 1.651)
			(layers "F.Cu" "F.Mask" "F.Paste")
			(net "P5VC")
		)
	)
	(footprint ""
		(layer "F.Cu")
		(at 188.988446 -458.377036)
		(property "Reference" "R349"
			(at 0 0 0)
			(layer "F.SilkS")
			(hide yes)
			(effects
				(font
					(size 1.27 1.27)
				)
			)
		)
		(property "Value" "4K7R2J-2-GP"
			(at 0.064008 -3.993896 0)
			(unlocked yes)
			(layer "F.Fab")
			(hide yes)
			(effects
				(font
					(size 1.016 1.016)
					(thickness 0.1524)
				)
			)
		)
		(property "Device Type" "R402H16"
			(at 0.064008 -5.517896 0)
			(unlocked yes)
			(layer "F.Fab")
			(hide yes)
			(effects
				(font
					(size 1.016 1.016)
					(thickness 0.1524)
				)
			)
		)
		(duplicate_pad_numbers_are_jumpers no)
		(fp_line
			(start -0.508 -0.9398)
			(end -0.508 0.9398)
			(stroke
				(width 0.1524)
				(type default)
			)
			(layer "F.SilkS")
		)
		(fp_line
			(start 0.508 -0.9398)
			(end -0.508 -0.9398)
			(stroke
				(width 0.1524)
				(type default)
			)
			(layer "F.SilkS")
		)
		(fp_rect
			(start -0.508 0.9398)
			(end 0.508 -0.9398)
			(stroke
				(width 0)
				(type default)
			)
			(fill no)
			(layer "F.CrtYd")
		)
		(fp_rect
			(start -0.508 0.9398)
			(end 0.508 -0.9398)
			(stroke
				(width 0)
				(type default)
			)
			(fill no)
			(layer "F.Fab")
		)
		(pad "1" smd custom
			(at 0 -0.4445)
			(size 0.1397 0.1397)
			(layers "F.Cu" "F.Mask" "F.Paste")
			(net "EEPROM_A1")
			(options
				(clearance outline)
				(anchor circle)
			)
			(primitives
				(gr_poly
					(pts
						(arc
							(start -0.1778 -0.2794)
							(mid -0.249642 -0.249642)
							(end -0.2794 -0.1778)
						)
						(arc
							(start -0.2794 0.1778)
							(mid -0.249642 0.249642)
							(end -0.1778 0.2794)
						)
						(arc
							(start 0.1778 0.2794)
							(mid 0.249642 0.249642)
							(end 0.2794 0.1778)
						)
						(arc
							(start 0.2794 -0.1778)
							(mid 0.249642 -0.249642)
							(end 0.1778 -0.2794)
						)
					)
					(width 0)
					(fill yes)
				)
			)
		)
		(pad "2" smd custom
			(at 0 0.4445)
			(size 0.1397 0.1397)
			(layers "F.Cu" "F.Mask" "F.Paste")
			(net "GND")
			(options
				(clearance outline)
				(anchor circle)
			)
			(primitives
				(gr_poly
					(pts
						(arc
							(start -0.1778 -0.2794)
							(mid -0.249642 -0.249642)
							(end -0.2794 -0.1778)
						)
						(arc
							(start -0.2794 0.1778)
							(mid -0.249642 0.249642)
							(end -0.1778 0.2794)
						)
						(arc
							(start 0.1778 0.2794)
							(mid 0.249642 0.249642)
							(end 0.2794 0.1778)
						)
						(arc
							(start 0.2794 -0.1778)
							(mid 0.249642 -0.249642)
							(end 0.1778 -0.2794)
						)
					)
					(width 0)
					(fill yes)
				)
			)
		)
	)
	(footprint ""
		(layer "F.Cu")
		(at 229.996746 -31.6357 90)
		(property "Reference" "PC8"
			(at 0 0 90)
			(layer "F.SilkS")
			(hide yes)
			(effects
				(font
					(size 1.27 1.27)
				)
			)
		)
		(property "Value" "SCD1U25V2KX-GP"
			(at 1.1811 -2.7051 90)
			(unlocked yes)
			(layer "F.Fab")
			(hide yes)
			(effects
				(font
					(size 1.016 1.016)
					(thickness 0.1524)
				)
			)
		)
		(property "Device Type" "C402H22"
			(at 1.1811 -4.2291 90)
			(unlocked yes)
			(layer "F.Fab")
			(hide yes)
			(effects
				(font
					(size 1.016 1.016)
					(thickness 0.1524)
				)
			)
		)
		(duplicate_pad_numbers_are_jumpers no)
		(fp_rect
			(start -0.4318 0.9525)
			(end 0.4318 -0.9525)
			(stroke
				(width 0)
				(type default)
			)
			(fill no)
			(layer "F.CrtYd")
		)
		(fp_rect
			(start -0.4318 0.9525)
			(end 0.4318 -0.9525)
			(stroke
				(width 0)
				(type default)
			)
			(fill no)
			(layer "F.Fab")
		)
		(pad "1" smd custom
			(at 0 -0.4445 90)
			(size 0.1524 0.1524)
			(layers "F.Cu" "F.Mask" "F.Paste")
			(net "P5VA")
			(options
				(clearance outline)
				(anchor circle)
			)
			(primitives
				(gr_poly
					(pts
						(arc
							(start 0.3048 -0.2032)
							(mid 0.275042 -0.275042)
							(end 0.2032 -0.3048)
						)
						(arc
							(start -0.2032 -0.3048)
							(mid -0.275042 -0.275042)
							(end -0.3048 -0.2032)
						)
						(arc
							(start -0.3048 0.2032)
							(mid -0.275042 0.275042)
							(end -0.2032 0.3048)
						)
						(arc
							(start 0.2032 0.3048)
							(mid 0.275042 0.275042)
							(end 0.3048 0.2032)
						)
					)
					(width 0)
					(fill yes)
				)
			)
		)
		(pad "2" smd custom
			(at 0 0.4445 90)
			(size 0.1524 0.1524)
			(layers "F.Cu" "F.Mask" "F.Paste")
			(net "P5VA_LL_NET")
			(options
				(clearance outline)
				(anchor circle)
			)
			(primitives
				(gr_poly
					(pts
						(arc
							(start 0.3048 -0.2032)
							(mid 0.275042 -0.275042)
							(end 0.2032 -0.3048)
						)
						(arc
							(start -0.2032 -0.3048)
							(mid -0.275042 -0.275042)
							(end -0.3048 -0.2032)
						)
						(arc
							(start -0.3048 0.2032)
							(mid -0.275042 0.275042)
							(end -0.2032 0.3048)
						)
						(arc
							(start 0.2032 0.3048)
							(mid 0.275042 0.275042)
							(end 0.3048 0.2032)
						)
					)
					(width 0)
					(fill yes)
				)
			)
		)
	)
	(footprint ""
		(layer "F.Cu")
		(at 6.857746 -493.1537 180)
		(property "Reference" "TP21"
			(at 0 0 180)
			(layer "F.SilkS")
			(hide yes)
			(effects
				(font
					(size 1.27 1.27)
				)
			)
		)
		(property "Value" "TPAD32-GP"
			(at 0 -3.166364 180)
			(unlocked yes)
			(layer "F.Fab")
			(hide yes)
			(effects
				(font
					(size 1.016 1.016)
					(thickness 0.1524)
				)
			)
		)
		(property "Device Type" "TPAD32"
			(at 0 -4.690618 180)
			(unlocked yes)
			(layer "F.Fab")
			(hide yes)
			(effects
				(font
					(size 1.016 1.016)
					(thickness 0.1524)
				)
			)
		)
		(duplicate_pad_numbers_are_jumpers no)
		(fp_poly
			(pts
				(arc
					(start -0.4064 0)
					(mid 0.4064 0)
					(end -0.4064 0)
				)
			)
			(stroke
				(width 0)
				(type default)
			)
			(fill no)
			(layer "F.CrtYd")
		)
		(fp_poly
			(pts
				(arc
					(start -0.7112 0)
					(mid 0.7112 0)
					(end -0.7112 0)
				)
			)
			(stroke
				(width 0)
				(type default)
			)
			(fill no)
			(layer "F.Fab")
		)
		(pad "1" smd circle
			(at 0 0 180)
			(size 0.8128 0.8128)
			(layers "F.Cu" "F.Mask" "F.Paste")
			(net "P5VC_EN")
		)
	)
	(footprint ""
		(layer "F.Cu")
		(at 199.855582 -292.453568 -90)
		(property "Reference" "U8"
			(at 0 0 270)
			(layer "F.SilkS")
			(hide yes)
			(effects
				(font
					(size 1.27 1.27)
				)
			)
		)
		(property "Value" "P2003EVG-GP"
			(at 0 -11.1252 270)
			(unlocked yes)
			(layer "F.Fab")
			(hide yes)
			(effects
				(font
					(size 1.016 1.016)
					(thickness 0.1524)
				)
			)
		)
		(property "Device Type" "SOIC8H79"
			(at 0 -12.6492 270)
			(unlocked yes)
			(layer "F.Fab")
			(hide yes)
			(effects
				(font
					(size 1.016 1.016)
					(thickness 0.1524)
				)
			)
		)
		(duplicate_pad_numbers_are_jumpers no)
		(fp_line
			(start -2.6162 3.429)
			(end -2.6162 1.4732)
			(stroke
				(width 0.4064)
				(type default)
			)
			(layer "F.SilkS")
		)
		(fp_line
			(start -2.7432 1.4224)
			(end 2.1336 1.4224)
			(stroke
				(width 0.1524)
				(type default)
			)
			(layer "F.SilkS")
		)
		(fp_line
			(start 2.1336 1.4224)
			(end 2.1336 -1.4224)
			(stroke
				(width 0.1524)
				(type default)
			)
			(layer "F.SilkS")
		)
		(fp_line
			(start -2.2352 0)
			(end -2.7432 0.508)
			(stroke
				(width 0.1524)
				(type default)
			)
			(layer "F.SilkS")
		)
		(fp_line
			(start -2.7432 -0.508)
			(end -2.2352 0)
			(stroke
				(width 0.1524)
				(type default)
			)
			(layer "F.SilkS")
		)
		(fp_line
			(start -2.7432 -1.4224)
			(end -2.7432 1.4224)
			(stroke
				(width 0.1524)
				(type default)
			)
			(layer "F.SilkS")
		)
		(fp_line
			(start 2.1336 -1.4224)
			(end -2.7432 -1.4224)
			(stroke
				(width 0.1524)
				(type default)
			)
			(layer "F.SilkS")
		)
		(fp_poly
			(pts
				(xy 2.2098 -1.4224) (xy 2.2098 1.4224) (xy -2.2225 1.4224) (xy -2.2225 -1.4224)
			)
			(stroke
				(width 0)
				(type default)
			)
			(fill yes)
			(layer "F.SilkS")
		)
		(fp_rect
			(start -2.4511 2.9972)
			(end 2.4511 -2.9972)
			(stroke
				(width 0)
				(type default)
			)
			(fill no)
			(layer "F.CrtYd")
		)
		(fp_poly
			(pts
				(xy -2.8194 3.6322) (xy -2.8194 -3.6322) (xy 2.8194 -3.6322) (xy 2.8194 -2.2987) (xy 2.4511 -2.2987)
				(xy 2.4511 -2.9972) (xy -2.4511 -2.9972) (xy -2.4511 2.9972) (xy 2.4511 2.9972) (xy 2.4511 -2.286)
				(xy 2.8194 -2.286) (xy 2.8194 3.6322)
			)
			(stroke
				(width 0)
				(type default)
			)
			(fill no)
			(layer "F.CrtYd")
		)
		(fp_rect
			(start -2.8194 3.6322)
			(end 2.8194 -3.6322)
			(stroke
				(width 0)
				(type default)
			)
			(fill no)
			(layer "F.Fab")
		)
		(pad "1" smd rect
			(at -1.905 2.54 270)
			(size 0.635 1.651)
			(layers "F.Cu" "F.Mask" "F.Paste")
			(net "P12V")
		)
		(pad "2" smd rect
			(at -0.635 2.54 270)
			(size 0.635 1.651)
			(layers "F.Cu" "F.Mask" "F.Paste")
			(net "P12V")
		)
		(pad "3" smd rect
			(at 0.635 2.54 270)
			(size 0.635 1.651)
			(layers "F.Cu" "F.Mask" "F.Paste")
			(net "P12V")
		)
		(pad "4" smd rect
			(at 1.905 2.54 270)
			(size 0.635 1.651)
			(layers "F.Cu" "F.Mask" "F.Paste")
			(net "SW_HDD2_N")
		)
		(pad "5" smd rect
			(at 1.905 -2.54 270)
			(size 0.635 1.651)
			(layers "F.Cu" "F.Mask" "F.Paste")
			(net "P12V_HDD2")
		)
		(pad "6" smd rect
			(at 0.635 -2.54 270)
			(size 0.635 1.651)
			(layers "F.Cu" "F.Mask" "F.Paste")
			(net "P12V_HDD2")
		)
		(pad "7" smd rect
			(at -0.635 -2.54 270)
			(size 0.635 1.651)
			(layers "F.Cu" "F.Mask" "F.Paste")
			(net "P12V_HDD2")
		)
		(pad "8" smd rect
			(at -1.905 -2.54 270)
			(size 0.635 1.651)
			(layers "F.Cu" "F.Mask" "F.Paste")
			(net "P12V_HDD2")
		)
	)
	(footprint ""
		(layer "F.Cu")
		(at 209.8294 -169.7736 180)
		(property "Reference" "R366"
			(at 0 0 180)
			(layer "F.SilkS")
			(hide yes)
			(effects
				(font
					(size 1.27 1.27)
				)
			)
		)
		(property "Value" "10KR2F-2-GP"
			(at 0.064008 -3.993896 180)
			(unlocked yes)
			(layer "F.Fab")
			(hide yes)
			(effects
				(font
					(size 1.016 1.016)
					(thickness 0.1524)
				)
			)
		)
		(property "Device Type" "R402H16"
			(at 0.064008 -5.517896 180)
			(unlocked yes)
			(layer "F.Fab")
			(hide yes)
			(effects
				(font
					(size 1.016 1.016)
					(thickness 0.1524)
				)
			)
		)
		(duplicate_pad_numbers_are_jumpers no)
		(fp_line
			(start 0.508 -0.9398)
			(end -0.508 -0.9398)
			(stroke
				(width 0.1524)
				(type default)
			)
			(layer "F.SilkS")
		)
		(fp_line
			(start -0.508 -0.9398)
			(end -0.508 0.9398)
			(stroke
				(width 0.1524)
				(type default)
			)
			(layer "F.SilkS")
		)
		(fp_rect
			(start -0.508 0.9398)
			(end 0.508 -0.9398)
			(stroke
				(width 0)
				(type default)
			)
			(fill no)
			(layer "F.CrtYd")
		)
		(fp_rect
			(start -0.508 0.9398)
			(end 0.508 -0.9398)
			(stroke
				(width 0)
				(type default)
			)
			(fill no)
			(layer "F.Fab")
		)
		(pad "1" smd custom
			(at 0 -0.4445 180)
			(size 0.1397 0.1397)
			(layers "F.Cu" "F.Mask" "F.Paste")
			(net "P12V")
			(options
				(clearance outline)
				(anchor circle)
			)
			(primitives
				(gr_poly
					(pts
						(arc
							(start -0.1778 -0.2794)
							(mid -0.249642 -0.249642)
							(end -0.2794 -0.1778)
						)
						(arc
							(start -0.2794 0.1778)
							(mid -0.249642 0.249642)
							(end -0.1778 0.2794)
						)
						(arc
							(start 0.1778 0.2794)
							(mid 0.249642 0.249642)
							(end 0.2794 0.1778)
						)
						(arc
							(start 0.2794 -0.1778)
							(mid 0.249642 -0.249642)
							(end 0.1778 -0.2794)
						)
					)
					(width 0)
					(fill yes)
				)
			)
		)
		(pad "2" smd custom
			(at 0 0.4445 180)
			(size 0.1397 0.1397)
			(layers "F.Cu" "F.Mask" "F.Paste")
			(net "HDD3_LED_G")
			(options
				(clearance outline)
				(anchor circle)
			)
			(primitives
				(gr_poly
					(pts
						(arc
							(start -0.1778 -0.2794)
							(mid -0.249642 -0.249642)
							(end -0.2794 -0.1778)
						)
						(arc
							(start -0.2794 0.1778)
							(mid -0.249642 0.249642)
							(end -0.1778 0.2794)
						)
						(arc
							(start 0.1778 0.2794)
							(mid 0.249642 0.249642)
							(end 0.2794 0.1778)
						)
						(arc
							(start 0.2794 -0.1778)
							(mid 0.249642 -0.249642)
							(end 0.1778 -0.2794)
						)
					)
					(width 0)
					(fill yes)
				)
			)
		)
	)
	(footprint ""
		(layer "F.Cu")
		(at 197.611746 -81.9277 -90)
		(property "Reference" "R441"
			(at 0 0 270)
			(layer "F.SilkS")
			(hide yes)
			(effects
				(font
					(size 1.27 1.27)
				)
			)
		)
		(property "Value" "4K7R2J-2-GP"
			(at 0.064008 -3.993896 270)
			(unlocked yes)
			(layer "F.Fab")
			(hide yes)
			(effects
				(font
					(size 1.016 1.016)
					(thickness 0.1524)
				)
			)
		)
		(property "Device Type" "R402H16"
			(at 0.064008 -5.517896 270)
			(unlocked yes)
			(layer "F.Fab")
			(hide yes)
			(effects
				(font
					(size 1.016 1.016)
					(thickness 0.1524)
				)
			)
		)
		(duplicate_pad_numbers_are_jumpers no)
		(fp_line
			(start -0.508 -0.9398)
			(end -0.508 0.9398)
			(stroke
				(width 0.1524)
				(type default)
			)
			(layer "F.SilkS")
		)
		(fp_line
			(start 0.508 -0.9398)
			(end -0.508 -0.9398)
			(stroke
				(width 0.1524)
				(type default)
			)
			(layer "F.SilkS")
		)
		(fp_rect
			(start -0.508 0.9398)
			(end 0.508 -0.9398)
			(stroke
				(width 0)
				(type default)
			)
			(fill no)
			(layer "F.CrtYd")
		)
		(fp_rect
			(start -0.508 0.9398)
			(end 0.508 -0.9398)
			(stroke
				(width 0)
				(type default)
			)
			(fill no)
			(layer "F.Fab")
		)
		(pad "1" smd custom
			(at 0 -0.4445 270)
			(size 0.1397 0.1397)
			(layers "F.Cu" "F.Mask" "F.Paste")
			(net "P3V3")
			(options
				(clearance outline)
				(anchor circle)
			)
			(primitives
				(gr_poly
					(pts
						(arc
							(start -0.1778 -0.2794)
							(mid -0.249642 -0.249642)
							(end -0.2794 -0.1778)
						)
						(arc
							(start -0.2794 0.1778)
							(mid -0.249642 0.249642)
							(end -0.1778 0.2794)
						)
						(arc
							(start 0.1778 0.2794)
							(mid 0.249642 0.249642)
							(end 0.2794 0.1778)
						)
						(arc
							(start 0.2794 -0.1778)
							(mid 0.249642 -0.249642)
							(end 0.1778 -0.2794)
						)
					)
					(width 0)
					(fill yes)
				)
			)
		)
		(pad "2" smd custom
			(at 0 0.4445 270)
			(size 0.1397 0.1397)
			(layers "F.Cu" "F.Mask" "F.Paste")
			(net "SAS_EXP_B_PWR4")
			(options
				(clearance outline)
				(anchor circle)
			)
			(primitives
				(gr_poly
					(pts
						(arc
							(start -0.1778 -0.2794)
							(mid -0.249642 -0.249642)
							(end -0.2794 -0.1778)
						)
						(arc
							(start -0.2794 0.1778)
							(mid -0.249642 0.249642)
							(end -0.1778 0.2794)
						)
						(arc
							(start 0.1778 0.2794)
							(mid 0.249642 0.249642)
							(end 0.2794 0.1778)
						)
						(arc
							(start 0.2794 -0.1778)
							(mid 0.249642 -0.249642)
							(end 0.1778 -0.2794)
						)
					)
					(width 0)
					(fill yes)
				)
			)
		)
	)
	(footprint ""
		(layer "F.Cu")
		(at 230.267256 -451.513702 90)
		(property "Reference" "R105"
			(at 0 0 90)
			(layer "F.SilkS")
			(hide yes)
			(effects
				(font
					(size 1.27 1.27)
				)
			)
		)
		(property "Value" "0R2J-2-GP"
			(at 0.064008 -3.993896 90)
			(unlocked yes)
			(layer "F.Fab")
			(hide yes)
			(effects
				(font
					(size 1.016 1.016)
					(thickness 0.1524)
				)
			)
		)
		(property "Device Type" "R402H16"
			(at 0.064008 -5.517896 90)
			(unlocked yes)
			(layer "F.Fab")
			(hide yes)
			(effects
				(font
					(size 1.016 1.016)
					(thickness 0.1524)
				)
			)
		)
		(duplicate_pad_numbers_are_jumpers no)
		(fp_line
			(start 0.508 -0.9398)
			(end -0.508 -0.9398)
			(stroke
				(width 0.1524)
				(type default)
			)
			(layer "F.SilkS")
		)
		(fp_line
			(start -0.508 -0.9398)
			(end -0.508 0.9398)
			(stroke
				(width 0.1524)
				(type default)
			)
			(layer "F.SilkS")
		)
		(fp_rect
			(start -0.508 0.9398)
			(end 0.508 -0.9398)
			(stroke
				(width 0)
				(type default)
			)
			(fill no)
			(layer "F.CrtYd")
		)
		(fp_rect
			(start -0.508 0.9398)
			(end 0.508 -0.9398)
			(stroke
				(width 0)
				(type default)
			)
			(fill no)
			(layer "F.Fab")
		)
		(pad "1" smd custom
			(at 0 -0.4445 90)
			(size 0.1397 0.1397)
			(layers "F.Cu" "F.Mask" "F.Paste")
			(net "FLT_NET_HDD0")
			(options
				(clearance outline)
				(anchor circle)
			)
			(primitives
				(gr_poly
					(pts
						(arc
							(start -0.1778 -0.2794)
							(mid -0.249642 -0.249642)
							(end -0.2794 -0.1778)
						)
						(arc
							(start -0.2794 0.1778)
							(mid -0.249642 0.249642)
							(end -0.1778 0.2794)
						)
						(arc
							(start 0.1778 0.2794)
							(mid 0.249642 0.249642)
							(end 0.2794 0.1778)
						)
						(arc
							(start 0.2794 -0.1778)
							(mid 0.249642 -0.249642)
							(end 0.1778 -0.2794)
						)
					)
					(width 0)
					(fill yes)
				)
			)
		)
		(pad "2" smd custom
			(at 0 0.4445 90)
			(size 0.1397 0.1397)
			(layers "F.Cu" "F.Mask" "F.Paste")
			(net "FLT_HDD0_DRIVE")
			(options
				(clearance outline)
				(anchor circle)
			)
			(primitives
				(gr_poly
					(pts
						(arc
							(start -0.1778 -0.2794)
							(mid -0.249642 -0.249642)
							(end -0.2794 -0.1778)
						)
						(arc
							(start -0.2794 0.1778)
							(mid -0.249642 0.249642)
							(end -0.1778 0.2794)
						)
						(arc
							(start 0.1778 0.2794)
							(mid 0.249642 0.249642)
							(end 0.2794 0.1778)
						)
						(arc
							(start 0.2794 -0.1778)
							(mid 0.249642 -0.249642)
							(end 0.1778 -0.2794)
						)
					)
					(width 0)
					(fill yes)
				)
			)
		)
	)
	(footprint ""
		(layer "F.Cu")
		(at 9.651746 -487.1847 90)
		(property "Reference" "PC28"
			(at 0 0 90)
			(layer "F.SilkS")
			(hide yes)
			(effects
				(font
					(size 1.27 1.27)
				)
			)
		)
		(property "Value" "SCD1U25V2KX-GP"
			(at 1.1811 -2.7051 90)
			(unlocked yes)
			(layer "F.Fab")
			(hide yes)
			(effects
				(font
					(size 1.016 1.016)
					(thickness 0.1524)
				)
			)
		)
		(property "Device Type" "C402H22"
			(at 1.1811 -4.2291 90)
			(unlocked yes)
			(layer "F.Fab")
			(hide yes)
			(effects
				(font
					(size 1.016 1.016)
					(thickness 0.1524)
				)
			)
		)
		(duplicate_pad_numbers_are_jumpers no)
		(fp_rect
			(start -0.4318 0.9525)
			(end 0.4318 -0.9525)
			(stroke
				(width 0)
				(type default)
			)
			(fill no)
			(layer "F.CrtYd")
		)
		(fp_rect
			(start -0.4318 0.9525)
			(end 0.4318 -0.9525)
			(stroke
				(width 0)
				(type default)
			)
			(fill no)
			(layer "F.Fab")
		)
		(pad "1" smd custom
			(at 0 -0.4445 90)
			(size 0.1524 0.1524)
			(layers "F.Cu" "F.Mask" "F.Paste")
			(net "P5VC_VBST_NET")
			(options
				(clearance outline)
				(anchor circle)
			)
			(primitives
				(gr_poly
					(pts
						(arc
							(start 0.3048 -0.2032)
							(mid 0.275042 -0.275042)
							(end 0.2032 -0.3048)
						)
						(arc
							(start -0.2032 -0.3048)
							(mid -0.275042 -0.275042)
							(end -0.3048 -0.2032)
						)
						(arc
							(start -0.3048 0.2032)
							(mid -0.275042 0.275042)
							(end -0.2032 0.3048)
						)
						(arc
							(start 0.2032 0.3048)
							(mid 0.275042 0.275042)
							(end 0.3048 0.2032)
						)
					)
					(width 0)
					(fill yes)
				)
			)
		)
		(pad "2" smd custom
			(at 0 0.4445 90)
			(size 0.1524 0.1524)
			(layers "F.Cu" "F.Mask" "F.Paste")
			(net "P5VC_LL")
			(options
				(clearance outline)
				(anchor circle)
			)
			(primitives
				(gr_poly
					(pts
						(arc
							(start 0.3048 -0.2032)
							(mid 0.275042 -0.275042)
							(end 0.2032 -0.3048)
						)
						(arc
							(start -0.2032 -0.3048)
							(mid -0.275042 -0.275042)
							(end -0.3048 -0.2032)
						)
						(arc
							(start -0.3048 0.2032)
							(mid -0.275042 0.275042)
							(end -0.2032 0.3048)
						)
						(arc
							(start 0.2032 0.3048)
							(mid 0.275042 0.275042)
							(end 0.3048 0.2032)
						)
					)
					(width 0)
					(fill yes)
				)
			)
		)
	)
	(footprint ""
		(layer "F.Cu")
		(at 58.166 -497.6114 180)
		(property "Reference" "C193"
			(at 0 0 180)
			(layer "F.SilkS")
			(hide yes)
			(effects
				(font
					(size 1.27 1.27)
				)
			)
		)
		(property "Value" "SC10U25V6KX-1GP"
			(at -0.0762 -5.1308 180)
			(unlocked yes)
			(layer "F.Fab")
			(hide yes)
			(effects
				(font
					(size 1.016 1.016)
					(thickness 0.1524)
				)
			)
		)
		(property "Device Type" "C1206H71"
			(at -0.127 -6.6548 180)
			(unlocked yes)
			(layer "F.Fab")
			(hide yes)
			(effects
				(font
					(size 1.016 1.016)
					(thickness 0.1524)
				)
			)
		)
		(duplicate_pad_numbers_are_jumpers no)
		(fp_line
			(start 1.016 2.2352)
			(end -1.016 2.2352)
			(stroke
				(width 0.1524)
				(type default)
			)
			(layer "F.SilkS")
		)
		(fp_line
			(start 1.016 0.8382)
			(end 1.016 2.2352)
			(stroke
				(width 0.1524)
				(type default)
			)
			(layer "F.SilkS")
		)
		(fp_line
			(start 1.016 -2.2352)
			(end 1.016 -0.8382)
			(stroke
				(width 0.1524)
				(type default)
			)
			(layer "F.SilkS")
		)
		(fp_line
			(start -1.016 2.2352)
			(end -1.016 0.8382)
			(stroke
				(width 0.1524)
				(type default)
			)
			(layer "F.SilkS")
		)
		(fp_line
			(start -1.016 -0.8382)
			(end -1.016 -2.2352)
			(stroke
				(width 0.1524)
				(type default)
			)
			(layer "F.SilkS")
		)
		(fp_line
			(start -1.016 -2.2352)
			(end 1.016 -2.2352)
			(stroke
				(width 0.1524)
				(type default)
			)
			(layer "F.SilkS")
		)
		(fp_rect
			(start -1.0922 2.3114)
			(end 1.0922 -2.3114)
			(stroke
				(width 0)
				(type default)
			)
			(fill no)
			(layer "F.CrtYd")
		)
		(fp_poly
			(pts
				(xy 1.0922 -2.3114) (xy 1.0922 2.3114) (xy -1.0922 2.3114) (xy -1.0922 -2.3114)
			)
			(stroke
				(width 0)
				(type default)
			)
			(fill no)
			(layer "F.Fab")
		)
		(pad "1" smd rect
			(at 0 -1.397 180)
			(size 1.651 1.27)
			(layers "F.Cu" "F.Mask" "F.Paste")
			(net "P12V_HDD5")
		)
		(pad "2" smd rect
			(at 0 1.397 180)
			(size 1.651 1.27)
			(layers "F.Cu" "F.Mask" "F.Paste")
			(net "GND")
		)
	)
	(footprint ""
		(layer "F.Cu")
		(at 58.149236 -484.298498 90)
		(property "Reference" "R175"
			(at 0 0 90)
			(layer "F.SilkS")
			(hide yes)
			(effects
				(font
					(size 1.27 1.27)
				)
			)
		)
		(property "Value" "2R2010J-1-GP"
			(at 0.254 -8.0772 90)
			(unlocked yes)
			(layer "F.Fab")
			(hide yes)
			(effects
				(font
					(size 1.016 1.016)
					(thickness 0.1524)
				)
			)
		)
		(property "Device Type" "R2010H28"
			(at 0.254 -9.6774 90)
			(unlocked yes)
			(layer "F.Fab")
			(hide yes)
			(effects
				(font
					(size 1.016 1.016)
					(thickness 0.1524)
				)
			)
		)
		(duplicate_pad_numbers_are_jumpers no)
		(fp_line
			(start 1.651 -3.302)
			(end -1.651 -3.302)
			(stroke
				(width 0.1524)
				(type default)
			)
			(layer "F.SilkS")
		)
		(fp_line
			(start -1.651 -3.302)
			(end -1.651 3.302)
			(stroke
				(width 0.1524)
				(type default)
			)
			(layer "F.SilkS")
		)
		(fp_line
			(start 1.651 3.302)
			(end 1.651 -3.302)
			(stroke
				(width 0.1524)
				(type default)
			)
			(layer "F.SilkS")
		)
		(fp_line
			(start -1.651 3.302)
			(end 1.651 3.302)
			(stroke
				(width 0.1524)
				(type default)
			)
			(layer "F.SilkS")
		)
		(fp_rect
			(start -1.7272 -3.3782)
			(end 1.7272 3.3782)
			(stroke
				(width 0)
				(type default)
			)
			(fill no)
			(layer "F.CrtYd")
		)
		(fp_poly
			(pts
				(xy 1.7272 3.3782) (xy 1.7272 -3.3782) (xy -1.7272 -3.3782) (xy -1.7272 3.3782)
			)
			(stroke
				(width 0)
				(type default)
			)
			(fill no)
			(layer "F.Fab")
		)
		(pad "1" smd rect
			(at 0 -2.3495 90)
			(size 2.794 1.143)
			(layers "F.Cu" "F.Mask" "F.Paste")
			(net "5V_PRE_5")
		)
		(pad "2" smd rect
			(at 0 2.3495 90)
			(size 2.794 1.143)
			(layers "F.Cu" "F.Mask" "F.Paste")
			(net "P5V_HDD5")
		)
	)
	(footprint ""
		(layer "F.Cu")
		(at 212.1662 -171.1706 180)
		(property "Reference" "Q53"
			(at 0 0 180)
			(layer "F.SilkS")
			(hide yes)
			(effects
				(font
					(size 1.27 1.27)
				)
			)
		)
		(property "Value" "2N7002-11-GP"
			(at 0.127 -8.9662 180)
			(unlocked yes)
			(layer "F.Fab")
			(hide yes)
			(effects
				(font
					(size 1.016 1.016)
					(thickness 0.1524)
				)
			)
		)
		(property "Device Type" "SOT23DGS2D4H44"
			(at 0.127 -10.4902 180)
			(unlocked yes)
			(layer "F.Fab")
			(hide yes)
			(effects
				(font
					(size 1.016 1.016)
					(thickness 0.1524)
				)
			)
		)
		(duplicate_pad_numbers_are_jumpers no)
		(fp_line
			(start 1.651 1.778)
			(end 1.651 -1.778)
			(stroke
				(width 0.1524)
				(type default)
			)
			(layer "F.SilkS")
		)
		(fp_line
			(start 1.651 -1.778)
			(end -1.651 -1.778)
			(stroke
				(width 0.1524)
				(type default)
			)
			(layer "F.SilkS")
		)
		(fp_line
			(start -1.651 1.778)
			(end 1.651 1.778)
			(stroke
				(width 0.1524)
				(type default)
			)
			(layer "F.SilkS")
		)
		(fp_line
			(start -1.651 -1.778)
			(end -1.651 1.778)
			(stroke
				(width 0.1524)
				(type default)
			)
			(layer "F.SilkS")
		)
		(fp_poly
			(pts
				(xy -1.778 1.8796) (xy -1.778 -1.8796) (xy 1.778 -1.8796) (xy 1.778 1.8796)
			)
			(stroke
				(width 0)
				(type default)
			)
			(fill no)
			(layer "F.CrtYd")
		)
		(fp_poly
			(pts
				(xy -1.778 1.8796) (xy -1.778 -1.8796) (xy 1.778 -1.8796) (xy 1.778 1.8796)
			)
			(stroke
				(width 0)
				(type default)
			)
			(fill no)
			(layer "F.Fab")
		)
		(pad "D" smd custom
			(at 0 -0.9525 180)
			(size 0.1905 0.1905)
			(layers "F.Cu" "F.Mask" "F.Paste")
			(net "HDD3_LED_G")
			(options
				(clearance outline)
				(anchor circle)
			)
			(primitives
				(gr_poly
					(pts
						(arc
							(start -0.1778 0.5715)
							(mid -0.321484 0.511984)
							(end -0.381 0.3683)
						)
						(arc
							(start -0.381 -0.3683)
							(mid -0.321484 -0.511984)
							(end -0.1778 -0.5715)
						)
						(arc
							(start 0.1778 -0.5715)
							(mid 0.321484 -0.511984)
							(end 0.381 -0.3683)
						)
						(arc
							(start 0.381 0.3683)
							(mid 0.321484 0.511984)
							(end 0.1778 0.5715)
						)
					)
					(width 0)
					(fill yes)
				)
			)
		)
		(pad "G" smd custom
			(at -0.98425 0.9525 180)
			(size 0.1905 0.1905)
			(layers "F.Cu" "F.Mask" "F.Paste")
			(net "HDD3_LED_B")
			(options
				(clearance outline)
				(anchor circle)
			)
			(primitives
				(gr_poly
					(pts
						(arc
							(start -0.1778 0.5715)
							(mid -0.321484 0.511984)
							(end -0.381 0.3683)
						)
						(arc
							(start -0.381 -0.3683)
							(mid -0.321484 -0.511984)
							(end -0.1778 -0.5715)
						)
						(arc
							(start 0.1778 -0.5715)
							(mid 0.321484 -0.511984)
							(end 0.381 -0.3683)
						)
						(arc
							(start 0.381 0.3683)
							(mid 0.321484 0.511984)
							(end 0.1778 0.5715)
						)
					)
					(width 0)
					(fill yes)
				)
			)
		)
		(pad "S" smd custom
			(at 0.98425 0.9525 180)
			(size 0.1905 0.1905)
			(layers "F.Cu" "F.Mask" "F.Paste")
			(net "GND")
			(options
				(clearance outline)
				(anchor circle)
			)
			(primitives
				(gr_poly
					(pts
						(arc
							(start -0.1778 0.5715)
							(mid -0.321484 0.511984)
							(end -0.381 0.3683)
						)
						(arc
							(start -0.381 -0.3683)
							(mid -0.321484 -0.511984)
							(end -0.1778 -0.5715)
						)
						(arc
							(start 0.1778 -0.5715)
							(mid 0.321484 -0.511984)
							(end 0.381 -0.3683)
						)
						(arc
							(start 0.381 0.3683)
							(mid 0.321484 0.511984)
							(end 0.1778 0.5715)
						)
					)
					(width 0)
					(fill yes)
				)
			)
		)
	)
	(footprint ""
		(layer "F.Cu")
		(at 6.86562 -489.442252)
		(property "Reference" "PR47"
			(at 0 0 0)
			(layer "F.SilkS")
			(hide yes)
			(effects
				(font
					(size 1.27 1.27)
				)
			)
		)
		(property "Value" "76K8R2F-GP"
			(at 0.064008 -3.993896 0)
			(unlocked yes)
			(layer "F.Fab")
			(hide yes)
			(effects
				(font
					(size 1.016 1.016)
					(thickness 0.1524)
				)
			)
		)
		(property "Device Type" "R402H16"
			(at 0.064008 -5.517896 0)
			(unlocked yes)
			(layer "F.Fab")
			(hide yes)
			(effects
				(font
					(size 1.016 1.016)
					(thickness 0.1524)
				)
			)
		)
		(duplicate_pad_numbers_are_jumpers no)
		(fp_line
			(start -0.508 -0.9398)
			(end -0.508 0.9398)
			(stroke
				(width 0.1524)
				(type default)
			)
			(layer "F.SilkS")
		)
		(fp_line
			(start 0.508 -0.9398)
			(end -0.508 -0.9398)
			(stroke
				(width 0.1524)
				(type default)
			)
			(layer "F.SilkS")
		)
		(fp_rect
			(start -0.508 0.9398)
			(end 0.508 -0.9398)
			(stroke
				(width 0)
				(type default)
			)
			(fill no)
			(layer "F.CrtYd")
		)
		(fp_rect
			(start -0.508 0.9398)
			(end 0.508 -0.9398)
			(stroke
				(width 0)
				(type default)
			)
			(fill no)
			(layer "F.Fab")
		)
		(pad "1" smd custom
			(at 0 -0.4445)
			(size 0.1397 0.1397)
			(layers "F.Cu" "F.Mask" "F.Paste")
			(net "P5VC_ROVP")
			(options
				(clearance outline)
				(anchor circle)
			)
			(primitives
				(gr_poly
					(pts
						(arc
							(start -0.1778 -0.2794)
							(mid -0.249642 -0.249642)
							(end -0.2794 -0.1778)
						)
						(arc
							(start -0.2794 0.1778)
							(mid -0.249642 0.249642)
							(end -0.1778 0.2794)
						)
						(arc
							(start 0.1778 0.2794)
							(mid 0.249642 0.249642)
							(end 0.2794 0.1778)
						)
						(arc
							(start 0.2794 -0.1778)
							(mid 0.249642 -0.249642)
							(end 0.1778 -0.2794)
						)
					)
					(width 0)
					(fill yes)
				)
			)
		)
		(pad "2" smd custom
			(at 0 0.4445)
			(size 0.1397 0.1397)
			(layers "F.Cu" "F.Mask" "F.Paste")
			(net "P5VC")
			(options
				(clearance outline)
				(anchor circle)
			)
			(primitives
				(gr_poly
					(pts
						(arc
							(start -0.1778 -0.2794)
							(mid -0.249642 -0.249642)
							(end -0.2794 -0.1778)
						)
						(arc
							(start -0.2794 0.1778)
							(mid -0.249642 0.249642)
							(end -0.1778 0.2794)
						)
						(arc
							(start 0.1778 0.2794)
							(mid 0.249642 0.249642)
							(end 0.2794 0.1778)
						)
						(arc
							(start 0.2794 -0.1778)
							(mid 0.249642 -0.249642)
							(end 0.1778 -0.2794)
						)
					)
					(width 0)
					(fill yes)
				)
			)
		)
	)
	(footprint ""
		(layer "F.Cu")
		(at 56.6166 -276.4282)
		(property "Reference" "C222"
			(at 0 0 0)
			(layer "F.SilkS")
			(hide yes)
			(effects
				(font
					(size 1.27 1.27)
				)
			)
		)
		(property "Value" "SCD01U50V2KX-1GP"
			(at 1.1811 -2.7051 0)
			(unlocked yes)
			(layer "F.Fab")
			(hide yes)
			(effects
				(font
					(size 1.016 1.016)
					(thickness 0.1524)
				)
			)
		)
		(property "Device Type" "C402H22"
			(at 1.1811 -4.2291 0)
			(unlocked yes)
			(layer "F.Fab")
			(hide yes)
			(effects
				(font
					(size 1.016 1.016)
					(thickness 0.1524)
				)
			)
		)
		(duplicate_pad_numbers_are_jumpers no)
		(fp_rect
			(start -0.4318 0.9525)
			(end 0.4318 -0.9525)
			(stroke
				(width 0)
				(type default)
			)
			(fill no)
			(layer "F.CrtYd")
		)
		(fp_rect
			(start -0.4318 0.9525)
			(end 0.4318 -0.9525)
			(stroke
				(width 0)
				(type default)
			)
			(fill no)
			(layer "F.Fab")
		)
		(pad "1" smd custom
			(at 0 -0.4445)
			(size 0.1524 0.1524)
			(layers "F.Cu" "F.Mask" "F.Paste")
			(net "HDD_PRSNT_NET7")
			(options
				(clearance outline)
				(anchor circle)
			)
			(primitives
				(gr_poly
					(pts
						(arc
							(start 0.3048 -0.2032)
							(mid 0.275042 -0.275042)
							(end 0.2032 -0.3048)
						)
						(arc
							(start -0.2032 -0.3048)
							(mid -0.275042 -0.275042)
							(end -0.3048 -0.2032)
						)
						(arc
							(start -0.3048 0.2032)
							(mid -0.275042 0.275042)
							(end -0.2032 0.3048)
						)
						(arc
							(start 0.2032 0.3048)
							(mid 0.275042 0.275042)
							(end 0.3048 0.2032)
						)
					)
					(width 0)
					(fill yes)
				)
			)
		)
		(pad "2" smd custom
			(at 0 0.4445)
			(size 0.1524 0.1524)
			(layers "F.Cu" "F.Mask" "F.Paste")
			(net "GND")
			(options
				(clearance outline)
				(anchor circle)
			)
			(primitives
				(gr_poly
					(pts
						(arc
							(start 0.3048 -0.2032)
							(mid 0.275042 -0.275042)
							(end 0.2032 -0.3048)
						)
						(arc
							(start -0.2032 -0.3048)
							(mid -0.275042 -0.275042)
							(end -0.3048 -0.2032)
						)
						(arc
							(start -0.3048 0.2032)
							(mid -0.275042 0.275042)
							(end -0.2032 0.3048)
						)
						(arc
							(start 0.2032 0.3048)
							(mid 0.275042 0.275042)
							(end 0.3048 0.2032)
						)
					)
					(width 0)
					(fill yes)
				)
			)
		)
	)
	(footprint ""
		(layer "F.Cu")
		(at 198.894446 -461.425036 180)
		(property "Reference" "C346"
			(at 0 0 180)
			(layer "F.SilkS")
			(hide yes)
			(effects
				(font
					(size 1.27 1.27)
				)
			)
		)
		(property "Value" "SC1U16V3KX-5GP"
			(at 0 -2.8194 180)
			(unlocked yes)
			(layer "F.Fab")
			(hide yes)
			(effects
				(font
					(size 1.016 1.016)
					(thickness 0.1524)
				)
			)
		)
		(property "Device Type" "C603H36"
			(at 0 -4.3434 180)
			(unlocked yes)
			(layer "F.Fab")
			(hide yes)
			(effects
				(font
					(size 1.016 1.016)
					(thickness 0.1524)
				)
			)
		)
		(duplicate_pad_numbers_are_jumpers no)
		(fp_line
			(start 0.508 0)
			(end -0.508 0)
			(stroke
				(width 0.2032)
				(type default)
			)
			(layer "F.SilkS")
		)
		(fp_rect
			(start -0.5842 1.3335)
			(end 0.5842 -1.3335)
			(stroke
				(width 0)
				(type default)
			)
			(fill no)
			(layer "F.CrtYd")
		)
		(fp_rect
			(start -0.5842 1.3335)
			(end 0.5842 -1.3335)
			(stroke
				(width 0)
				(type default)
			)
			(fill no)
			(layer "F.Fab")
		)
		(pad "1" smd custom
			(at 0 -0.762 180)
			(size 0.2159 0.2159)
			(layers "F.Cu" "F.Mask" "F.Paste")
			(net "P3V3")
			(options
				(clearance outline)
				(anchor circle)
			)
			(primitives
				(gr_poly
					(pts
						(arc
							(start -0.3302 -0.4318)
							(mid -0.402042 -0.402042)
							(end -0.4318 -0.3302)
						)
						(arc
							(start -0.4318 0.3302)
							(mid -0.402042 0.402042)
							(end -0.3302 0.4318)
						)
						(arc
							(start 0.3302 0.4318)
							(mid 0.402042 0.402042)
							(end 0.4318 0.3302)
						)
						(arc
							(start 0.4318 -0.3302)
							(mid 0.402042 -0.402042)
							(end 0.3302 -0.4318)
						)
					)
					(width 0)
					(fill yes)
				)
			)
		)
		(pad "2" smd custom
			(at 0 0.762 180)
			(size 0.2159 0.2159)
			(layers "F.Cu" "F.Mask" "F.Paste")
			(net "GND")
			(options
				(clearance outline)
				(anchor circle)
			)
			(primitives
				(gr_poly
					(pts
						(arc
							(start -0.3302 -0.4318)
							(mid -0.402042 -0.402042)
							(end -0.4318 -0.3302)
						)
						(arc
							(start -0.4318 0.3302)
							(mid -0.402042 0.402042)
							(end -0.3302 0.4318)
						)
						(arc
							(start 0.3302 0.4318)
							(mid 0.402042 0.402042)
							(end 0.4318 0.3302)
						)
						(arc
							(start 0.4318 -0.3302)
							(mid 0.402042 -0.402042)
							(end 0.3302 -0.4318)
						)
					)
					(width 0)
					(fill yes)
				)
			)
		)
	)
	(footprint ""
		(layer "F.Cu")
		(at 194.013582 -286.738568 -90)
		(property "Reference" "U9"
			(at 0 0 270)
			(layer "F.SilkS")
			(hide yes)
			(effects
				(font
					(size 1.27 1.27)
				)
			)
		)
		(property "Value" "74LVC1G08GW-1-GP"
			(at -2.3368 -8.6868 270)
			(unlocked yes)
			(layer "F.Fab")
			(hide yes)
			(effects
				(font
					(size 1.016 1.016)
					(thickness 0.1524)
				)
			)
		)
		(property "Device Type" "SC70-5H44"
			(at -2.3114 -10.414 270)
			(unlocked yes)
			(layer "F.Fab")
			(hide yes)
			(effects
				(font
					(size 1.016 1.016)
					(thickness 0.1524)
				)
			)
		)
		(duplicate_pad_numbers_are_jumpers no)
		(fp_line
			(start -1.27 1.7018)
			(end -1.27 -1.7018)
			(stroke
				(width 0.1524)
				(type default)
			)
			(layer "F.SilkS")
		)
		(fp_line
			(start 1.27 1.7018)
			(end -1.27 1.7018)
			(stroke
				(width 0.1524)
				(type default)
			)
			(layer "F.SilkS")
		)
		(fp_line
			(start -1.27 -1.7018)
			(end 1.27 -1.7018)
			(stroke
				(width 0.1524)
				(type default)
			)
			(layer "F.SilkS")
		)
		(fp_line
			(start 1.27 -1.7018)
			(end 1.27 1.7018)
			(stroke
				(width 0.1524)
				(type default)
			)
			(layer "F.SilkS")
		)
		(fp_line
			(start 0.6604 -1.8034)
			(end 1.3843 -1.8034)
			(stroke
				(width 0.3302)
				(type default)
			)
			(layer "F.SilkS")
		)
		(fp_line
			(start 1.3843 -1.8034)
			(end 1.3843 -1.1176)
			(stroke
				(width 0.3302)
				(type default)
			)
			(layer "F.SilkS")
		)
		(fp_rect
			(start -1.524 1.9558)
			(end 1.524 -1.9558)
			(stroke
				(width 0)
				(type default)
			)
			(fill no)
			(layer "F.CrtYd")
		)
		(fp_poly
			(pts
				(xy -1.524 -1.9558) (xy 1.524 -1.9558) (xy 1.524 1.9558) (xy -1.524 1.9558)
			)
			(stroke
				(width 0)
				(type default)
			)
			(fill no)
			(layer "F.Fab")
		)
		(pad "1" smd rect
			(at 0.65024 -0.8255 270)
			(size 0.4064 1.2192)
			(layers "F.Cu" "F.Mask" "F.Paste")
			(net "SAS_EXP_B_PWR2")
		)
		(pad "2" smd rect
			(at 0 -0.8255 270)
			(size 0.4064 1.2192)
			(layers "F.Cu" "F.Mask" "F.Paste")
			(net "SAS_EXP_A_PWR2")
		)
		(pad "3" smd rect
			(at -0.65024 -0.8255 270)
			(size 0.4064 1.2192)
			(layers "F.Cu" "F.Mask" "F.Paste")
			(net "GND")
		)
		(pad "4" smd rect
			(at -0.65024 0.8255 270)
			(size 0.4064 1.2192)
			(layers "F.Cu" "F.Mask" "F.Paste")
			(net "DRIVE_PWR2")
		)
		(pad "5" smd rect
			(at 0.65024 0.8255 270)
			(size 0.4064 1.2192)
			(layers "F.Cu" "F.Mask" "F.Paste")
			(net "P3V3")
		)
	)
	(footprint ""
		(layer "F.Cu")
		(at 208.914746 -42.4307 -90)
		(property "Reference" "R340"
			(at 0 0 270)
			(layer "F.SilkS")
			(hide yes)
			(effects
				(font
					(size 1.27 1.27)
				)
			)
		)
		(property "Value" "4K7R2J-2-GP"
			(at 0.064008 -3.993896 270)
			(unlocked yes)
			(layer "F.Fab")
			(hide yes)
			(effects
				(font
					(size 1.016 1.016)
					(thickness 0.1524)
				)
			)
		)
		(property "Device Type" "R402H16"
			(at 0.064008 -5.517896 270)
			(unlocked yes)
			(layer "F.Fab")
			(hide yes)
			(effects
				(font
					(size 1.016 1.016)
					(thickness 0.1524)
				)
			)
		)
		(duplicate_pad_numbers_are_jumpers no)
		(fp_line
			(start -0.508 -0.9398)
			(end -0.508 0.9398)
			(stroke
				(width 0.1524)
				(type default)
			)
			(layer "F.SilkS")
		)
		(fp_line
			(start 0.508 -0.9398)
			(end -0.508 -0.9398)
			(stroke
				(width 0.1524)
				(type default)
			)
			(layer "F.SilkS")
		)
		(fp_rect
			(start -0.508 0.9398)
			(end 0.508 -0.9398)
			(stroke
				(width 0)
				(type default)
			)
			(fill no)
			(layer "F.CrtYd")
		)
		(fp_rect
			(start -0.508 0.9398)
			(end 0.508 -0.9398)
			(stroke
				(width 0)
				(type default)
			)
			(fill no)
			(layer "F.Fab")
		)
		(pad "1" smd custom
			(at 0 -0.4445 270)
			(size 0.1397 0.1397)
			(layers "F.Cu" "F.Mask" "F.Paste")
			(net "I2C_B_TMP4_A1")
			(options
				(clearance outline)
				(anchor circle)
			)
			(primitives
				(gr_poly
					(pts
						(arc
							(start -0.1778 -0.2794)
							(mid -0.249642 -0.249642)
							(end -0.2794 -0.1778)
						)
						(arc
							(start -0.2794 0.1778)
							(mid -0.249642 0.249642)
							(end -0.1778 0.2794)
						)
						(arc
							(start 0.1778 0.2794)
							(mid 0.249642 0.249642)
							(end 0.2794 0.1778)
						)
						(arc
							(start 0.2794 -0.1778)
							(mid 0.249642 -0.249642)
							(end 0.1778 -0.2794)
						)
					)
					(width 0)
					(fill yes)
				)
			)
		)
		(pad "2" smd custom
			(at 0 0.4445 270)
			(size 0.1397 0.1397)
			(layers "F.Cu" "F.Mask" "F.Paste")
			(net "GND")
			(options
				(clearance outline)
				(anchor circle)
			)
			(primitives
				(gr_poly
					(pts
						(arc
							(start -0.1778 -0.2794)
							(mid -0.249642 -0.249642)
							(end -0.2794 -0.1778)
						)
						(arc
							(start -0.2794 0.1778)
							(mid -0.249642 0.249642)
							(end -0.1778 0.2794)
						)
						(arc
							(start 0.1778 0.2794)
							(mid 0.249642 0.249642)
							(end 0.2794 0.1778)
						)
						(arc
							(start 0.2794 -0.1778)
							(mid 0.249642 -0.249642)
							(end 0.1778 -0.2794)
						)
					)
					(width 0)
					(fill yes)
				)
			)
		)
	)
	(footprint ""
		(layer "F.Cu")
		(at 2.500122 -210.00466 -90)
		(property "Reference" "CN6"
			(at 0 0 270)
			(layer "F.SilkS")
			(hide yes)
			(effects
				(font
					(size 1.27 1.27)
				)
			)
		)
		(property "Value" "PCISLT36-27-GP"
			(at 5.281422 -7.491476 270)
			(unlocked yes)
			(layer "F.Fab")
			(hide yes)
			(effects
				(font
					(size 1.016 1.016)
					(thickness 0.1524)
				)
			)
		)
		(property "Device Type" "G630H3612248EU"
			(at 5.281422 -9.015476 270)
			(unlocked yes)
			(layer "F.Fab")
			(hide yes)
			(effects
				(font
					(size 1.016 1.016)
					(thickness 0.1524)
				)
			)
		)
		(duplicate_pad_numbers_are_jumpers no)
		(fp_line
			(start -14.899894 2.499868)
			(end -1.450086 2.499868)
			(stroke
				(width 0.1524)
				(type default)
			)
			(layer "F.SilkS")
		)
		(fp_line
			(start -1.450086 2.499868)
			(end -0.94996 1.999742)
			(stroke
				(width 0.1524)
				(type default)
			)
			(layer "F.SilkS")
		)
		(fp_line
			(start 1.450086 2.499868)
			(end 18.899886 2.499868)
			(stroke
				(width 0.1524)
				(type default)
			)
			(layer "F.SilkS")
		)
		(fp_line
			(start 18.899886 2.499868)
			(end 19.400012 1.999742)
			(stroke
				(width 0.1524)
				(type default)
			)
			(layer "F.SilkS")
		)
		(fp_line
			(start -15.40002 1.999742)
			(end -14.899894 2.499868)
			(stroke
				(width 0.1524)
				(type default)
			)
			(layer "F.SilkS")
		)
		(fp_line
			(start -0.94996 1.999742)
			(end -0.94996 -2.55016)
			(stroke
				(width 0.1524)
				(type default)
			)
			(layer "F.SilkS")
		)
		(fp_line
			(start 0.94996 1.999742)
			(end 1.450086 2.499868)
			(stroke
				(width 0.1524)
				(type default)
			)
			(layer "F.SilkS")
		)
		(fp_line
			(start 19.400012 1.999742)
			(end 19.400012 -4.064)
			(stroke
				(width 0.1524)
				(type default)
			)
			(layer "F.SilkS")
		)
		(fp_line
			(start 0.94996 -2.539746)
			(end 0.94996 1.999742)
			(stroke
				(width 0.1524)
				(type default)
			)
			(layer "F.SilkS")
		)
		(fp_line
			(start 0.94996 -2.55016)
			(end 0.94996 -2.539746)
			(stroke
				(width 0.1524)
				(type default)
			)
			(layer "F.SilkS")
		)
		(fp_line
			(start -15.40002 -4.064)
			(end -15.40002 1.999742)
			(stroke
				(width 0.1524)
				(type default)
			)
			(layer "F.SilkS")
		)
		(fp_line
			(start 19.400012 -4.064)
			(end -15.40002 -4.064)
			(stroke
				(width 0.1524)
				(type default)
			)
			(layer "F.SilkS")
		)
		(fp_line
			(start 11.6713 -4.1529)
			(end 11.2903 -4.1529)
			(stroke
				(width 0.3302)
				(type default)
			)
			(layer "F.SilkS")
		)
		(fp_arc
			(start -0.94996 -2.55016)
			(mid 0 -3.50012)
			(end 0.94996 -2.55016)
			(stroke
				(width 0.1524)
				(type default)
			)
			(layer "F.SilkS")
		)
		(fp_poly
			(pts
				(xy 11.474704 -4.1402) (xy 10.966704 -4.6482) (xy 11.982704 -4.6482)
			)
			(stroke
				(width 0)
				(type default)
			)
			(fill yes)
			(layer "F.SilkS")
		)
		(fp_poly
			(pts
				(xy -10.4902 14.986) (xy -10.4902 4.8006) (xy -15.3924 4.8006) (xy -15.3924 -3.81) (xy 19.4056 -3.81)
				(xy 19.4056 4.8006) (xy 14.5034 4.8006) (xy 14.5034 14.986)
			)
			(stroke
				(width 0)
				(type default)
			)
			(fill no)
			(layer "B.CrtYd")
		)
		(fp_poly
			(pts
				(xy -10.9982 15.494) (xy -10.9982 5.3086) (xy -15.9004 5.3086) (xy -15.9004 -4.318) (xy 19.9136 -4.318)
				(xy 19.9136 5.3086) (xy 15.0114 5.3086) (xy 15.0114 15.494) (xy 0.00254 15.494) (xy 0.00254 14.986)
				(xy 14.5034 14.986) (xy 14.5034 4.8006) (xy 19.4056 4.8006) (xy 19.4056 -3.81) (xy -15.3924 -3.81)
				(xy -15.3924 4.8006) (xy -10.4902 4.8006) (xy -10.4902 14.986) (xy -0.00254 14.986) (xy -0.00254 15.494)
			)
			(stroke
				(width 0)
				(type default)
			)
			(fill no)
			(layer "B.CrtYd")
		)
		(fp_poly
			(pts
				(xy -10.4902 14.986) (xy -10.4902 4.8006) (xy -15.3924 4.8006) (xy -15.3924 -3.81) (xy 19.4056 -3.81)
				(xy 19.4056 4.8006) (xy 14.5034 4.8006) (xy 14.5034 14.986)
			)
			(stroke
				(width 0)
				(type default)
			)
			(fill no)
			(layer "F.CrtYd")
		)
		(fp_poly
			(pts
				(xy -10.9982 15.494) (xy -10.9982 5.3086) (xy -15.9004 5.3086) (xy -15.9004 -4.318) (xy 19.9136 -4.318)
				(xy 19.9136 5.3086) (xy 15.0114 5.3086) (xy 15.0114 15.494) (xy 0.00254 15.494) (xy 0.00254 14.986)
				(xy 14.5034 14.986) (xy 14.5034 4.8006) (xy 19.4056 4.8006) (xy 19.4056 -3.81) (xy -15.3924 -3.81)
				(xy -15.3924 4.8006) (xy -10.4902 4.8006) (xy -10.4902 14.986) (xy -0.00254 14.986) (xy -0.00254 15.494)
			)
			(stroke
				(width 0)
				(type default)
			)
			(fill no)
			(layer "F.CrtYd")
		)
		(fp_poly
			(pts
				(xy -10.9982 15.494) (xy -10.9982 5.3086) (xy -15.9004 5.3086) (xy -15.9004 -4.318) (xy 19.9136 -4.318)
				(xy 19.9136 5.3086) (xy 15.0114 5.3086) (xy 15.0114 15.494)
			)
			(stroke
				(width 0)
				(type default)
			)
			(fill no)
			(layer "B.Fab")
		)
		(fp_poly
			(pts
				(xy -10.9982 15.494) (xy -10.9982 5.3086) (xy -15.9004 5.3086) (xy -15.9004 -4.318) (xy 19.9136 -4.318)
				(xy 19.9136 5.3086) (xy 15.0114 5.3086) (xy 15.0114 15.494)
			)
			(stroke
				(width 0)
				(type default)
			)
			(fill no)
			(layer "F.Fab")
		)
		(fp_text user "Slit"
			(at 1.9304 5.260086 270)
			(unlocked yes)
			(layer "F.SilkS")
			(effects
				(font
					(size 0.635 0.635)
					(thickness 0.1524)
				)
				(justify left)
			)
		)
		(pad "" np_thru_hole circle
			(at -12.300204 0 270)
			(size 0.254 0.254)
			(drill 2.3114)
			(layers "*.Cu" "*.Mask")
			(clearance 1.3843)
			(thermal_gap 1.3843)
		)
		(pad "" np_thru_hole circle
			(at 16.299942 0 270)
			(size 0.254 0.254)
			(drill 2.3114)
			(layers "*.Cu" "*.Mask")
			(clearance 1.3843)
			(thermal_gap 1.3843)
		)
		(pad "A1" smd rect
			(at 11.500104 -0.309118 270)
			(size 0.7112 3.6068)
			(drill
				(offset 0 -0.381)
			)
			(layers "F.Cu" "F.Mask" "F.Paste")
			(net "HDD_PRSNT14")
		)
		(pad "A2" smd rect
			(at 10.500106 -0.309118 270)
			(size 0.7112 3.6068)
			(drill
				(offset 0 -0.381)
			)
			(layers "F.Cu" "F.Mask" "F.Paste")
			(net "HDD_PRSNT4")
		)
		(pad "A3" smd rect
			(at 9.500108 -0.309118 270)
			(size 0.7112 3.6068)
			(drill
				(offset 0 -0.381)
			)
			(layers "F.Cu" "F.Mask" "F.Paste")
			(net "HDD_PRSNT9")
		)
		(pad "A4" smd rect
			(at 8.50011 -0.309118 270)
			(size 0.7112 3.6068)
			(drill
				(offset 0 -0.381)
			)
			(layers "F.Cu" "F.Mask" "F.Paste")
			(net "HDD_PRSNT3")
		)
		(pad "A5" smd rect
			(at 7.500112 -0.309118 270)
			(size 0.7112 3.6068)
			(drill
				(offset 0 -0.381)
			)
			(layers "F.Cu" "F.Mask" "F.Paste")
			(net "HDD_PRSNT2")
		)
		(pad "A6" smd rect
			(at 6.500114 -0.309118 270)
			(size 0.7112 3.6068)
			(drill
				(offset 0 -0.381)
			)
			(layers "F.Cu" "F.Mask" "F.Paste")
			(net "HDD_PRSNT8")
		)
		(pad "A7" smd rect
			(at 5.500116 -0.309118 270)
			(size 0.7112 3.6068)
			(drill
				(offset 0 -0.381)
			)
			(layers "F.Cu" "F.Mask" "F.Paste")
			(net "HDD_PRSNT7")
		)
		(pad "A8" smd rect
			(at 4.500118 -0.309118 270)
			(size 0.7112 3.6068)
			(drill
				(offset 0 -0.381)
			)
			(layers "F.Cu" "F.Mask" "F.Paste")
			(net "HDD_PRSNT1")
		)
		(pad "A9" smd rect
			(at 3.50012 -0.309118 270)
			(size 0.7112 3.6068)
			(drill
				(offset 0 -0.381)
			)
			(layers "F.Cu" "F.Mask" "F.Paste")
			(net "HDD_PRSNT0")
		)
		(pad "A10" smd rect
			(at 2.500122 -0.309118 270)
			(size 0.7112 3.6068)
			(drill
				(offset 0 -0.381)
			)
			(layers "F.Cu" "F.Mask" "F.Paste")
			(net "HDD_PRSNT13")
		)
		(pad "A11" smd rect
			(at 1.500124 -0.309118 270)
			(size 0.7112 3.6068)
			(drill
				(offset 0 -0.381)
			)
			(layers "F.Cu" "F.Mask" "F.Paste")
			(net "HDD_PRSNT6")
		)
		(pad "A12" smd rect
			(at -1.500124 -0.309118 270)
			(size 0.7112 3.6068)
			(drill
				(offset 0 -0.381)
			)
			(layers "F.Cu" "F.Mask" "F.Paste")
			(net "HDD_PRSNT5")
		)
		(pad "A13" smd rect
			(at -2.500122 -0.309118 270)
			(size 0.7112 3.6068)
			(drill
				(offset 0 -0.381)
			)
			(layers "F.Cu" "F.Mask" "F.Paste")
			(net "HDD_PRSNT10")
		)
		(pad "A14" smd rect
			(at -3.50012 -0.309118 270)
			(size 0.7112 3.6068)
			(drill
				(offset 0 -0.381)
			)
			(layers "F.Cu" "F.Mask" "F.Paste")
			(net "HDD_PRSNT11")
		)
		(pad "A15" smd rect
			(at -4.500118 -0.309118 270)
			(size 0.7112 3.6068)
			(drill
				(offset 0 -0.381)
			)
			(layers "F.Cu" "F.Mask" "F.Paste")
			(net "HDD_PRSNT12")
		)
		(pad "A16" smd rect
			(at -5.500116 -0.309118 270)
			(size 0.7112 3.6068)
			(drill
				(offset 0 -0.381)
			)
			(layers "F.Cu" "F.Mask" "F.Paste")
			(net "SELF_TRAY_PRESENT")
		)
		(pad "A17" smd rect
			(at -6.500114 -0.309118 270)
			(size 0.7112 3.6068)
			(drill
				(offset 0 -0.381)
			)
			(layers "F.Cu" "F.Mask" "F.Paste")
			(net "PEER_TRAY_PRESENT")
		)
		(pad "A18" smd rect
			(at -7.500112 -0.309118 270)
			(size 0.7112 3.6068)
			(drill
				(offset 0 -0.381)
			)
			(layers "F.Cu" "F.Mask" "F.Paste")
			(net "EXP_B_PRNST_TX")
		)
		(pad "B1" smd rect
			(at 11.500104 -0.690118 270)
			(size 0.7112 3.6068)
			(layers "F.Cu" "F.Mask" "F.Paste")
			(net "SAS_EXP_B_PWR14")
		)
		(pad "B2" smd rect
			(at 10.500106 -0.690118 270)
			(size 0.7112 3.6068)
			(layers "F.Cu" "F.Mask" "F.Paste")
			(net "SAS_EXP_B_PWR4")
		)
		(pad "B3" smd rect
			(at 9.500108 -0.690118 270)
			(size 0.7112 3.6068)
			(layers "F.Cu" "F.Mask" "F.Paste")
			(net "SAS_EXP_B_PWR9")
		)
		(pad "B4" smd rect
			(at 8.50011 -0.690118 270)
			(size 0.7112 3.6068)
			(layers "F.Cu" "F.Mask" "F.Paste")
			(net "SAS_EXP_B_PWR3")
		)
		(pad "B5" smd rect
			(at 7.500112 -0.690118 270)
			(size 0.7112 3.6068)
			(layers "F.Cu" "F.Mask" "F.Paste")
			(net "SAS_EXP_B_PWR2")
		)
		(pad "B6" smd rect
			(at 6.500114 -0.690118 270)
			(size 0.7112 3.6068)
			(layers "F.Cu" "F.Mask" "F.Paste")
			(net "SAS_EXP_B_PWR8")
		)
		(pad "B7" smd rect
			(at 5.500116 -0.690118 270)
			(size 0.7112 3.6068)
			(layers "F.Cu" "F.Mask" "F.Paste")
			(net "SAS_EXP_B_PWR7")
		)
		(pad "B8" smd rect
			(at 4.500118 -0.690118 270)
			(size 0.7112 3.6068)
			(layers "F.Cu" "F.Mask" "F.Paste")
			(net "SAS_EXP_B_PWR1")
		)
		(pad "B9" smd rect
			(at 3.50012 -0.690118 270)
			(size 0.7112 3.6068)
			(layers "F.Cu" "F.Mask" "F.Paste")
			(net "SAS_EXP_B_PWR0")
		)
		(pad "B10" smd rect
			(at 2.500122 -0.690118 270)
			(size 0.7112 3.6068)
			(layers "F.Cu" "F.Mask" "F.Paste")
			(net "SAS_EXP_B_PWR13")
		)
		(pad "B11" smd rect
			(at 1.500124 -0.690118 270)
			(size 0.7112 3.6068)
			(layers "F.Cu" "F.Mask" "F.Paste")
			(net "SAS_EXP_B_PWR6")
		)
		(pad "B12" smd rect
			(at -1.500124 -0.690118 270)
			(size 0.7112 3.6068)
			(layers "F.Cu" "F.Mask" "F.Paste")
			(net "SAS_EXP_B_PWR5")
		)
		(pad "B13" smd rect
			(at -2.500122 -0.690118 270)
			(size 0.7112 3.6068)
			(layers "F.Cu" "F.Mask" "F.Paste")
			(net "SAS_EXP_B_PWR10")
		)
		(pad "B14" smd rect
			(at -3.50012 -0.690118 270)
			(size 0.7112 3.6068)
			(layers "F.Cu" "F.Mask" "F.Paste")
			(net "SAS_EXP_B_PWR11")
		)
		(pad "B15" smd rect
			(at -4.500118 -0.690118 270)
			(size 0.7112 3.6068)
			(layers "F.Cu" "F.Mask" "F.Paste")
			(net "SAS_EXP_B_PWR12")
		)
		(pad "B16" smd rect
			(at -5.500116 -0.690118 270)
			(size 0.7112 3.6068)
			(layers "F.Cu" "F.Mask" "F.Paste")
			(net "SAS_EXP_B_PWR15")
		)
		(pad "B17" smd rect
			(at -6.500114 -0.690118 270)
			(size 0.7112 3.6068)
			(layers "F.Cu" "F.Mask" "F.Paste")
			(net "PCIE_MATED#_B")
		)
		(pad "B18" smd rect
			(at -7.500112 -0.690118 270)
			(size 0.7112 3.6068)
			(layers "F.Cu" "F.Mask" "F.Paste")
			(net "EXP_A_PRNST_RX")
		)
		(zone
			(layers "F.Cu" "B.Cu" "In1.Cu" "In2.Cu" "In3.Cu" "In4.Cu" "In5.Cu" "In6.Cu")
			(hatch none 0.5)
			(connect_pads
				(clearance 0)
			)
			(min_thickness 0.25)
			(keepout
				(tracks not_allowed)
				(vias allowed)
				(pads allowed)
				(copperpour not_allowed)
				(footprints allowed)
			)
			(placement
				(enabled no)
				(sheetname "")
			)
			(fill
				(thermal_gap 0.5)
				(thermal_bridge_width 0.5)
				(island_removal_mode 0)
			)
			(polygon
				(pts
					(arc
						(start 3.960622 -222.304864)
						(mid 1.039622 -222.304864)
						(end 3.960622 -222.304864)
					)
				)
			)
		)
		(zone
			(layers "F.Cu" "B.Cu" "In1.Cu" "In2.Cu" "In3.Cu" "In4.Cu" "In5.Cu" "In6.Cu")
			(hatch none 0.5)
			(connect_pads
				(clearance 0)
			)
			(min_thickness 0.25)
			(keepout
				(tracks not_allowed)
				(vias allowed)
				(pads allowed)
				(copperpour not_allowed)
				(footprints allowed)
			)
			(placement
				(enabled no)
				(sheetname "")
			)
			(fill
				(thermal_gap 0.5)
				(thermal_bridge_width 0.5)
				(island_removal_mode 0)
			)
			(polygon
				(pts
					(arc
						(start 3.960622 -193.704718)
						(mid 1.039622 -193.704718)
						(end 3.960622 -193.704718)
					)
				)
			)
		)
	)
	(footprint ""
		(layer "F.Cu")
		(at 8.5852 -150.6982 90)
		(property "Reference" "R546"
			(at 0 0 90)
			(layer "F.SilkS")
			(hide yes)
			(effects
				(font
					(size 1.27 1.27)
				)
			)
		)
		(property "Value" "0R2J-2-GP"
			(at 0.064008 -3.993896 90)
			(unlocked yes)
			(layer "F.Fab")
			(hide yes)
			(effects
				(font
					(size 1.016 1.016)
					(thickness 0.1524)
				)
			)
		)
		(property "Device Type" "R402H16"
			(at 0.064008 -5.517896 90)
			(unlocked yes)
			(layer "F.Fab")
			(hide yes)
			(effects
				(font
					(size 1.016 1.016)
					(thickness 0.1524)
				)
			)
		)
		(duplicate_pad_numbers_are_jumpers no)
		(fp_line
			(start 0.508 -0.9398)
			(end -0.508 -0.9398)
			(stroke
				(width 0.1524)
				(type default)
			)
			(layer "F.SilkS")
		)
		(fp_line
			(start -0.508 -0.9398)
			(end -0.508 0.9398)
			(stroke
				(width 0.1524)
				(type default)
			)
			(layer "F.SilkS")
		)
		(fp_rect
			(start -0.508 0.9398)
			(end 0.508 -0.9398)
			(stroke
				(width 0)
				(type default)
			)
			(fill no)
			(layer "F.CrtYd")
		)
		(fp_rect
			(start -0.508 0.9398)
			(end 0.508 -0.9398)
			(stroke
				(width 0)
				(type default)
			)
			(fill no)
			(layer "F.Fab")
		)
		(pad "1" smd custom
			(at 0 -0.4445 90)
			(size 0.1397 0.1397)
			(layers "F.Cu" "F.Mask" "F.Paste")
			(net "I2C_C_SCL_DAMP_B")
			(options
				(clearance outline)
				(anchor circle)
			)
			(primitives
				(gr_poly
					(pts
						(arc
							(start -0.1778 -0.2794)
							(mid -0.249642 -0.249642)
							(end -0.2794 -0.1778)
						)
						(arc
							(start -0.2794 0.1778)
							(mid -0.249642 0.249642)
							(end -0.1778 0.2794)
						)
						(arc
							(start 0.1778 0.2794)
							(mid 0.249642 0.249642)
							(end 0.2794 0.1778)
						)
						(arc
							(start 0.2794 -0.1778)
							(mid 0.249642 -0.249642)
							(end 0.1778 -0.2794)
						)
					)
					(width 0)
					(fill yes)
				)
			)
		)
		(pad "2" smd custom
			(at 0 0.4445 90)
			(size 0.1397 0.1397)
			(layers "F.Cu" "F.Mask" "F.Paste")
			(net "I2C_C_SCL")
			(options
				(clearance outline)
				(anchor circle)
			)
			(primitives
				(gr_poly
					(pts
						(arc
							(start -0.1778 -0.2794)
							(mid -0.249642 -0.249642)
							(end -0.2794 -0.1778)
						)
						(arc
							(start -0.2794 0.1778)
							(mid -0.249642 0.249642)
							(end -0.1778 0.2794)
						)
						(arc
							(start 0.1778 0.2794)
							(mid 0.249642 0.249642)
							(end 0.2794 0.1778)
						)
						(arc
							(start 0.2794 -0.1778)
							(mid 0.249642 -0.249642)
							(end 0.1778 -0.2794)
						)
					)
					(width 0)
					(fill yes)
				)
			)
		)
	)
	(footprint ""
		(layer "F.Cu")
		(at 58.927746 -26.6827 -90)
		(property "Reference" "PR22"
			(at 0 0 270)
			(layer "F.SilkS")
			(hide yes)
			(effects
				(font
					(size 1.27 1.27)
				)
			)
		)
		(property "Value" "866KR2F-GP"
			(at 0.064008 -3.993896 270)
			(unlocked yes)
			(layer "F.Fab")
			(hide yes)
			(effects
				(font
					(size 1.016 1.016)
					(thickness 0.1524)
				)
			)
		)
		(property "Device Type" "R402H16"
			(at 0.064008 -5.517896 270)
			(unlocked yes)
			(layer "F.Fab")
			(hide yes)
			(effects
				(font
					(size 1.016 1.016)
					(thickness 0.1524)
				)
			)
		)
		(duplicate_pad_numbers_are_jumpers no)
		(fp_line
			(start -0.508 -0.9398)
			(end -0.508 0.9398)
			(stroke
				(width 0.1524)
				(type default)
			)
			(layer "F.SilkS")
		)
		(fp_line
			(start 0.508 -0.9398)
			(end -0.508 -0.9398)
			(stroke
				(width 0.1524)
				(type default)
			)
			(layer "F.SilkS")
		)
		(fp_rect
			(start -0.508 0.9398)
			(end 0.508 -0.9398)
			(stroke
				(width 0)
				(type default)
			)
			(fill no)
			(layer "F.CrtYd")
		)
		(fp_rect
			(start -0.508 0.9398)
			(end 0.508 -0.9398)
			(stroke
				(width 0)
				(type default)
			)
			(fill no)
			(layer "F.Fab")
		)
		(pad "1" smd custom
			(at 0 -0.4445 270)
			(size 0.1397 0.1397)
			(layers "F.Cu" "F.Mask" "F.Paste")
			(net "P5VB_VREG")
			(options
				(clearance outline)
				(anchor circle)
			)
			(primitives
				(gr_poly
					(pts
						(arc
							(start -0.1778 -0.2794)
							(mid -0.249642 -0.249642)
							(end -0.2794 -0.1778)
						)
						(arc
							(start -0.2794 0.1778)
							(mid -0.249642 0.249642)
							(end -0.1778 0.2794)
						)
						(arc
							(start 0.1778 0.2794)
							(mid 0.249642 0.249642)
							(end 0.2794 0.1778)
						)
						(arc
							(start 0.2794 -0.1778)
							(mid 0.249642 -0.249642)
							(end 0.1778 -0.2794)
						)
					)
					(width 0)
					(fill yes)
				)
			)
		)
		(pad "2" smd custom
			(at 0 0.4445 270)
			(size 0.1397 0.1397)
			(layers "F.Cu" "F.Mask" "F.Paste")
			(net "P5VB_RF")
			(options
				(clearance outline)
				(anchor circle)
			)
			(primitives
				(gr_poly
					(pts
						(arc
							(start -0.1778 -0.2794)
							(mid -0.249642 -0.249642)
							(end -0.2794 -0.1778)
						)
						(arc
							(start -0.2794 0.1778)
							(mid -0.249642 0.249642)
							(end -0.1778 0.2794)
						)
						(arc
							(start 0.1778 0.2794)
							(mid 0.249642 0.249642)
							(end 0.2794 0.1778)
						)
						(arc
							(start 0.2794 -0.1778)
							(mid 0.249642 -0.249642)
							(end 0.1778 -0.2794)
						)
					)
					(width 0)
					(fill yes)
				)
			)
		)
	)
	(footprint ""
		(layer "F.Cu")
		(at 95.757746 -14.4907 90)
		(property "Reference" "R477"
			(at 0 0 90)
			(layer "F.SilkS")
			(hide yes)
			(effects
				(font
					(size 1.27 1.27)
				)
			)
		)
		(property "Value" "4K7R2J-2-GP"
			(at 0.064008 -3.993896 90)
			(unlocked yes)
			(layer "F.Fab")
			(hide yes)
			(effects
				(font
					(size 1.016 1.016)
					(thickness 0.1524)
				)
			)
		)
		(property "Device Type" "R402H16"
			(at 0.064008 -5.517896 90)
			(unlocked yes)
			(layer "F.Fab")
			(hide yes)
			(effects
				(font
					(size 1.016 1.016)
					(thickness 0.1524)
				)
			)
		)
		(duplicate_pad_numbers_are_jumpers no)
		(fp_line
			(start 0.508 -0.9398)
			(end -0.508 -0.9398)
			(stroke
				(width 0.1524)
				(type default)
			)
			(layer "F.SilkS")
		)
		(fp_line
			(start -0.508 -0.9398)
			(end -0.508 0.9398)
			(stroke
				(width 0.1524)
				(type default)
			)
			(layer "F.SilkS")
		)
		(fp_rect
			(start -0.508 0.9398)
			(end 0.508 -0.9398)
			(stroke
				(width 0)
				(type default)
			)
			(fill no)
			(layer "F.CrtYd")
		)
		(fp_rect
			(start -0.508 0.9398)
			(end 0.508 -0.9398)
			(stroke
				(width 0)
				(type default)
			)
			(fill no)
			(layer "F.Fab")
		)
		(pad "1" smd custom
			(at 0 -0.4445 90)
			(size 0.1397 0.1397)
			(layers "F.Cu" "F.Mask" "F.Paste")
			(net "P3V3")
			(options
				(clearance outline)
				(anchor circle)
			)
			(primitives
				(gr_poly
					(pts
						(arc
							(start -0.1778 -0.2794)
							(mid -0.249642 -0.249642)
							(end -0.2794 -0.1778)
						)
						(arc
							(start -0.2794 0.1778)
							(mid -0.249642 0.249642)
							(end -0.1778 0.2794)
						)
						(arc
							(start 0.1778 0.2794)
							(mid 0.249642 0.249642)
							(end 0.2794 0.1778)
						)
						(arc
							(start 0.2794 -0.1778)
							(mid 0.249642 -0.249642)
							(end 0.1778 -0.2794)
						)
					)
					(width 0)
					(fill yes)
				)
			)
		)
		(pad "2" smd custom
			(at 0 0.4445 90)
			(size 0.1397 0.1397)
			(layers "F.Cu" "F.Mask" "F.Paste")
			(net "SAS_EXP_B_PWR14")
			(options
				(clearance outline)
				(anchor circle)
			)
			(primitives
				(gr_poly
					(pts
						(arc
							(start -0.1778 -0.2794)
							(mid -0.249642 -0.249642)
							(end -0.2794 -0.1778)
						)
						(arc
							(start -0.2794 0.1778)
							(mid -0.249642 0.249642)
							(end -0.1778 0.2794)
						)
						(arc
							(start 0.1778 0.2794)
							(mid 0.249642 0.249642)
							(end 0.2794 0.1778)
						)
						(arc
							(start 0.2794 -0.1778)
							(mid 0.249642 -0.249642)
							(end 0.1778 -0.2794)
						)
					)
					(width 0)
					(fill yes)
				)
			)
		)
	)
	(footprint ""
		(layer "F.Cu")
		(at 165.112446 -458.123036 90)
		(property "Reference" "R373"
			(at 0 0 90)
			(layer "F.SilkS")
			(hide yes)
			(effects
				(font
					(size 1.27 1.27)
				)
			)
		)
		(property "Value" "0R2J-2-GP"
			(at 0.064008 -3.993896 90)
			(unlocked yes)
			(layer "F.Fab")
			(hide yes)
			(effects
				(font
					(size 1.016 1.016)
					(thickness 0.1524)
				)
			)
		)
		(property "Device Type" "R402H16"
			(at 0.064008 -5.517896 90)
			(unlocked yes)
			(layer "F.Fab")
			(hide yes)
			(effects
				(font
					(size 1.016 1.016)
					(thickness 0.1524)
				)
			)
		)
		(duplicate_pad_numbers_are_jumpers no)
		(fp_line
			(start 0.508 -0.9398)
			(end -0.508 -0.9398)
			(stroke
				(width 0.1524)
				(type default)
			)
			(layer "F.SilkS")
		)
		(fp_line
			(start -0.508 -0.9398)
			(end -0.508 0.9398)
			(stroke
				(width 0.1524)
				(type default)
			)
			(layer "F.SilkS")
		)
		(fp_rect
			(start -0.508 0.9398)
			(end 0.508 -0.9398)
			(stroke
				(width 0)
				(type default)
			)
			(fill no)
			(layer "F.CrtYd")
		)
		(fp_rect
			(start -0.508 0.9398)
			(end 0.508 -0.9398)
			(stroke
				(width 0)
				(type default)
			)
			(fill no)
			(layer "F.Fab")
		)
		(pad "1" smd custom
			(at 0 -0.4445 90)
			(size 0.1397 0.1397)
			(layers "F.Cu" "F.Mask" "F.Paste")
			(net "P5VA_DIV")
			(options
				(clearance outline)
				(anchor circle)
			)
			(primitives
				(gr_poly
					(pts
						(arc
							(start -0.1778 -0.2794)
							(mid -0.249642 -0.249642)
							(end -0.2794 -0.1778)
						)
						(arc
							(start -0.2794 0.1778)
							(mid -0.249642 0.249642)
							(end -0.1778 0.2794)
						)
						(arc
							(start 0.1778 0.2794)
							(mid 0.249642 0.249642)
							(end 0.2794 0.1778)
						)
						(arc
							(start 0.2794 -0.1778)
							(mid 0.249642 -0.249642)
							(end 0.1778 -0.2794)
						)
					)
					(width 0)
					(fill yes)
				)
			)
		)
		(pad "2" smd custom
			(at 0 0.4445 90)
			(size 0.1397 0.1397)
			(layers "F.Cu" "F.Mask" "F.Paste")
			(net "P5VA_SENSE")
			(options
				(clearance outline)
				(anchor circle)
			)
			(primitives
				(gr_poly
					(pts
						(arc
							(start -0.1778 -0.2794)
							(mid -0.249642 -0.249642)
							(end -0.2794 -0.1778)
						)
						(arc
							(start -0.2794 0.1778)
							(mid -0.249642 0.249642)
							(end -0.1778 0.2794)
						)
						(arc
							(start 0.1778 0.2794)
							(mid 0.249642 0.249642)
							(end 0.2794 0.1778)
						)
						(arc
							(start 0.2794 -0.1778)
							(mid 0.249642 -0.249642)
							(end 0.1778 -0.2794)
						)
					)
					(width 0)
					(fill yes)
				)
			)
		)
	)
	(footprint ""
		(layer "F.Cu")
		(at 219.184982 -291.183568 180)
		(property "Reference" "C146"
			(at 0 0 180)
			(layer "F.SilkS")
			(hide yes)
			(effects
				(font
					(size 1.27 1.27)
				)
			)
		)
		(property "Value" "SC1U25V3KX-1-GP"
			(at 0 -2.8194 180)
			(unlocked yes)
			(layer "F.Fab")
			(hide yes)
			(effects
				(font
					(size 1.016 1.016)
					(thickness 0.1524)
				)
			)
		)
		(property "Device Type" "C603H36"
			(at 0 -4.3434 180)
			(unlocked yes)
			(layer "F.Fab")
			(hide yes)
			(effects
				(font
					(size 1.016 1.016)
					(thickness 0.1524)
				)
			)
		)
		(duplicate_pad_numbers_are_jumpers no)
		(fp_line
			(start 0.508 0)
			(end -0.508 0)
			(stroke
				(width 0.2032)
				(type default)
			)
			(layer "F.SilkS")
		)
		(fp_rect
			(start -0.5842 1.3335)
			(end 0.5842 -1.3335)
			(stroke
				(width 0)
				(type default)
			)
			(fill no)
			(layer "F.CrtYd")
		)
		(fp_rect
			(start -0.5842 1.3335)
			(end 0.5842 -1.3335)
			(stroke
				(width 0)
				(type default)
			)
			(fill no)
			(layer "F.Fab")
		)
		(pad "1" smd custom
			(at 0 -0.762 180)
			(size 0.2159 0.2159)
			(layers "F.Cu" "F.Mask" "F.Paste")
			(net "P12V_HDD2")
			(options
				(clearance outline)
				(anchor circle)
			)
			(primitives
				(gr_poly
					(pts
						(arc
							(start -0.3302 -0.4318)
							(mid -0.402042 -0.402042)
							(end -0.4318 -0.3302)
						)
						(arc
							(start -0.4318 0.3302)
							(mid -0.402042 0.402042)
							(end -0.3302 0.4318)
						)
						(arc
							(start 0.3302 0.4318)
							(mid 0.402042 0.402042)
							(end 0.4318 0.3302)
						)
						(arc
							(start 0.4318 -0.3302)
							(mid 0.402042 -0.402042)
							(end 0.3302 -0.4318)
						)
					)
					(width 0)
					(fill yes)
				)
			)
		)
		(pad "2" smd custom
			(at 0 0.762 180)
			(size 0.2159 0.2159)
			(layers "F.Cu" "F.Mask" "F.Paste")
			(net "GND")
			(options
				(clearance outline)
				(anchor circle)
			)
			(primitives
				(gr_poly
					(pts
						(arc
							(start -0.3302 -0.4318)
							(mid -0.402042 -0.402042)
							(end -0.4318 -0.3302)
						)
						(arc
							(start -0.4318 0.3302)
							(mid -0.402042 0.402042)
							(end -0.3302 0.4318)
						)
						(arc
							(start 0.3302 0.4318)
							(mid 0.402042 0.402042)
							(end 0.4318 0.3302)
						)
						(arc
							(start 0.4318 -0.3302)
							(mid 0.402042 -0.402042)
							(end 0.3302 -0.4318)
						)
					)
					(width 0)
					(fill yes)
				)
			)
		)
	)
	(footprint ""
		(layer "F.Cu")
		(at 227.499926 -170.669966 90)
		(property "Reference" "SKT4"
			(at 0 0 90)
			(layer "F.SilkS")
			(hide yes)
			(effects
				(font
					(size 1.27 1.27)
				)
			)
		)
		(property "Value" "SKT-SATA14P-15P-12-GP"
			(at -22.6187 8.1788 90)
			(unlocked yes)
			(layer "F.Fab")
			(hide yes)
			(effects
				(font
					(size 1.016 1.016)
					(thickness 0.1524)
				)
			)
		)
		(property "Device Type" "87945-1001"
			(at -22.6187 6.6548 90)
			(unlocked yes)
			(layer "F.Fab")
			(hide yes)
			(effects
				(font
					(size 1.016 1.016)
					(thickness 0.1524)
				)
			)
		)
		(duplicate_pad_numbers_are_jumpers no)
		(fp_line
			(start -15.3924 -5.8547)
			(end -16.3576 -5.8547)
			(stroke
				(width 0.3302)
				(type default)
			)
			(layer "F.SilkS")
		)
		(fp_line
			(start 20.4724 -5.7658)
			(end 20.4724 -2.3114)
			(stroke
				(width 0.1524)
				(type default)
			)
			(layer "F.SilkS")
		)
		(fp_line
			(start -20.4724 -5.7658)
			(end 20.4724 -5.7658)
			(stroke
				(width 0.1524)
				(type default)
			)
			(layer "F.SilkS")
		)
		(fp_line
			(start 23.7617 -2.3114)
			(end 23.7617 2.3114)
			(stroke
				(width 0.1524)
				(type default)
			)
			(layer "F.SilkS")
		)
		(fp_line
			(start 20.4724 -2.3114)
			(end 23.7617 -2.3114)
			(stroke
				(width 0.1524)
				(type default)
			)
			(layer "F.SilkS")
		)
		(fp_line
			(start -20.4724 -2.3114)
			(end -20.4724 -5.7658)
			(stroke
				(width 0.1524)
				(type default)
			)
			(layer "F.SilkS")
		)
		(fp_line
			(start -23.7617 -2.3114)
			(end -20.4724 -2.3114)
			(stroke
				(width 0.1524)
				(type default)
			)
			(layer "F.SilkS")
		)
		(fp_line
			(start 23.117556 -0.5461)
			(end 23.117556 0.5461)
			(stroke
				(width 0.3048)
				(type default)
			)
			(layer "F.SilkS")
		)
		(fp_line
			(start -20.882356 -0.5461)
			(end -20.882356 0.5461)
			(stroke
				(width 0.3048)
				(type default)
			)
			(layer "F.SilkS")
		)
		(fp_line
			(start 20.882356 0.5461)
			(end 20.882356 -0.5461)
			(stroke
				(width 0.3048)
				(type default)
			)
			(layer "F.SilkS")
		)
		(fp_line
			(start -23.117556 0.5461)
			(end -23.117556 -0.5461)
			(stroke
				(width 0.3048)
				(type default)
			)
			(layer "F.SilkS")
		)
		(fp_line
			(start 23.7617 2.3114)
			(end 20.4724 2.3114)
			(stroke
				(width 0.1524)
				(type default)
			)
			(layer "F.SilkS")
		)
		(fp_line
			(start 20.4724 2.3114)
			(end 20.4724 9.652)
			(stroke
				(width 0.1524)
				(type default)
			)
			(layer "F.SilkS")
		)
		(fp_line
			(start -20.4724 2.3114)
			(end -23.7617 2.3114)
			(stroke
				(width 0.1524)
				(type default)
			)
			(layer "F.SilkS")
		)
		(fp_line
			(start -23.7617 2.3114)
			(end -23.7617 -2.3114)
			(stroke
				(width 0.1524)
				(type default)
			)
			(layer "F.SilkS")
		)
		(fp_line
			(start 17.8435 7.9502)
			(end -17.8435 7.9502)
			(stroke
				(width 0.1524)
				(type default)
			)
			(layer "F.SilkS")
		)
		(fp_line
			(start -17.8435 7.9502)
			(end -17.8435 9.652)
			(stroke
				(width 0.1524)
				(type default)
			)
			(layer "F.SilkS")
		)
		(fp_line
			(start 20.4724 9.652)
			(end 17.8435 9.652)
			(stroke
				(width 0.1524)
				(type default)
			)
			(layer "F.SilkS")
		)
		(fp_line
			(start 17.8435 9.652)
			(end 17.8435 7.9502)
			(stroke
				(width 0.1524)
				(type default)
			)
			(layer "F.SilkS")
		)
		(fp_line
			(start -17.8435 9.652)
			(end -20.4724 9.652)
			(stroke
				(width 0.1524)
				(type default)
			)
			(layer "F.SilkS")
		)
		(fp_line
			(start -20.4724 9.652)
			(end -20.4724 2.3114)
			(stroke
				(width 0.1524)
				(type default)
			)
			(layer "F.SilkS")
		)
		(fp_arc
			(start 20.882356 -0.5461)
			(mid 21.999956 -1.6637)
			(end 23.117556 -0.5461)
			(stroke
				(width 0.3048)
				(type default)
			)
			(layer "F.SilkS")
		)
		(fp_arc
			(start -23.117556 -0.5461)
			(mid -21.999956 -1.6637)
			(end -20.882356 -0.5461)
			(stroke
				(width 0.3048)
				(type default)
			)
			(layer "F.SilkS")
		)
		(fp_arc
			(start 23.117556 0.5461)
			(mid 21.999956 1.6637)
			(end 20.882356 0.5461)
			(stroke
				(width 0.3048)
				(type default)
			)
			(layer "F.SilkS")
		)
		(fp_arc
			(start -20.882356 0.5461)
			(mid -21.999956 1.6637)
			(end -23.117556 0.5461)
			(stroke
				(width 0.3048)
				(type default)
			)
			(layer "F.SilkS")
		)
		(fp_poly
			(pts
				(xy -15.87119 -5.838698) (xy -15.23619 -6.473698) (xy -16.50619 -6.473698)
			)
			(stroke
				(width 0)
				(type default)
			)
			(fill yes)
			(layer "F.SilkS")
		)
		(fp_poly
			(pts
				(xy -20.2184 -5.5118) (xy 20.2184 -5.5118) (xy 20.2184 -2.0574) (xy 23.5077 -2.0574) (xy 23.5077 2.0574)
				(xy 20.2184 2.0574) (xy 20.2184 9.398) (xy 18.0975 9.398) (xy 18.0975 7.6962) (xy -18.0975 7.6962)
				(xy -18.0975 9.398) (xy -20.2184 9.398) (xy -20.2184 2.0574) (xy -23.5077 2.0574) (xy -23.5077 -2.0574)
				(xy -20.2184 -2.0574)
			)
			(stroke
				(width 0)
				(type default)
			)
			(fill no)
			(layer "F.CrtYd")
		)
		(fp_poly
			(pts
				(xy -20.2184 -5.5118) (xy -20.2184 -6.0198) (xy -20.7264 -6.0198) (xy -20.7264 -2.5654) (xy -24.0157 -2.5654)
				(xy -24.0157 2.5654) (xy -20.7264 2.5654) (xy -20.7264 9.906) (xy -17.5895 9.906) (xy -17.5895 8.2042)
				(xy 17.5895 8.2042) (xy 17.5895 9.906) (xy 20.7264 9.906) (xy 20.7264 2.5654) (xy 24.0157 2.5654)
				(xy 24.0157 -2.5654) (xy 20.7264 -2.5654) (xy 20.7264 -6.0198) (xy -20.21586 -6.0198) (xy -20.21586 -5.5118)
				(xy 20.2184 -5.5118) (xy 20.2184 -2.0574) (xy 23.5077 -2.0574) (xy 23.5077 2.0574) (xy 20.2184 2.0574)
				(xy 20.2184 9.398) (xy 18.0975 9.398) (xy 18.0975 7.6962) (xy -18.0975 7.6962) (xy -18.0975 9.398)
				(xy -20.2184 9.398) (xy -20.2184 2.0574) (xy -23.5077 2.0574) (xy -23.5077 -2.0574) (xy -20.2184 -2.0574)
			)
			(stroke
				(width 0)
				(type default)
			)
			(fill no)
			(layer "F.CrtYd")
		)
		(fp_poly
			(pts
				(xy -20.7264 -6.0198) (xy -20.7264 -2.5654) (xy -24.0157 -2.5654) (xy -24.0157 2.5654) (xy -20.7264 2.5654)
				(xy -20.7264 9.906) (xy -17.5895 9.906) (xy -17.5895 8.2042) (xy 17.5895 8.2042) (xy 17.5895 9.906)
				(xy 20.7264 9.906) (xy 20.7264 2.5654) (xy 24.0157 2.5654) (xy 24.0157 -2.5654) (xy 20.7264 -2.5654)
				(xy 20.7264 -6.0198)
			)
			(stroke
				(width 0)
				(type default)
			)
			(fill no)
			(layer "F.Fab")
		)
		(pad "" np_thru_hole circle
			(at -18.999962 -2.350008 90)
			(size 0.254 0.254)
			(drill 1.8542)
			(layers "*.Cu" "*.Mask")
			(clearance 1.1557)
			(thermal_gap 1.1557)
		)
		(pad "" np_thru_hole circle
			(at 18.999962 -2.350008 90)
			(size 0.254 0.254)
			(drill 1.8542)
			(layers "*.Cu" "*.Mask")
			(clearance 1.1557)
			(thermal_gap 1.1557)
		)
		(pad "H1" thru_hole oval
			(at -21.999956 0 90)
			(size 1.524 2.6162)
			(drill oval 0.8128 1.905)
			(layers "*.Cu" "*.Mask")
			(remove_unused_layers no)
			(net "GND")
			(clearance 0.1524)
			(thermal_gap 0.1524)
		)
		(pad "H2" thru_hole oval
			(at 21.999956 0 90)
			(size 1.524 2.6162)
			(drill oval 0.8128 1.905)
			(layers "*.Cu" "*.Mask")
			(remove_unused_layers no)
			(net "GND")
			(clearance 0.1524)
			(thermal_gap 0.1524)
		)
		(pad "P1" smd rect
			(at -1.89992 -4.249928 90)
			(size 0.6604 2.3876)
			(layers "F.Cu" "F.Mask" "F.Paste")
			(net "Net_30")
		)
		(pad "P2" smd rect
			(at -0.62992 -4.249928 90)
			(size 0.6604 2.3876)
			(layers "F.Cu" "F.Mask" "F.Paste")
			(net "Net_29")
		)
		(pad "P3" smd rect
			(at 0.64008 -4.249928 90)
			(size 0.6604 2.3876)
			(layers "F.Cu" "F.Mask" "F.Paste")
			(net "Net_28")
		)
		(pad "P4" smd rect
			(at 1.91008 -4.249928 90)
			(size 0.6604 2.3876)
			(layers "F.Cu" "F.Mask" "F.Paste")
			(net "GND")
		)
		(pad "P5" smd rect
			(at 3.18008 -4.249928 90)
			(size 0.6604 2.3876)
			(layers "F.Cu" "F.Mask" "F.Paste")
			(net "HDD_PRSNT_NET3")
		)
		(pad "P6" smd rect
			(at 4.45008 -4.249928 90)
			(size 0.6604 2.3876)
			(layers "F.Cu" "F.Mask" "F.Paste")
			(net "GND")
		)
		(pad "P7" smd rect
			(at 5.72008 -4.249928 90)
			(size 0.6604 2.3876)
			(layers "F.Cu" "F.Mask" "F.Paste")
			(net "5V_PRE_3")
		)
		(pad "P8" smd rect
			(at 6.99008 -4.249928 90)
			(size 0.6604 2.3876)
			(layers "F.Cu" "F.Mask" "F.Paste")
			(net "P5V_HDD3")
		)
		(pad "P9" smd rect
			(at 8.26008 -4.249928 90)
			(size 0.6604 2.3876)
			(layers "F.Cu" "F.Mask" "F.Paste")
			(net "P5V_HDD3")
		)
		(pad "P10" smd rect
			(at 9.53008 -4.249928 90)
			(size 0.6604 2.3876)
			(layers "F.Cu" "F.Mask" "F.Paste")
			(net "GND")
		)
		(pad "P11" smd rect
			(at 10.80008 -4.249928 90)
			(size 0.6604 2.3876)
			(layers "F.Cu" "F.Mask" "F.Paste")
			(net "ACT_HDD3")
		)
		(pad "P12" smd rect
			(at 12.07008 -4.249928 90)
			(size 0.6604 2.3876)
			(layers "F.Cu" "F.Mask" "F.Paste")
			(net "GND")
		)
		(pad "P13" smd rect
			(at 13.34008 -4.249928 90)
			(size 0.6604 2.3876)
			(layers "F.Cu" "F.Mask" "F.Paste")
			(net "12V_PRE_3")
		)
		(pad "P14" smd rect
			(at 14.61008 -4.249928 90)
			(size 0.6604 2.3876)
			(layers "F.Cu" "F.Mask" "F.Paste")
			(net "P12V_HDD3")
		)
		(pad "P15" smd rect
			(at 15.88008 -4.249928 90)
			(size 0.6604 2.3876)
			(layers "F.Cu" "F.Mask" "F.Paste")
			(net "P12V_HDD3")
		)
		(pad "S1" smd rect
			(at -15.86992 -4.249928 90)
			(size 0.6604 2.3876)
			(layers "F.Cu" "F.Mask" "F.Paste")
			(net "GND")
		)
		(pad "S2" smd rect
			(at -14.59992 -4.249928 90)
			(size 0.6604 2.3876)
			(layers "F.Cu" "F.Mask" "F.Paste")
			(net "SAS2X28_A_HDD3_TX_+")
		)
		(pad "S3" smd rect
			(at -13.32992 -4.249928 90)
			(size 0.6604 2.3876)
			(layers "F.Cu" "F.Mask" "F.Paste")
			(net "SAS2X28_A_HDD3_TX_-")
		)
		(pad "S4" smd rect
			(at -12.05992 -4.249928 90)
			(size 0.6604 2.3876)
			(layers "F.Cu" "F.Mask" "F.Paste")
			(net "GND")
		)
		(pad "S5" smd rect
			(at -10.78992 -4.249928 90)
			(size 0.6604 2.3876)
			(layers "F.Cu" "F.Mask" "F.Paste")
			(net "SAS2X28_DRIVE_RX_N_A3")
		)
		(pad "S6" smd rect
			(at -9.51992 -4.249928 90)
			(size 0.6604 2.3876)
			(layers "F.Cu" "F.Mask" "F.Paste")
			(net "SAS2X28_DRIVE_RX_P_A3")
		)
		(pad "S7" smd rect
			(at -8.24992 -4.249928 90)
			(size 0.6604 2.3876)
			(layers "F.Cu" "F.Mask" "F.Paste")
			(net "GND")
		)
		(pad "S8" smd rect
			(at -7.480046 -2.100072 90)
			(size 0.508 1.905)
			(layers "F.Cu" "F.Mask" "F.Paste")
			(net "GND")
		)
		(pad "S9" smd rect
			(at -6.679946 -2.100072 90)
			(size 0.508 1.905)
			(layers "F.Cu" "F.Mask" "F.Paste")
			(net "SAS2X28_B_HDD3_TX_+")
		)
		(pad "S10" smd rect
			(at -5.8801 -2.100072 90)
			(size 0.508 1.905)
			(layers "F.Cu" "F.Mask" "F.Paste")
			(net "SAS2X28_B_HDD3_TX_-")
		)
		(pad "S11" smd rect
			(at -5.08 -2.100072 90)
			(size 0.508 1.905)
			(layers "F.Cu" "F.Mask" "F.Paste")
			(net "GND")
		)
		(pad "S12" smd rect
			(at -4.2799 -2.100072 90)
			(size 0.508 1.905)
			(layers "F.Cu" "F.Mask" "F.Paste")
			(net "SAS2X28_DRIVE_RX_N_B3")
		)
		(pad "S13" smd rect
			(at -3.480054 -2.100072 90)
			(size 0.508 1.905)
			(layers "F.Cu" "F.Mask" "F.Paste")
			(net "SAS2X28_DRIVE_RX_P_B3")
		)
		(pad "S14" smd rect
			(at -2.679954 -2.100072 90)
			(size 0.508 1.905)
			(layers "F.Cu" "F.Mask" "F.Paste")
			(net "GND")
		)
		(zone
			(layers "F.Cu" "B.Cu" "In1.Cu" "In2.Cu" "In3.Cu" "In4.Cu" "In5.Cu" "In6.Cu")
			(hatch none 0.5)
			(connect_pads
				(clearance 0)
			)
			(min_thickness 0.25)
			(keepout
				(tracks not_allowed)
				(vias allowed)
				(pads allowed)
				(copperpour not_allowed)
				(footprints allowed)
			)
			(placement
				(enabled no)
				(sheetname "")
			)
			(fill
				(thermal_gap 0.5)
				(thermal_bridge_width 0.5)
				(island_removal_mode 0)
			)
			(polygon
				(pts
					(arc
						(start 226.381818 -189.669928)
						(mid 223.918018 -189.669928)
						(end 226.381818 -189.669928)
					)
				)
			)
		)
		(zone
			(layers "F.Cu" "B.Cu" "In1.Cu" "In2.Cu" "In3.Cu" "In4.Cu" "In5.Cu" "In6.Cu")
			(hatch none 0.5)
			(connect_pads
				(clearance 0)
			)
			(min_thickness 0.25)
			(keepout
				(tracks not_allowed)
				(vias allowed)
				(pads allowed)
				(copperpour not_allowed)
				(footprints allowed)
			)
			(placement
				(enabled no)
				(sheetname "")
			)
			(fill
				(thermal_gap 0.5)
				(thermal_bridge_width 0.5)
				(island_removal_mode 0)
			)
			(polygon
				(pts
					(arc
						(start 226.381818 -151.670004)
						(mid 223.918018 -151.670004)
						(end 226.381818 -151.670004)
					)
				)
			)
		)
	)
	(footprint ""
		(layer "F.Cu")
		(at 26.796746 -425.732702)
		(property "Reference" "C266"
			(at 0 0 0)
			(layer "F.SilkS")
			(hide yes)
			(effects
				(font
					(size 1.27 1.27)
				)
			)
		)
		(property "Value" "SC1U16V3KX-5GP"
			(at 0 -2.8194 0)
			(unlocked yes)
			(layer "F.Fab")
			(hide yes)
			(effects
				(font
					(size 1.016 1.016)
					(thickness 0.1524)
				)
			)
		)
		(property "Device Type" "C603H36"
			(at 0 -4.3434 0)
			(unlocked yes)
			(layer "F.Fab")
			(hide yes)
			(effects
				(font
					(size 1.016 1.016)
					(thickness 0.1524)
				)
			)
		)
		(duplicate_pad_numbers_are_jumpers no)
		(fp_line
			(start 0.508 0)
			(end -0.508 0)
			(stroke
				(width 0.2032)
				(type default)
			)
			(layer "F.SilkS")
		)
		(fp_rect
			(start -0.5842 1.3335)
			(end 0.5842 -1.3335)
			(stroke
				(width 0)
				(type default)
			)
			(fill no)
			(layer "F.CrtYd")
		)
		(fp_rect
			(start -0.5842 1.3335)
			(end 0.5842 -1.3335)
			(stroke
				(width 0)
				(type default)
			)
			(fill no)
			(layer "F.Fab")
		)
		(pad "1" smd custom
			(at 0 -0.762)
			(size 0.2159 0.2159)
			(layers "F.Cu" "F.Mask" "F.Paste")
			(net "P5V_HDD10")
			(options
				(clearance outline)
				(anchor circle)
			)
			(primitives
				(gr_poly
					(pts
						(arc
							(start -0.3302 -0.4318)
							(mid -0.402042 -0.402042)
							(end -0.4318 -0.3302)
						)
						(arc
							(start -0.4318 0.3302)
							(mid -0.402042 0.402042)
							(end -0.3302 0.4318)
						)
						(arc
							(start 0.3302 0.4318)
							(mid 0.402042 0.402042)
							(end 0.4318 0.3302)
						)
						(arc
							(start 0.4318 -0.3302)
							(mid 0.402042 -0.402042)
							(end 0.3302 -0.4318)
						)
					)
					(width 0)
					(fill yes)
				)
			)
		)
		(pad "2" smd custom
			(at 0 0.762)
			(size 0.2159 0.2159)
			(layers "F.Cu" "F.Mask" "F.Paste")
			(net "GND")
			(options
				(clearance outline)
				(anchor circle)
			)
			(primitives
				(gr_poly
					(pts
						(arc
							(start -0.3302 -0.4318)
							(mid -0.402042 -0.402042)
							(end -0.4318 -0.3302)
						)
						(arc
							(start -0.4318 0.3302)
							(mid -0.402042 0.402042)
							(end -0.3302 0.4318)
						)
						(arc
							(start 0.3302 0.4318)
							(mid 0.402042 0.402042)
							(end 0.4318 0.3302)
						)
						(arc
							(start 0.4318 -0.3302)
							(mid 0.402042 -0.402042)
							(end 0.3302 -0.4318)
						)
					)
					(width 0)
					(fill yes)
				)
			)
		)
	)
	(footprint ""
		(layer "F.Cu")
		(at 30.606746 -436.2577 90)
		(property "Reference" "U31"
			(at 0 0 90)
			(layer "F.SilkS")
			(hide yes)
			(effects
				(font
					(size 1.27 1.27)
				)
			)
		)
		(property "Value" "74LVC1G08GW-1-GP"
			(at -2.3368 -8.6868 90)
			(unlocked yes)
			(layer "F.Fab")
			(hide yes)
			(effects
				(font
					(size 1.016 1.016)
					(thickness 0.1524)
				)
			)
		)
		(property "Device Type" "SC70-5H44"
			(at -2.3114 -10.414 90)
			(unlocked yes)
			(layer "F.Fab")
			(hide yes)
			(effects
				(font
					(size 1.016 1.016)
					(thickness 0.1524)
				)
			)
		)
		(duplicate_pad_numbers_are_jumpers no)
		(fp_line
			(start 1.3843 -1.8034)
			(end 1.3843 -1.1176)
			(stroke
				(width 0.3302)
				(type default)
			)
			(layer "F.SilkS")
		)
		(fp_line
			(start 0.6604 -1.8034)
			(end 1.3843 -1.8034)
			(stroke
				(width 0.3302)
				(type default)
			)
			(layer "F.SilkS")
		)
		(fp_line
			(start 1.27 -1.7018)
			(end 1.27 1.7018)
			(stroke
				(width 0.1524)
				(type default)
			)
			(layer "F.SilkS")
		)
		(fp_line
			(start -1.27 -1.7018)
			(end 1.27 -1.7018)
			(stroke
				(width 0.1524)
				(type default)
			)
			(layer "F.SilkS")
		)
		(fp_line
			(start 1.27 1.7018)
			(end -1.27 1.7018)
			(stroke
				(width 0.1524)
				(type default)
			)
			(layer "F.SilkS")
		)
		(fp_line
			(start -1.27 1.7018)
			(end -1.27 -1.7018)
			(stroke
				(width 0.1524)
				(type default)
			)
			(layer "F.SilkS")
		)
		(fp_rect
			(start -1.524 1.9558)
			(end 1.524 -1.9558)
			(stroke
				(width 0)
				(type default)
			)
			(fill no)
			(layer "F.CrtYd")
		)
		(fp_poly
			(pts
				(xy -1.524 -1.9558) (xy 1.524 -1.9558) (xy 1.524 1.9558) (xy -1.524 1.9558)
			)
			(stroke
				(width 0)
				(type default)
			)
			(fill no)
			(layer "F.Fab")
		)
		(pad "1" smd rect
			(at 0.65024 -0.8255 90)
			(size 0.4064 1.2192)
			(layers "F.Cu" "F.Mask" "F.Paste")
			(net "SAS2X28_B_HDD10_FLT")
		)
		(pad "2" smd rect
			(at 0 -0.8255 90)
			(size 0.4064 1.2192)
			(layers "F.Cu" "F.Mask" "F.Paste")
			(net "SAS2X28_A_HDD10_FLT")
		)
		(pad "3" smd rect
			(at -0.65024 -0.8255 90)
			(size 0.4064 1.2192)
			(layers "F.Cu" "F.Mask" "F.Paste")
			(net "GND")
		)
		(pad "4" smd rect
			(at -0.65024 0.8255 90)
			(size 0.4064 1.2192)
			(layers "F.Cu" "F.Mask" "F.Paste")
			(net "FLT_HDD10_DRIVE")
		)
		(pad "5" smd rect
			(at 0.65024 0.8255 90)
			(size 0.4064 1.2192)
			(layers "F.Cu" "F.Mask" "F.Paste")
			(net "P3V3")
		)
	)
	(footprint ""
		(layer "F.Cu")
		(at 11.269472 -494.464848 180)
		(property "Reference" "PU3"
			(at 0 0 180)
			(layer "F.SilkS")
			(hide yes)
			(effects
				(font
					(size 1.27 1.27)
				)
			)
		)
		(property "Value" "TPS53319DQPR-GP"
			(at 4.7498 -5.6896 180)
			(unlocked yes)
			(layer "F.Fab")
			(hide yes)
			(effects
				(font
					(size 1.016 1.016)
					(thickness 0.1524)
				)
			)
		)
		(property "Device Type" "QFN22G6050-G6133H60"
			(at 4.7498 -7.2136 180)
			(unlocked yes)
			(layer "F.Fab")
			(hide yes)
			(effects
				(font
					(size 1.016 1.016)
					(thickness 0.1524)
				)
			)
		)
		(duplicate_pad_numbers_are_jumpers no)
		(fp_line
			(start 3.556 3.5179)
			(end 3.556 2.2479)
			(stroke
				(width 0.1524)
				(type default)
			)
			(layer "F.SilkS")
		)
		(fp_line
			(start 2.286 3.5179)
			(end 3.556 3.5179)
			(stroke
				(width 0.1524)
				(type default)
			)
			(layer "F.SilkS")
		)
		(fp_line
			(start 1.500124 3.262122)
			(end 1.500124 4.024122)
			(stroke
				(width 0.1524)
				(type default)
			)
			(layer "F.SilkS")
		)
		(fp_line
			(start 0.500126 -3.262122)
			(end 0.500126 -3.770122)
			(stroke
				(width 0.1524)
				(type default)
			)
			(layer "F.SilkS")
		)
		(fp_line
			(start -0.999998 3.262122)
			(end -0.999998 3.770122)
			(stroke
				(width 0.1524)
				(type default)
			)
			(layer "F.SilkS")
		)
		(fp_line
			(start -1.999996 -3.262122)
			(end -1.999996 -4.024122)
			(stroke
				(width 0.1524)
				(type default)
			)
			(layer "F.SilkS")
		)
		(fp_line
			(start -2.286 -3.5179)
			(end -3.556 -3.5179)
			(stroke
				(width 0.1524)
				(type default)
			)
			(layer "F.SilkS")
		)
		(fp_line
			(start -3.556 3.5179)
			(end -2.286 3.5179)
			(stroke
				(width 0.1524)
				(type default)
			)
			(layer "F.SilkS")
		)
		(fp_line
			(start -3.556 2.2479)
			(end -3.556 3.5179)
			(stroke
				(width 0.1524)
				(type default)
			)
			(layer "F.SilkS")
		)
		(fp_line
			(start -3.556 -3.5179)
			(end -3.556 -2.2479)
			(stroke
				(width 0.1524)
				(type default)
			)
			(layer "F.SilkS")
		)
		(fp_poly
			(pts
				(xy 3.556 -3.5179) (xy 2.5273 -3.5179) (xy 3.556 -2.4892)
			)
			(stroke
				(width 0)
				(type default)
			)
			(fill yes)
			(layer "F.SilkS")
		)
		(fp_rect
			(start -2.9972 2.5019)
			(end 2.9972 -2.5019)
			(stroke
				(width 0)
				(type default)
			)
			(fill no)
			(layer "F.CrtYd")
		)
		(fp_poly
			(pts
				(xy 3.556 -2.5019) (xy -2.9972 -2.5019) (xy -2.9972 2.5019) (xy 2.9972 2.5019) (xy 2.9972 -2.4892)
				(xy 3.556 -2.4892) (xy 3.556 3.5179) (xy -3.556 3.5179) (xy -3.556 -3.5179) (xy 3.556 -3.5179)
			)
			(stroke
				(width 0)
				(type default)
			)
			(fill no)
			(layer "F.CrtYd")
		)
		(fp_rect
			(start -3.556 3.5179)
			(end 3.556 -3.5179)
			(stroke
				(width 0)
				(type default)
			)
			(fill no)
			(layer "F.Fab")
		)
		(pad "1" smd rect
			(at 2.500122 -2.449322 180)
			(size 0.3048 1.1176)
			(layers "F.Cu" "F.Mask" "F.Paste")
			(net "P5VC_VFB")
		)
		(pad "2" smd rect
			(at 1.999996 -2.449322 180)
			(size 0.3048 1.1176)
			(layers "F.Cu" "F.Mask" "F.Paste")
			(net "P5VC_EN")
		)
		(pad "3" smd rect
			(at 1.500124 -2.449322 180)
			(size 0.3048 1.1176)
			(layers "F.Cu" "F.Mask" "F.Paste")
			(net "P5VC_PGD")
		)
		(pad "4" smd rect
			(at 0.999998 -2.449322 180)
			(size 0.3048 1.1176)
			(layers "F.Cu" "F.Mask" "F.Paste")
			(net "P5VC_VBST")
		)
		(pad "5" smd rect
			(at 0.500126 -2.449322 180)
			(size 0.3048 1.1176)
			(layers "F.Cu" "F.Mask" "F.Paste")
			(net "P5VC_ROVP")
		)
		(pad "6" smd rect
			(at 0 -2.449322 180)
			(size 0.3048 1.1176)
			(layers "F.Cu" "F.Mask" "F.Paste")
			(net "P5VC_LL")
		)
		(pad "7" smd rect
			(at -0.500126 -2.449322 180)
			(size 0.3048 1.1176)
			(layers "F.Cu" "F.Mask" "F.Paste")
			(net "P5VC_LL")
		)
		(pad "8" smd rect
			(at -0.999998 -2.449322 180)
			(size 0.3048 1.1176)
			(layers "F.Cu" "F.Mask" "F.Paste")
			(net "P5VC_LL")
		)
		(pad "9" smd rect
			(at -1.500124 -2.449322 180)
			(size 0.3048 1.1176)
			(layers "F.Cu" "F.Mask" "F.Paste")
			(net "P5VC_LL")
		)
		(pad "10" smd rect
			(at -1.999996 -2.449322 180)
			(size 0.3048 1.1176)
			(layers "F.Cu" "F.Mask" "F.Paste")
			(net "P5VC_LL")
		)
		(pad "11" smd rect
			(at -2.500122 -2.449322 180)
			(size 0.3048 1.1176)
			(layers "F.Cu" "F.Mask" "F.Paste")
			(net "P5VC_LL")
		)
		(pad "12" smd rect
			(at -2.500122 2.449322 180)
			(size 0.3048 1.1176)
			(layers "F.Cu" "F.Mask" "F.Paste")
			(net "P5VC_12VIN")
		)
		(pad "13" smd rect
			(at -1.999996 2.449322 180)
			(size 0.3048 1.1176)
			(layers "F.Cu" "F.Mask" "F.Paste")
			(net "P5VC_12VIN")
		)
		(pad "14" smd rect
			(at -1.500124 2.449322 180)
			(size 0.3048 1.1176)
			(layers "F.Cu" "F.Mask" "F.Paste")
			(net "P5VC_12VIN")
		)
		(pad "15" smd rect
			(at -0.999998 2.449322 180)
			(size 0.3048 1.1176)
			(layers "F.Cu" "F.Mask" "F.Paste")
			(net "P5VC_12VIN")
		)
		(pad "16" smd rect
			(at -0.500126 2.449322 180)
			(size 0.3048 1.1176)
			(layers "F.Cu" "F.Mask" "F.Paste")
			(net "P5VC_12VIN")
		)
		(pad "17" smd rect
			(at 0 2.449322 180)
			(size 0.3048 1.1176)
			(layers "F.Cu" "F.Mask" "F.Paste")
			(net "P5VC_12VIN")
		)
		(pad "18" smd rect
			(at 0.500126 2.449322 180)
			(size 0.3048 1.1176)
			(layers "F.Cu" "F.Mask" "F.Paste")
			(net "P5VC_VREG")
		)
		(pad "19" smd rect
			(at 0.999998 2.449322 180)
			(size 0.3048 1.1176)
			(layers "F.Cu" "F.Mask" "F.Paste")
			(net "P5VC_VDD")
		)
		(pad "20" smd rect
			(at 1.500124 2.449322 180)
			(size 0.3048 1.1176)
			(layers "F.Cu" "F.Mask" "F.Paste")
			(net "P5VC_MODE")
		)
		(pad "21" smd rect
			(at 1.999996 2.449322 180)
			(size 0.3048 1.1176)
			(layers "F.Cu" "F.Mask" "F.Paste")
			(net "P5VC_TRIP")
		)
		(pad "22" smd rect
			(at 2.500122 2.449322 180)
			(size 0.3048 1.1176)
			(layers "F.Cu" "F.Mask" "F.Paste")
			(net "P5VC_RF")
		)
		(pad "23" smd custom
			(at 0 0 180)
			(size 0.83185 0.83185)
			(layers "F.Cu" "F.Mask" "F.Paste")
			(net "GND")
			(options
				(clearance outline)
				(anchor circle)
			)
			(primitives
				(gr_poly
					(pts
						(xy -2.7813 1.6637) (xy -2.7813 1.2954) (xy -3.048 1.2954) (xy -3.048 0.9525) (xy -2.7813 0.9525)
						(xy -2.7813 -0.9525) (xy -3.048 -0.9525) (xy -3.048 -1.2954) (xy -2.7813 -1.2954) (xy -2.7813 -1.6637)
						(xy 2.7813 -1.6637) (xy 2.7813 -1.2954) (xy 3.048 -1.2954) (xy 3.048 -0.9525) (xy 2.7813 -0.9525)
						(xy 2.7813 0.9525) (xy 3.048 0.9525) (xy 3.048 1.2954) (xy 2.7813 1.2954) (xy 2.7813 1.6637)
					)
					(width 0)
					(fill yes)
				)
			)
		)
	)
	(footprint ""
		(layer "F.Cu")
		(at 83.692746 -395.6177 -90)
		(property "Reference" "R448"
			(at 0 0 270)
			(layer "F.SilkS")
			(hide yes)
			(effects
				(font
					(size 1.27 1.27)
				)
			)
		)
		(property "Value" "4K7R2J-2-GP"
			(at 0.064008 -3.993896 270)
			(unlocked yes)
			(layer "F.Fab")
			(hide yes)
			(effects
				(font
					(size 1.016 1.016)
					(thickness 0.1524)
				)
			)
		)
		(property "Device Type" "R402H16"
			(at 0.064008 -5.517896 270)
			(unlocked yes)
			(layer "F.Fab")
			(hide yes)
			(effects
				(font
					(size 1.016 1.016)
					(thickness 0.1524)
				)
			)
		)
		(duplicate_pad_numbers_are_jumpers no)
		(fp_line
			(start -0.508 -0.9398)
			(end -0.508 0.9398)
			(stroke
				(width 0.1524)
				(type default)
			)
			(layer "F.SilkS")
		)
		(fp_line
			(start 0.508 -0.9398)
			(end -0.508 -0.9398)
			(stroke
				(width 0.1524)
				(type default)
			)
			(layer "F.SilkS")
		)
		(fp_rect
			(start -0.508 0.9398)
			(end 0.508 -0.9398)
			(stroke
				(width 0)
				(type default)
			)
			(fill no)
			(layer "F.CrtYd")
		)
		(fp_rect
			(start -0.508 0.9398)
			(end 0.508 -0.9398)
			(stroke
				(width 0)
				(type default)
			)
			(fill no)
			(layer "F.Fab")
		)
		(pad "1" smd custom
			(at 0 -0.4445 270)
			(size 0.1397 0.1397)
			(layers "F.Cu" "F.Mask" "F.Paste")
			(net "P3V3")
			(options
				(clearance outline)
				(anchor circle)
			)
			(primitives
				(gr_poly
					(pts
						(arc
							(start -0.1778 -0.2794)
							(mid -0.249642 -0.249642)
							(end -0.2794 -0.1778)
						)
						(arc
							(start -0.2794 0.1778)
							(mid -0.249642 0.249642)
							(end -0.1778 0.2794)
						)
						(arc
							(start 0.1778 0.2794)
							(mid 0.249642 0.249642)
							(end 0.2794 0.1778)
						)
						(arc
							(start 0.2794 -0.1778)
							(mid 0.249642 -0.249642)
							(end 0.1778 -0.2794)
						)
					)
					(width 0)
					(fill yes)
				)
			)
		)
		(pad "2" smd custom
			(at 0 0.4445 270)
			(size 0.1397 0.1397)
			(layers "F.Cu" "F.Mask" "F.Paste")
			(net "SAS_EXP_A_PWR6")
			(options
				(clearance outline)
				(anchor circle)
			)
			(primitives
				(gr_poly
					(pts
						(arc
							(start -0.1778 -0.2794)
							(mid -0.249642 -0.249642)
							(end -0.2794 -0.1778)
						)
						(arc
							(start -0.2794 0.1778)
							(mid -0.249642 0.249642)
							(end -0.1778 0.2794)
						)
						(arc
							(start 0.1778 0.2794)
							(mid 0.249642 0.249642)
							(end 0.2794 0.1778)
						)
						(arc
							(start 0.2794 -0.1778)
							(mid 0.249642 -0.249642)
							(end 0.1778 -0.2794)
						)
					)
					(width 0)
					(fill yes)
				)
			)
		)
	)
	(footprint ""
		(layer "F.Cu")
		(at 242.569746 -18.5547 90)
		(property "Reference" "PC3"
			(at 0 0 90)
			(layer "F.SilkS")
			(hide yes)
			(effects
				(font
					(size 1.27 1.27)
				)
			)
		)
		(property "Value" "SC22U25V5MX-GP"
			(at -0.0762 -6.1214 90)
			(unlocked yes)
			(layer "F.Fab")
			(hide yes)
			(effects
				(font
					(size 1.016 1.016)
					(thickness 0.1524)
				)
			)
		)
		(property "Device Type" "C805H58"
			(at -0.0762 -8.1534 90)
			(unlocked yes)
			(layer "F.Fab")
			(hide yes)
			(effects
				(font
					(size 1.016 1.016)
					(thickness 0.1524)
				)
			)
		)
		(duplicate_pad_numbers_are_jumpers no)
		(fp_line
			(start 0.635 0)
			(end -0.635 0)
			(stroke
				(width 0.508)
				(type default)
			)
			(layer "F.SilkS")
		)
		(fp_rect
			(start -0.9652 1.778)
			(end 0.9652 -1.778)
			(stroke
				(width 0)
				(type default)
			)
			(fill no)
			(layer "F.CrtYd")
		)
		(fp_poly
			(pts
				(xy -0.9652 -1.778) (xy 0.9652 -1.778) (xy 0.9652 1.778) (xy -0.9652 1.778)
			)
			(stroke
				(width 0)
				(type default)
			)
			(fill no)
			(layer "F.Fab")
		)
		(pad "1" smd rect
			(at 0 -0.9652 90)
			(size 1.397 1.143)
			(layers "F.Cu" "F.Mask" "F.Paste")
			(net "P5VA_12VIN")
		)
		(pad "2" smd rect
			(at 0 0.9652 90)
			(size 1.397 1.143)
			(layers "F.Cu" "F.Mask" "F.Paste")
			(net "GND")
		)
	)
	(footprint ""
		(layer "F.Cu")
		(at 36.448746 -132.235702 180)
		(property "Reference" "R293"
			(at 0 0 180)
			(layer "F.SilkS")
			(hide yes)
			(effects
				(font
					(size 1.27 1.27)
				)
			)
		)
		(property "Value" "220R3F-1-GP"
			(at -0.0254 -2.5146 180)
			(unlocked yes)
			(layer "F.Fab")
			(hide yes)
			(effects
				(font
					(size 1.016 1.016)
					(thickness 0.1524)
				)
			)
		)
		(property "Device Type" "R603H22"
			(at -0.0254 -4.0386 180)
			(unlocked yes)
			(layer "F.Fab")
			(hide yes)
			(effects
				(font
					(size 1.016 1.016)
					(thickness 0.1524)
				)
			)
		)
		(duplicate_pad_numbers_are_jumpers no)
		(fp_line
			(start 0.2032 0)
			(end 0.4826 0)
			(stroke
				(width 0.2032)
				(type default)
			)
			(layer "F.SilkS")
		)
		(fp_line
			(start -0.4826 0)
			(end -0.2032 0)
			(stroke
				(width 0.2032)
				(type default)
			)
			(layer "F.SilkS")
		)
		(fp_rect
			(start -0.5842 1.3335)
			(end 0.5842 -1.3335)
			(stroke
				(width 0)
				(type default)
			)
			(fill no)
			(layer "F.CrtYd")
		)
		(fp_rect
			(start -0.5842 1.3335)
			(end 0.5842 -1.3335)
			(stroke
				(width 0)
				(type default)
			)
			(fill no)
			(layer "F.Fab")
		)
		(pad "1" smd custom
			(at 0 -0.762 180)
			(size 0.2159 0.2159)
			(layers "F.Cu" "F.Mask" "F.Paste")
			(net "HDD_PRSNT_NET13")
			(options
				(clearance outline)
				(anchor circle)
			)
			(primitives
				(gr_poly
					(pts
						(arc
							(start -0.3302 -0.4318)
							(mid -0.402042 -0.402042)
							(end -0.4318 -0.3302)
						)
						(arc
							(start -0.4318 0.3302)
							(mid -0.402042 0.402042)
							(end -0.3302 0.4318)
						)
						(arc
							(start 0.3302 0.4318)
							(mid 0.402042 0.402042)
							(end 0.4318 0.3302)
						)
						(arc
							(start 0.4318 -0.3302)
							(mid 0.402042 -0.402042)
							(end 0.3302 -0.4318)
						)
					)
					(width 0)
					(fill yes)
				)
			)
		)
		(pad "2" smd custom
			(at 0 0.762 180)
			(size 0.2159 0.2159)
			(layers "F.Cu" "F.Mask" "F.Paste")
			(net "HDD_PRSNT13")
			(options
				(clearance outline)
				(anchor circle)
			)
			(primitives
				(gr_poly
					(pts
						(arc
							(start -0.3302 -0.4318)
							(mid -0.402042 -0.402042)
							(end -0.4318 -0.3302)
						)
						(arc
							(start -0.4318 0.3302)
							(mid -0.402042 0.402042)
							(end -0.3302 0.4318)
						)
						(arc
							(start 0.3302 0.4318)
							(mid 0.402042 0.402042)
							(end 0.4318 0.3302)
						)
						(arc
							(start 0.4318 -0.3302)
							(mid 0.402042 -0.402042)
							(end 0.3302 -0.4318)
						)
					)
					(width 0)
					(fill yes)
				)
			)
		)
	)
	(footprint ""
		(layer "F.Cu")
		(at 26.288746 -442.7347 90)
		(property "Reference" "C264"
			(at 0 0 90)
			(layer "F.SilkS")
			(hide yes)
			(effects
				(font
					(size 1.27 1.27)
				)
			)
		)
		(property "Value" "SCD01U50V2KX-1GP"
			(at 1.1811 -2.7051 90)
			(unlocked yes)
			(layer "F.Fab")
			(hide yes)
			(effects
				(font
					(size 1.016 1.016)
					(thickness 0.1524)
				)
			)
		)
		(property "Device Type" "C402H22"
			(at 1.1811 -4.2291 90)
			(unlocked yes)
			(layer "F.Fab")
			(hide yes)
			(effects
				(font
					(size 1.016 1.016)
					(thickness 0.1524)
				)
			)
		)
		(duplicate_pad_numbers_are_jumpers no)
		(fp_rect
			(start -0.4318 0.9525)
			(end 0.4318 -0.9525)
			(stroke
				(width 0)
				(type default)
			)
			(fill no)
			(layer "F.CrtYd")
		)
		(fp_rect
			(start -0.4318 0.9525)
			(end 0.4318 -0.9525)
			(stroke
				(width 0)
				(type default)
			)
			(fill no)
			(layer "F.Fab")
		)
		(pad "1" smd custom
			(at 0 -0.4445 90)
			(size 0.1524 0.1524)
			(layers "F.Cu" "F.Mask" "F.Paste")
			(net "SAS2X28_DRIVE_RX_N_B10")
			(options
				(clearance outline)
				(anchor circle)
			)
			(primitives
				(gr_poly
					(pts
						(arc
							(start 0.3048 -0.2032)
							(mid 0.275042 -0.275042)
							(end 0.2032 -0.3048)
						)
						(arc
							(start -0.2032 -0.3048)
							(mid -0.275042 -0.275042)
							(end -0.3048 -0.2032)
						)
						(arc
							(start -0.3048 0.2032)
							(mid -0.275042 0.275042)
							(end -0.2032 0.3048)
						)
						(arc
							(start 0.2032 0.3048)
							(mid 0.275042 0.275042)
							(end 0.3048 0.2032)
						)
					)
					(width 0)
					(fill yes)
				)
			)
		)
		(pad "2" smd custom
			(at 0 0.4445 90)
			(size 0.1524 0.1524)
			(layers "F.Cu" "F.Mask" "F.Paste")
			(net "SAS2X28_B_HDD10_RX_-")
			(options
				(clearance outline)
				(anchor circle)
			)
			(primitives
				(gr_poly
					(pts
						(arc
							(start 0.3048 -0.2032)
							(mid 0.275042 -0.275042)
							(end 0.2032 -0.3048)
						)
						(arc
							(start -0.2032 -0.3048)
							(mid -0.275042 -0.275042)
							(end -0.3048 -0.2032)
						)
						(arc
							(start -0.3048 0.2032)
							(mid -0.275042 0.275042)
							(end -0.2032 0.3048)
						)
						(arc
							(start 0.2032 0.3048)
							(mid 0.275042 0.275042)
							(end 0.3048 0.2032)
						)
					)
					(width 0)
					(fill yes)
				)
			)
		)
	)
	(footprint ""
		(layer "F.Cu")
		(at 45.783246 -124.041662 90)
		(property "Reference" "U40"
			(at 0 0 90)
			(layer "F.SilkS")
			(hide yes)
			(effects
				(font
					(size 1.27 1.27)
				)
			)
		)
		(property "Value" "74LVC1G08GW-1-GP"
			(at -2.3368 -8.6868 90)
			(unlocked yes)
			(layer "F.Fab")
			(hide yes)
			(effects
				(font
					(size 1.016 1.016)
					(thickness 0.1524)
				)
			)
		)
		(property "Device Type" "SC70-5H44"
			(at -2.3114 -10.414 90)
			(unlocked yes)
			(layer "F.Fab")
			(hide yes)
			(effects
				(font
					(size 1.016 1.016)
					(thickness 0.1524)
				)
			)
		)
		(duplicate_pad_numbers_are_jumpers no)
		(fp_line
			(start 1.3843 -1.8034)
			(end 1.3843 -1.1176)
			(stroke
				(width 0.3302)
				(type default)
			)
			(layer "F.SilkS")
		)
		(fp_line
			(start 0.6604 -1.8034)
			(end 1.3843 -1.8034)
			(stroke
				(width 0.3302)
				(type default)
			)
			(layer "F.SilkS")
		)
		(fp_line
			(start 1.27 -1.7018)
			(end 1.27 1.7018)
			(stroke
				(width 0.1524)
				(type default)
			)
			(layer "F.SilkS")
		)
		(fp_line
			(start -1.27 -1.7018)
			(end 1.27 -1.7018)
			(stroke
				(width 0.1524)
				(type default)
			)
			(layer "F.SilkS")
		)
		(fp_line
			(start 1.27 1.7018)
			(end -1.27 1.7018)
			(stroke
				(width 0.1524)
				(type default)
			)
			(layer "F.SilkS")
		)
		(fp_line
			(start -1.27 1.7018)
			(end -1.27 -1.7018)
			(stroke
				(width 0.1524)
				(type default)
			)
			(layer "F.SilkS")
		)
		(fp_rect
			(start -1.524 1.9558)
			(end 1.524 -1.9558)
			(stroke
				(width 0)
				(type default)
			)
			(fill no)
			(layer "F.CrtYd")
		)
		(fp_poly
			(pts
				(xy -1.524 -1.9558) (xy 1.524 -1.9558) (xy 1.524 1.9558) (xy -1.524 1.9558)
			)
			(stroke
				(width 0)
				(type default)
			)
			(fill no)
			(layer "F.Fab")
		)
		(pad "1" smd rect
			(at 0.65024 -0.8255 90)
			(size 0.4064 1.2192)
			(layers "F.Cu" "F.Mask" "F.Paste")
			(net "SAS2X28_B_HDD13_FLT")
		)
		(pad "2" smd rect
			(at 0 -0.8255 90)
			(size 0.4064 1.2192)
			(layers "F.Cu" "F.Mask" "F.Paste")
			(net "SAS2X28_A_HDD13_FLT")
		)
		(pad "3" smd rect
			(at -0.65024 -0.8255 90)
			(size 0.4064 1.2192)
			(layers "F.Cu" "F.Mask" "F.Paste")
			(net "GND")
		)
		(pad "4" smd rect
			(at -0.65024 0.8255 90)
			(size 0.4064 1.2192)
			(layers "F.Cu" "F.Mask" "F.Paste")
			(net "FLT_HDD13_DRIVE")
		)
		(pad "5" smd rect
			(at 0.65024 0.8255 90)
			(size 0.4064 1.2192)
			(layers "F.Cu" "F.Mask" "F.Paste")
			(net "P3V3")
		)
	)
	(footprint ""
		(layer "F.Cu")
		(at 224.789746 -143.5227 90)
		(property "Reference" "R145"
			(at 0 0 90)
			(layer "F.SilkS")
			(hide yes)
			(effects
				(font
					(size 1.27 1.27)
				)
			)
		)
		(property "Value" "330R2F-GP"
			(at 0.064008 -3.993896 90)
			(unlocked yes)
			(layer "F.Fab")
			(hide yes)
			(effects
				(font
					(size 1.016 1.016)
					(thickness 0.1524)
				)
			)
		)
		(property "Device Type" "R402H16"
			(at 0.064008 -5.517896 90)
			(unlocked yes)
			(layer "F.Fab")
			(hide yes)
			(effects
				(font
					(size 1.016 1.016)
					(thickness 0.1524)
				)
			)
		)
		(duplicate_pad_numbers_are_jumpers no)
		(fp_line
			(start 0.508 -0.9398)
			(end -0.508 -0.9398)
			(stroke
				(width 0.1524)
				(type default)
			)
			(layer "F.SilkS")
		)
		(fp_line
			(start -0.508 -0.9398)
			(end -0.508 0.9398)
			(stroke
				(width 0.1524)
				(type default)
			)
			(layer "F.SilkS")
		)
		(fp_rect
			(start -0.508 0.9398)
			(end 0.508 -0.9398)
			(stroke
				(width 0)
				(type default)
			)
			(fill no)
			(layer "F.CrtYd")
		)
		(fp_rect
			(start -0.508 0.9398)
			(end 0.508 -0.9398)
			(stroke
				(width 0)
				(type default)
			)
			(fill no)
			(layer "F.Fab")
		)
		(pad "1" smd custom
			(at 0 -0.4445 90)
			(size 0.1397 0.1397)
			(layers "F.Cu" "F.Mask" "F.Paste")
			(net "P3V3_HDD3_LED")
			(options
				(clearance outline)
				(anchor circle)
			)
			(primitives
				(gr_poly
					(pts
						(arc
							(start -0.1778 -0.2794)
							(mid -0.249642 -0.249642)
							(end -0.2794 -0.1778)
						)
						(arc
							(start -0.2794 0.1778)
							(mid -0.249642 0.249642)
							(end -0.1778 0.2794)
						)
						(arc
							(start 0.1778 0.2794)
							(mid 0.249642 0.249642)
							(end 0.2794 0.1778)
						)
						(arc
							(start 0.2794 -0.1778)
							(mid 0.249642 -0.249642)
							(end 0.1778 -0.2794)
						)
					)
					(width 0)
					(fill yes)
				)
			)
		)
		(pad "2" smd custom
			(at 0 0.4445 90)
			(size 0.1397 0.1397)
			(layers "F.Cu" "F.Mask" "F.Paste")
			(net "FLT_HDD3")
			(options
				(clearance outline)
				(anchor circle)
			)
			(primitives
				(gr_poly
					(pts
						(arc
							(start -0.1778 -0.2794)
							(mid -0.249642 -0.249642)
							(end -0.2794 -0.1778)
						)
						(arc
							(start -0.2794 0.1778)
							(mid -0.249642 0.249642)
							(end -0.1778 0.2794)
						)
						(arc
							(start 0.1778 0.2794)
							(mid 0.249642 0.249642)
							(end 0.2794 0.1778)
						)
						(arc
							(start 0.2794 -0.1778)
							(mid 0.249642 -0.249642)
							(end 0.1778 -0.2794)
						)
					)
					(width 0)
					(fill yes)
				)
			)
		)
	)
	(footprint ""
		(layer "F.Cu")
		(at 84.581746 -188.2267 -90)
		(property "Reference" "R455"
			(at 0 0 270)
			(layer "F.SilkS")
			(hide yes)
			(effects
				(font
					(size 1.27 1.27)
				)
			)
		)
		(property "Value" "4K7R2J-2-GP"
			(at 0.064008 -3.993896 270)
			(unlocked yes)
			(layer "F.Fab")
			(hide yes)
			(effects
				(font
					(size 1.016 1.016)
					(thickness 0.1524)
				)
			)
		)
		(property "Device Type" "R402H16"
			(at 0.064008 -5.517896 270)
			(unlocked yes)
			(layer "F.Fab")
			(hide yes)
			(effects
				(font
					(size 1.016 1.016)
					(thickness 0.1524)
				)
			)
		)
		(duplicate_pad_numbers_are_jumpers no)
		(fp_line
			(start -0.508 -0.9398)
			(end -0.508 0.9398)
			(stroke
				(width 0.1524)
				(type default)
			)
			(layer "F.SilkS")
		)
		(fp_line
			(start 0.508 -0.9398)
			(end -0.508 -0.9398)
			(stroke
				(width 0.1524)
				(type default)
			)
			(layer "F.SilkS")
		)
		(fp_rect
			(start -0.508 0.9398)
			(end 0.508 -0.9398)
			(stroke
				(width 0)
				(type default)
			)
			(fill no)
			(layer "F.CrtYd")
		)
		(fp_rect
			(start -0.508 0.9398)
			(end 0.508 -0.9398)
			(stroke
				(width 0)
				(type default)
			)
			(fill no)
			(layer "F.Fab")
		)
		(pad "1" smd custom
			(at 0 -0.4445 270)
			(size 0.1397 0.1397)
			(layers "F.Cu" "F.Mask" "F.Paste")
			(net "P3V3")
			(options
				(clearance outline)
				(anchor circle)
			)
			(primitives
				(gr_poly
					(pts
						(arc
							(start -0.1778 -0.2794)
							(mid -0.249642 -0.249642)
							(end -0.2794 -0.1778)
						)
						(arc
							(start -0.2794 0.1778)
							(mid -0.249642 0.249642)
							(end -0.1778 0.2794)
						)
						(arc
							(start 0.1778 0.2794)
							(mid 0.249642 0.249642)
							(end 0.2794 0.1778)
						)
						(arc
							(start 0.2794 -0.1778)
							(mid 0.249642 -0.249642)
							(end 0.1778 -0.2794)
						)
					)
					(width 0)
					(fill yes)
				)
			)
		)
		(pad "2" smd custom
			(at 0 0.4445 270)
			(size 0.1397 0.1397)
			(layers "F.Cu" "F.Mask" "F.Paste")
			(net "SAS_EXP_B_PWR8")
			(options
				(clearance outline)
				(anchor circle)
			)
			(primitives
				(gr_poly
					(pts
						(arc
							(start -0.1778 -0.2794)
							(mid -0.249642 -0.249642)
							(end -0.2794 -0.1778)
						)
						(arc
							(start -0.2794 0.1778)
							(mid -0.249642 0.249642)
							(end -0.1778 0.2794)
						)
						(arc
							(start 0.1778 0.2794)
							(mid 0.249642 0.249642)
							(end 0.2794 0.1778)
						)
						(arc
							(start 0.2794 -0.1778)
							(mid 0.249642 -0.249642)
							(end 0.1778 -0.2794)
						)
					)
					(width 0)
					(fill yes)
				)
			)
		)
	)
	(footprint ""
		(layer "F.Cu")
		(at 79.304134 -494.006886 -90)
		(property "Reference" "R179"
			(at 0 0 270)
			(layer "F.SilkS")
			(hide yes)
			(effects
				(font
					(size 1.27 1.27)
				)
			)
		)
		(property "Value" "1KR2F-3-GP"
			(at 0.064008 -3.993896 270)
			(unlocked yes)
			(layer "F.Fab")
			(hide yes)
			(effects
				(font
					(size 1.016 1.016)
					(thickness 0.1524)
				)
			)
		)
		(property "Device Type" "R402H16"
			(at 0.064008 -5.517896 270)
			(unlocked yes)
			(layer "F.Fab")
			(hide yes)
			(effects
				(font
					(size 1.016 1.016)
					(thickness 0.1524)
				)
			)
		)
		(duplicate_pad_numbers_are_jumpers no)
		(fp_line
			(start -0.508 -0.9398)
			(end -0.508 0.9398)
			(stroke
				(width 0.1524)
				(type default)
			)
			(layer "F.SilkS")
		)
		(fp_line
			(start 0.508 -0.9398)
			(end -0.508 -0.9398)
			(stroke
				(width 0.1524)
				(type default)
			)
			(layer "F.SilkS")
		)
		(fp_rect
			(start -0.508 0.9398)
			(end 0.508 -0.9398)
			(stroke
				(width 0)
				(type default)
			)
			(fill no)
			(layer "F.CrtYd")
		)
		(fp_rect
			(start -0.508 0.9398)
			(end 0.508 -0.9398)
			(stroke
				(width 0)
				(type default)
			)
			(fill no)
			(layer "F.Fab")
		)
		(pad "1" smd custom
			(at 0 -0.4445 270)
			(size 0.1397 0.1397)
			(layers "F.Cu" "F.Mask" "F.Paste")
			(net "P3V3")
			(options
				(clearance outline)
				(anchor circle)
			)
			(primitives
				(gr_poly
					(pts
						(arc
							(start -0.1778 -0.2794)
							(mid -0.249642 -0.249642)
							(end -0.2794 -0.1778)
						)
						(arc
							(start -0.2794 0.1778)
							(mid -0.249642 0.249642)
							(end -0.1778 0.2794)
						)
						(arc
							(start 0.1778 0.2794)
							(mid 0.249642 0.249642)
							(end 0.2794 0.1778)
						)
						(arc
							(start 0.2794 -0.1778)
							(mid 0.249642 -0.249642)
							(end 0.1778 -0.2794)
						)
					)
					(width 0)
					(fill yes)
				)
			)
		)
		(pad "2" smd custom
			(at 0 0.4445 270)
			(size 0.1397 0.1397)
			(layers "F.Cu" "F.Mask" "F.Paste")
			(net "SW_PWR_HDD5")
			(options
				(clearance outline)
				(anchor circle)
			)
			(primitives
				(gr_poly
					(pts
						(arc
							(start -0.1778 -0.2794)
							(mid -0.249642 -0.249642)
							(end -0.2794 -0.1778)
						)
						(arc
							(start -0.2794 0.1778)
							(mid -0.249642 0.249642)
							(end -0.1778 0.2794)
						)
						(arc
							(start 0.1778 0.2794)
							(mid 0.249642 0.249642)
							(end 0.2794 0.1778)
						)
						(arc
							(start 0.2794 -0.1778)
							(mid 0.249642 -0.249642)
							(end 0.1778 -0.2794)
						)
					)
					(width 0)
					(fill yes)
				)
			)
		)
	)
	(footprint ""
		(layer "F.Cu")
		(at 71.500746 -393.2047)
		(property "Reference" "U19"
			(at 0 0 0)
			(layer "F.SilkS")
			(hide yes)
			(effects
				(font
					(size 1.27 1.27)
				)
			)
		)
		(property "Value" "74LVC1G08GW-1-GP"
			(at -2.3368 -8.6868 0)
			(unlocked yes)
			(layer "F.Fab")
			(hide yes)
			(effects
				(font
					(size 1.016 1.016)
					(thickness 0.1524)
				)
			)
		)
		(property "Device Type" "SC70-5H44"
			(at -2.3114 -10.414 0)
			(unlocked yes)
			(layer "F.Fab")
			(hide yes)
			(effects
				(font
					(size 1.016 1.016)
					(thickness 0.1524)
				)
			)
		)
		(duplicate_pad_numbers_are_jumpers no)
		(fp_line
			(start -1.27 -1.7018)
			(end 1.27 -1.7018)
			(stroke
				(width 0.1524)
				(type default)
			)
			(layer "F.SilkS")
		)
		(fp_line
			(start -1.27 1.7018)
			(end -1.27 -1.7018)
			(stroke
				(width 0.1524)
				(type default)
			)
			(layer "F.SilkS")
		)
		(fp_line
			(start 0.6604 -1.8034)
			(end 1.3843 -1.8034)
			(stroke
				(width 0.3302)
				(type default)
			)
			(layer "F.SilkS")
		)
		(fp_line
			(start 1.27 -1.7018)
			(end 1.27 1.7018)
			(stroke
				(width 0.1524)
				(type default)
			)
			(layer "F.SilkS")
		)
		(fp_line
			(start 1.27 1.7018)
			(end -1.27 1.7018)
			(stroke
				(width 0.1524)
				(type default)
			)
			(layer "F.SilkS")
		)
		(fp_line
			(start 1.3843 -1.8034)
			(end 1.3843 -1.1176)
			(stroke
				(width 0.3302)
				(type default)
			)
			(layer "F.SilkS")
		)
		(fp_rect
			(start -1.524 1.9558)
			(end 1.524 -1.9558)
			(stroke
				(width 0)
				(type default)
			)
			(fill no)
			(layer "F.CrtYd")
		)
		(fp_poly
			(pts
				(xy -1.524 -1.9558) (xy 1.524 -1.9558) (xy 1.524 1.9558) (xy -1.524 1.9558)
			)
			(stroke
				(width 0)
				(type default)
			)
			(fill no)
			(layer "F.Fab")
		)
		(pad "1" smd rect
			(at 0.65024 -0.8255)
			(size 0.4064 1.2192)
			(layers "F.Cu" "F.Mask" "F.Paste")
			(net "SAS2X28_B_HDD6_FLT")
		)
		(pad "2" smd rect
			(at 0 -0.8255)
			(size 0.4064 1.2192)
			(layers "F.Cu" "F.Mask" "F.Paste")
			(net "SAS2X28_A_HDD6_FLT")
		)
		(pad "3" smd rect
			(at -0.65024 -0.8255)
			(size 0.4064 1.2192)
			(layers "F.Cu" "F.Mask" "F.Paste")
			(net "GND")
		)
		(pad "4" smd rect
			(at -0.65024 0.8255)
			(size 0.4064 1.2192)
			(layers "F.Cu" "F.Mask" "F.Paste")
			(net "FLT_HDD6_DRIVE")
		)
		(pad "5" smd rect
			(at 0.65024 0.8255)
			(size 0.4064 1.2192)
			(layers "F.Cu" "F.Mask" "F.Paste")
			(net "P3V3")
		)
	)
	(footprint ""
		(layer "F.Cu")
		(at 92.202 -11.303)
		(property "Reference" "R577"
			(at 0 0 0)
			(layer "F.SilkS")
			(hide yes)
			(effects
				(font
					(size 1.27 1.27)
				)
			)
		)
		(property "Value" "300KR2F-GP"
			(at 0.064008 -3.993896 0)
			(unlocked yes)
			(layer "F.Fab")
			(hide yes)
			(effects
				(font
					(size 1.016 1.016)
					(thickness 0.1524)
				)
			)
		)
		(property "Device Type" "R402H16"
			(at 0.064008 -5.517896 0)
			(unlocked yes)
			(layer "F.Fab")
			(hide yes)
			(effects
				(font
					(size 1.016 1.016)
					(thickness 0.1524)
				)
			)
		)
		(duplicate_pad_numbers_are_jumpers no)
		(fp_line
			(start -0.508 -0.9398)
			(end -0.508 0.9398)
			(stroke
				(width 0.1524)
				(type default)
			)
			(layer "F.SilkS")
		)
		(fp_line
			(start 0.508 -0.9398)
			(end -0.508 -0.9398)
			(stroke
				(width 0.1524)
				(type default)
			)
			(layer "F.SilkS")
		)
		(fp_rect
			(start -0.508 0.9398)
			(end 0.508 -0.9398)
			(stroke
				(width 0)
				(type default)
			)
			(fill no)
			(layer "F.CrtYd")
		)
		(fp_rect
			(start -0.508 0.9398)
			(end 0.508 -0.9398)
			(stroke
				(width 0)
				(type default)
			)
			(fill no)
			(layer "F.Fab")
		)
		(pad "1" smd custom
			(at 0 -0.4445)
			(size 0.1397 0.1397)
			(layers "F.Cu" "F.Mask" "F.Paste")
			(net "SW_HDD14_N")
			(options
				(clearance outline)
				(anchor circle)
			)
			(primitives
				(gr_poly
					(pts
						(arc
							(start -0.1778 -0.2794)
							(mid -0.249642 -0.249642)
							(end -0.2794 -0.1778)
						)
						(arc
							(start -0.2794 0.1778)
							(mid -0.249642 0.249642)
							(end -0.1778 0.2794)
						)
						(arc
							(start 0.1778 0.2794)
							(mid 0.249642 0.249642)
							(end 0.2794 0.1778)
						)
						(arc
							(start 0.2794 -0.1778)
							(mid 0.249642 -0.249642)
							(end 0.1778 -0.2794)
						)
					)
					(width 0)
					(fill yes)
				)
			)
		)
		(pad "2" smd custom
			(at 0 0.4445)
			(size 0.1397 0.1397)
			(layers "F.Cu" "F.Mask" "F.Paste")
			(net "P12V")
			(options
				(clearance outline)
				(anchor circle)
			)
			(primitives
				(gr_poly
					(pts
						(arc
							(start -0.1778 -0.2794)
							(mid -0.249642 -0.249642)
							(end -0.2794 -0.1778)
						)
						(arc
							(start -0.2794 0.1778)
							(mid -0.249642 0.249642)
							(end -0.1778 0.2794)
						)
						(arc
							(start 0.1778 0.2794)
							(mid 0.249642 0.249642)
							(end 0.2794 0.1778)
						)
						(arc
							(start 0.2794 -0.1778)
							(mid 0.249642 -0.249642)
							(end 0.1778 -0.2794)
						)
					)
					(width 0)
					(fill yes)
				)
			)
		)
	)
	(footprint ""
		(layer "F.Cu")
		(at 230.267256 -453.545702 90)
		(property "Reference" "R101"
			(at 0 0 90)
			(layer "F.SilkS")
			(hide yes)
			(effects
				(font
					(size 1.27 1.27)
				)
			)
		)
		(property "Value" "10KR2F-2-GP"
			(at 0.064008 -3.993896 90)
			(unlocked yes)
			(layer "F.Fab")
			(hide yes)
			(effects
				(font
					(size 1.016 1.016)
					(thickness 0.1524)
				)
			)
		)
		(property "Device Type" "R402H16"
			(at 0.064008 -5.517896 90)
			(unlocked yes)
			(layer "F.Fab")
			(hide yes)
			(effects
				(font
					(size 1.016 1.016)
					(thickness 0.1524)
				)
			)
		)
		(duplicate_pad_numbers_are_jumpers no)
		(fp_line
			(start 0.508 -0.9398)
			(end -0.508 -0.9398)
			(stroke
				(width 0.1524)
				(type default)
			)
			(layer "F.SilkS")
		)
		(fp_line
			(start -0.508 -0.9398)
			(end -0.508 0.9398)
			(stroke
				(width 0.1524)
				(type default)
			)
			(layer "F.SilkS")
		)
		(fp_rect
			(start -0.508 0.9398)
			(end 0.508 -0.9398)
			(stroke
				(width 0)
				(type default)
			)
			(fill no)
			(layer "F.CrtYd")
		)
		(fp_rect
			(start -0.508 0.9398)
			(end 0.508 -0.9398)
			(stroke
				(width 0)
				(type default)
			)
			(fill no)
			(layer "F.Fab")
		)
		(pad "1" smd custom
			(at 0 -0.4445 90)
			(size 0.1397 0.1397)
			(layers "F.Cu" "F.Mask" "F.Paste")
			(net "P5VA")
			(options
				(clearance outline)
				(anchor circle)
			)
			(primitives
				(gr_poly
					(pts
						(arc
							(start -0.1778 -0.2794)
							(mid -0.249642 -0.249642)
							(end -0.2794 -0.1778)
						)
						(arc
							(start -0.2794 0.1778)
							(mid -0.249642 0.249642)
							(end -0.1778 0.2794)
						)
						(arc
							(start 0.1778 0.2794)
							(mid 0.249642 0.249642)
							(end 0.2794 0.1778)
						)
						(arc
							(start 0.2794 -0.1778)
							(mid 0.249642 -0.249642)
							(end 0.1778 -0.2794)
						)
					)
					(width 0)
					(fill yes)
				)
			)
		)
		(pad "2" smd custom
			(at 0 0.4445 90)
			(size 0.1397 0.1397)
			(layers "F.Cu" "F.Mask" "F.Paste")
			(net "DRIVE_ACT_0")
			(options
				(clearance outline)
				(anchor circle)
			)
			(primitives
				(gr_poly
					(pts
						(arc
							(start -0.1778 -0.2794)
							(mid -0.249642 -0.249642)
							(end -0.2794 -0.1778)
						)
						(arc
							(start -0.2794 0.1778)
							(mid -0.249642 0.249642)
							(end -0.1778 0.2794)
						)
						(arc
							(start 0.1778 0.2794)
							(mid 0.249642 0.249642)
							(end 0.2794 0.1778)
						)
						(arc
							(start 0.2794 -0.1778)
							(mid 0.249642 -0.249642)
							(end 0.1778 -0.2794)
						)
					)
					(width 0)
					(fill yes)
				)
			)
		)
	)
	(footprint ""
		(layer "F.Cu")
		(at 60.832746 -25.9207 90)
		(property "Reference" "PG2"
			(at 0 0 90)
			(layer "F.SilkS")
			(hide yes)
			(effects
				(font
					(size 1.27 1.27)
				)
			)
		)
		(property "Value" "COPPER-CLOSE-GP-U"
			(at 0.0762 -2.8702 90)
			(unlocked yes)
			(layer "F.Fab")
			(hide yes)
			(effects
				(font
					(size 1.016 1.016)
					(thickness 0.1524)
				)
			)
		)
		(property "Device Type" "CON2C-U"
			(at 0.0762 -4.3942 90)
			(unlocked yes)
			(layer "F.Fab")
			(hide yes)
			(effects
				(font
					(size 1.016 1.016)
					(thickness 0.1524)
				)
			)
		)
		(duplicate_pad_numbers_are_jumpers no)
		(fp_rect
			(start -0.9398 0.9652)
			(end 0.9398 -0.9652)
			(stroke
				(width 0)
				(type default)
			)
			(fill no)
			(layer "F.CrtYd")
		)
		(fp_rect
			(start -0.9398 0.9652)
			(end 0.9398 -0.9652)
			(stroke
				(width 0)
				(type default)
			)
			(fill no)
			(layer "F.Fab")
		)
		(pad "1" smd custom
			(at 0 -0.5334 90)
			(size 0.17145 0.17145)
			(layers "F.Cu" "F.Mask" "F.Paste")
			(net "P5VB_AGND")
			(options
				(clearance outline)
				(anchor circle)
			)
			(primitives
				(gr_poly
					(pts
						(xy -0.127 0.3429) (xy -0.127 0.1651) (xy -0.635 -0.3429) (xy 0.635 -0.3429) (xy 0.127 0.1651)
						(xy 0.127 0.3429)
					)
					(width 0)
					(fill yes)
				)
			)
		)
		(pad "2" smd custom
			(at 0 0.5334 90)
			(size 0.17145 0.17145)
			(layers "F.Cu" "F.Mask" "F.Paste")
			(net "GND")
			(options
				(clearance outline)
				(anchor circle)
			)
			(primitives
				(gr_poly
					(pts
						(xy -0.635 0.3429) (xy -0.127 -0.1651) (xy -0.127 -0.3429) (xy 0.127 -0.3429) (xy 0.127 -0.1651)
						(xy 0.635 0.3429)
					)
					(width 0)
					(fill yes)
				)
			)
		)
	)
	(footprint ""
		(layer "F.Cu")
		(at 36.575746 -18.1737 180)
		(property "Reference" "PL4"
			(at 0 0 180)
			(layer "F.SilkS")
			(hide yes)
			(effects
				(font
					(size 1.27 1.27)
				)
			)
		)
		(property "Value" "IND-4D7UH-291-GP"
			(at -6.34492 -3.502152 180)
			(unlocked yes)
			(layer "F.Fab")
			(hide yes)
			(effects
				(font
					(size 1.016 1.016)
					(thickness 0.1524)
				)
			)
		)
		(property "Device Type" "L11102530H158"
			(at -6.3246 -5.08 180)
			(unlocked yes)
			(layer "F.Fab")
			(hide yes)
			(effects
				(font
					(size 1.016 1.016)
					(thickness 0.1524)
				)
			)
		)
		(duplicate_pad_numbers_are_jumpers no)
		(fp_line
			(start 5.2578 6.3754)
			(end 5.2578 -6.3754)
			(stroke
				(width 0.1524)
				(type default)
			)
			(layer "F.SilkS")
		)
		(fp_line
			(start 5.2578 -6.3754)
			(end -5.2578 -6.3754)
			(stroke
				(width 0.1524)
				(type default)
			)
			(layer "F.SilkS")
		)
		(fp_line
			(start -5.2578 6.3754)
			(end 5.2578 6.3754)
			(stroke
				(width 0.1524)
				(type default)
			)
			(layer "F.SilkS")
		)
		(fp_line
			(start -5.2578 -6.3754)
			(end -5.2578 6.3754)
			(stroke
				(width 0.1524)
				(type default)
			)
			(layer "F.SilkS")
		)
		(fp_rect
			(start -5.0038 5.4991)
			(end 5.0038 -5.4991)
			(stroke
				(width 0)
				(type default)
			)
			(fill no)
			(layer "F.CrtYd")
		)
		(fp_poly
			(pts
				(xy -5.5118 6.4516) (xy -5.5118 -6.4516) (xy 5.5118 -6.4516) (xy 5.5118 -0.8509) (xy 5.0038 -0.8509)
				(xy 5.0038 -5.4991) (xy -5.0038 -5.4991) (xy -5.0038 5.4991) (xy 5.0038 5.4991) (xy 5.0038 -0.8382)
				(xy 5.5118 -0.8382) (xy 5.5118 6.4516)
			)
			(stroke
				(width 0)
				(type default)
			)
			(fill no)
			(layer "F.CrtYd")
		)
		(fp_rect
			(start -5.5118 6.4516)
			(end 5.5118 -6.4516)
			(stroke
				(width 0)
				(type default)
			)
			(fill no)
			(layer "F.Fab")
		)
		(pad "1" smd rect
			(at 0 -4.435094 180)
			(size 3.2512 3.3782)
			(layers "F.Cu" "F.Mask" "F.Paste")
			(net "P5VB_LL")
		)
		(pad "2" smd rect
			(at 0 4.435094 180)
			(size 3.2512 3.3782)
			(layers "F.Cu" "F.Mask" "F.Paste")
			(net "P5VB")
		)
	)
	(footprint ""
		(layer "F.Cu")
		(at 30.860746 -343.4207 90)
		(property "Reference" "R256"
			(at 0 0 90)
			(layer "F.SilkS")
			(hide yes)
			(effects
				(font
					(size 1.27 1.27)
				)
			)
		)
		(property "Value" "0R2J-2-GP"
			(at 0.064008 -3.993896 90)
			(unlocked yes)
			(layer "F.Fab")
			(hide yes)
			(effects
				(font
					(size 1.016 1.016)
					(thickness 0.1524)
				)
			)
		)
		(property "Device Type" "R402H16"
			(at 0.064008 -5.517896 90)
			(unlocked yes)
			(layer "F.Fab")
			(hide yes)
			(effects
				(font
					(size 1.016 1.016)
					(thickness 0.1524)
				)
			)
		)
		(duplicate_pad_numbers_are_jumpers no)
		(fp_line
			(start 0.508 -0.9398)
			(end -0.508 -0.9398)
			(stroke
				(width 0.1524)
				(type default)
			)
			(layer "F.SilkS")
		)
		(fp_line
			(start -0.508 -0.9398)
			(end -0.508 0.9398)
			(stroke
				(width 0.1524)
				(type default)
			)
			(layer "F.SilkS")
		)
		(fp_rect
			(start -0.508 0.9398)
			(end 0.508 -0.9398)
			(stroke
				(width 0)
				(type default)
			)
			(fill no)
			(layer "F.CrtYd")
		)
		(fp_rect
			(start -0.508 0.9398)
			(end 0.508 -0.9398)
			(stroke
				(width 0)
				(type default)
			)
			(fill no)
			(layer "F.Fab")
		)
		(pad "1" smd custom
			(at 0 -0.4445 90)
			(size 0.1397 0.1397)
			(layers "F.Cu" "F.Mask" "F.Paste")
			(net "DRV_ACT_NET11")
			(options
				(clearance outline)
				(anchor circle)
			)
			(primitives
				(gr_poly
					(pts
						(arc
							(start -0.1778 -0.2794)
							(mid -0.249642 -0.249642)
							(end -0.2794 -0.1778)
						)
						(arc
							(start -0.2794 0.1778)
							(mid -0.249642 0.249642)
							(end -0.1778 0.2794)
						)
						(arc
							(start 0.1778 0.2794)
							(mid 0.249642 0.249642)
							(end 0.2794 0.1778)
						)
						(arc
							(start 0.2794 -0.1778)
							(mid 0.249642 -0.249642)
							(end 0.1778 -0.2794)
						)
					)
					(width 0)
					(fill yes)
				)
			)
		)
		(pad "2" smd custom
			(at 0 0.4445 90)
			(size 0.1397 0.1397)
			(layers "F.Cu" "F.Mask" "F.Paste")
			(net "DRIVE_ACT_11")
			(options
				(clearance outline)
				(anchor circle)
			)
			(primitives
				(gr_poly
					(pts
						(arc
							(start -0.1778 -0.2794)
							(mid -0.249642 -0.249642)
							(end -0.2794 -0.1778)
						)
						(arc
							(start -0.2794 0.1778)
							(mid -0.249642 0.249642)
							(end -0.1778 0.2794)
						)
						(arc
							(start 0.1778 0.2794)
							(mid 0.249642 0.249642)
							(end 0.2794 0.1778)
						)
						(arc
							(start 0.2794 -0.1778)
							(mid 0.249642 -0.249642)
							(end 0.1778 -0.2794)
						)
					)
					(width 0)
					(fill yes)
				)
			)
		)
	)
	(footprint ""
		(layer "F.Cu")
		(at 219.201746 -19.6977 180)
		(property "Reference" "PL2"
			(at 0 0 180)
			(layer "F.SilkS")
			(hide yes)
			(effects
				(font
					(size 1.27 1.27)
				)
			)
		)
		(property "Value" "IND-4D7UH-291-GP"
			(at -6.34492 -3.502152 180)
			(unlocked yes)
			(layer "F.Fab")
			(hide yes)
			(effects
				(font
					(size 1.016 1.016)
					(thickness 0.1524)
				)
			)
		)
		(property "Device Type" "L11102530H158"
			(at -6.3246 -5.08 180)
			(unlocked yes)
			(layer "F.Fab")
			(hide yes)
			(effects
				(font
					(size 1.016 1.016)
					(thickness 0.1524)
				)
			)
		)
		(duplicate_pad_numbers_are_jumpers no)
		(fp_line
			(start 5.2578 6.3754)
			(end 5.2578 -6.3754)
			(stroke
				(width 0.1524)
				(type default)
			)
			(layer "F.SilkS")
		)
		(fp_line
			(start 5.2578 -6.3754)
			(end -5.2578 -6.3754)
			(stroke
				(width 0.1524)
				(type default)
			)
			(layer "F.SilkS")
		)
		(fp_line
			(start -5.2578 6.3754)
			(end 5.2578 6.3754)
			(stroke
				(width 0.1524)
				(type default)
			)
			(layer "F.SilkS")
		)
		(fp_line
			(start -5.2578 -6.3754)
			(end -5.2578 6.3754)
			(stroke
				(width 0.1524)
				(type default)
			)
			(layer "F.SilkS")
		)
		(fp_rect
			(start -5.0038 5.4991)
			(end 5.0038 -5.4991)
			(stroke
				(width 0)
				(type default)
			)
			(fill no)
			(layer "F.CrtYd")
		)
		(fp_poly
			(pts
				(xy -5.5118 6.4516) (xy -5.5118 -6.4516) (xy 5.5118 -6.4516) (xy 5.5118 -0.8509) (xy 5.0038 -0.8509)
				(xy 5.0038 -5.4991) (xy -5.0038 -5.4991) (xy -5.0038 5.4991) (xy 5.0038 5.4991) (xy 5.0038 -0.8382)
				(xy 5.5118 -0.8382) (xy 5.5118 6.4516)
			)
			(stroke
				(width 0)
				(type default)
			)
			(fill no)
			(layer "F.CrtYd")
		)
		(fp_rect
			(start -5.5118 6.4516)
			(end 5.5118 -6.4516)
			(stroke
				(width 0)
				(type default)
			)
			(fill no)
			(layer "F.Fab")
		)
		(pad "1" smd rect
			(at 0 -4.435094 180)
			(size 3.2512 3.3782)
			(layers "F.Cu" "F.Mask" "F.Paste")
			(net "P5VA_LL")
		)
		(pad "2" smd rect
			(at 0 4.435094 180)
			(size 3.2512 3.3782)
			(layers "F.Cu" "F.Mask" "F.Paste")
			(net "P5VA")
		)
	)
	(footprint ""
		(layer "F.Cu")
		(at 10.5156 -151.7396 90)
		(property "Reference" "R544"
			(at 0 0 90)
			(layer "F.SilkS")
			(hide yes)
			(effects
				(font
					(size 1.27 1.27)
				)
			)
		)
		(property "Value" "0R2J-2-GP"
			(at 0.064008 -3.993896 90)
			(unlocked yes)
			(layer "F.Fab")
			(hide yes)
			(effects
				(font
					(size 1.016 1.016)
					(thickness 0.1524)
				)
			)
		)
		(property "Device Type" "R402H16"
			(at 0.064008 -5.517896 90)
			(unlocked yes)
			(layer "F.Fab")
			(hide yes)
			(effects
				(font
					(size 1.016 1.016)
					(thickness 0.1524)
				)
			)
		)
		(duplicate_pad_numbers_are_jumpers no)
		(fp_line
			(start 0.508 -0.9398)
			(end -0.508 -0.9398)
			(stroke
				(width 0.1524)
				(type default)
			)
			(layer "F.SilkS")
		)
		(fp_line
			(start -0.508 -0.9398)
			(end -0.508 0.9398)
			(stroke
				(width 0.1524)
				(type default)
			)
			(layer "F.SilkS")
		)
		(fp_rect
			(start -0.508 0.9398)
			(end 0.508 -0.9398)
			(stroke
				(width 0)
				(type default)
			)
			(fill no)
			(layer "F.CrtYd")
		)
		(fp_rect
			(start -0.508 0.9398)
			(end 0.508 -0.9398)
			(stroke
				(width 0)
				(type default)
			)
			(fill no)
			(layer "F.Fab")
		)
		(pad "1" smd custom
			(at 0 -0.4445 90)
			(size 0.1397 0.1397)
			(layers "F.Cu" "F.Mask" "F.Paste")
			(net "I2C_B_SCL_DAMP_B")
			(options
				(clearance outline)
				(anchor circle)
			)
			(primitives
				(gr_poly
					(pts
						(arc
							(start -0.1778 -0.2794)
							(mid -0.249642 -0.249642)
							(end -0.2794 -0.1778)
						)
						(arc
							(start -0.2794 0.1778)
							(mid -0.249642 0.249642)
							(end -0.1778 0.2794)
						)
						(arc
							(start 0.1778 0.2794)
							(mid 0.249642 0.249642)
							(end 0.2794 0.1778)
						)
						(arc
							(start 0.2794 -0.1778)
							(mid 0.249642 -0.249642)
							(end 0.1778 -0.2794)
						)
					)
					(width 0)
					(fill yes)
				)
			)
		)
		(pad "2" smd custom
			(at 0 0.4445 90)
			(size 0.1397 0.1397)
			(layers "F.Cu" "F.Mask" "F.Paste")
			(net "I2C_B_SCL")
			(options
				(clearance outline)
				(anchor circle)
			)
			(primitives
				(gr_poly
					(pts
						(arc
							(start -0.1778 -0.2794)
							(mid -0.249642 -0.249642)
							(end -0.2794 -0.1778)
						)
						(arc
							(start -0.2794 0.1778)
							(mid -0.249642 0.249642)
							(end -0.1778 0.2794)
						)
						(arc
							(start 0.1778 0.2794)
							(mid 0.249642 0.249642)
							(end 0.2794 0.1778)
						)
						(arc
							(start 0.2794 -0.1778)
							(mid 0.249642 -0.249642)
							(end 0.1778 -0.2794)
						)
					)
					(width 0)
					(fill yes)
				)
			)
		)
	)
	(footprint ""
		(layer "F.Cu")
		(at 188.988446 -456.472036)
		(property "Reference" "R350"
			(at 0 0 0)
			(layer "F.SilkS")
			(hide yes)
			(effects
				(font
					(size 1.27 1.27)
				)
			)
		)
		(property "Value" "4K7R2J-2-GP"
			(at 0.064008 -3.993896 0)
			(unlocked yes)
			(layer "F.Fab")
			(hide yes)
			(effects
				(font
					(size 1.016 1.016)
					(thickness 0.1524)
				)
			)
		)
		(property "Device Type" "R402H16"
			(at 0.064008 -5.517896 0)
			(unlocked yes)
			(layer "F.Fab")
			(hide yes)
			(effects
				(font
					(size 1.016 1.016)
					(thickness 0.1524)
				)
			)
		)
		(duplicate_pad_numbers_are_jumpers no)
		(fp_line
			(start -0.508 -0.9398)
			(end -0.508 0.9398)
			(stroke
				(width 0.1524)
				(type default)
			)
			(layer "F.SilkS")
		)
		(fp_line
			(start 0.508 -0.9398)
			(end -0.508 -0.9398)
			(stroke
				(width 0.1524)
				(type default)
			)
			(layer "F.SilkS")
		)
		(fp_rect
			(start -0.508 0.9398)
			(end 0.508 -0.9398)
			(stroke
				(width 0)
				(type default)
			)
			(fill no)
			(layer "F.CrtYd")
		)
		(fp_rect
			(start -0.508 0.9398)
			(end 0.508 -0.9398)
			(stroke
				(width 0)
				(type default)
			)
			(fill no)
			(layer "F.Fab")
		)
		(pad "1" smd custom
			(at 0 -0.4445)
			(size 0.1397 0.1397)
			(layers "F.Cu" "F.Mask" "F.Paste")
			(net "EEPROM_A2")
			(options
				(clearance outline)
				(anchor circle)
			)
			(primitives
				(gr_poly
					(pts
						(arc
							(start -0.1778 -0.2794)
							(mid -0.249642 -0.249642)
							(end -0.2794 -0.1778)
						)
						(arc
							(start -0.2794 0.1778)
							(mid -0.249642 0.249642)
							(end -0.1778 0.2794)
						)
						(arc
							(start 0.1778 0.2794)
							(mid 0.249642 0.249642)
							(end 0.2794 0.1778)
						)
						(arc
							(start 0.2794 -0.1778)
							(mid 0.249642 -0.249642)
							(end 0.1778 -0.2794)
						)
					)
					(width 0)
					(fill yes)
				)
			)
		)
		(pad "2" smd custom
			(at 0 0.4445)
			(size 0.1397 0.1397)
			(layers "F.Cu" "F.Mask" "F.Paste")
			(net "GND")
			(options
				(clearance outline)
				(anchor circle)
			)
			(primitives
				(gr_poly
					(pts
						(arc
							(start -0.1778 -0.2794)
							(mid -0.249642 -0.249642)
							(end -0.2794 -0.1778)
						)
						(arc
							(start -0.2794 0.1778)
							(mid -0.249642 0.249642)
							(end -0.1778 0.2794)
						)
						(arc
							(start 0.1778 0.2794)
							(mid 0.249642 0.249642)
							(end 0.2794 0.1778)
						)
						(arc
							(start 0.2794 -0.1778)
							(mid 0.249642 -0.249642)
							(end 0.1778 -0.2794)
						)
					)
					(width 0)
					(fill yes)
				)
			)
		)
	)
	(footprint ""
		(layer "F.Cu")
		(at 79.883 -404.114 -90)
		(property "Reference" "R555"
			(at 0 0 270)
			(layer "F.SilkS")
			(hide yes)
			(effects
				(font
					(size 1.27 1.27)
				)
			)
		)
		(property "Value" "200KR2F-L-GP"
			(at 0.064008 -3.993896 270)
			(unlocked yes)
			(layer "F.Fab")
			(hide yes)
			(effects
				(font
					(size 1.016 1.016)
					(thickness 0.1524)
				)
			)
		)
		(property "Device Type" "R402H16"
			(at 0.064008 -5.517896 270)
			(unlocked yes)
			(layer "F.Fab")
			(hide yes)
			(effects
				(font
					(size 1.016 1.016)
					(thickness 0.1524)
				)
			)
		)
		(duplicate_pad_numbers_are_jumpers no)
		(fp_line
			(start -0.508 -0.9398)
			(end -0.508 0.9398)
			(stroke
				(width 0.1524)
				(type default)
			)
			(layer "F.SilkS")
		)
		(fp_line
			(start 0.508 -0.9398)
			(end -0.508 -0.9398)
			(stroke
				(width 0.1524)
				(type default)
			)
			(layer "F.SilkS")
		)
		(fp_rect
			(start -0.508 0.9398)
			(end 0.508 -0.9398)
			(stroke
				(width 0)
				(type default)
			)
			(fill no)
			(layer "F.CrtYd")
		)
		(fp_rect
			(start -0.508 0.9398)
			(end 0.508 -0.9398)
			(stroke
				(width 0)
				(type default)
			)
			(fill no)
			(layer "F.Fab")
		)
		(pad "1" smd custom
			(at 0 -0.4445 270)
			(size 0.1397 0.1397)
			(layers "F.Cu" "F.Mask" "F.Paste")
			(net "SW_HDD6_R")
			(options
				(clearance outline)
				(anchor circle)
			)
			(primitives
				(gr_poly
					(pts
						(arc
							(start -0.1778 -0.2794)
							(mid -0.249642 -0.249642)
							(end -0.2794 -0.1778)
						)
						(arc
							(start -0.2794 0.1778)
							(mid -0.249642 0.249642)
							(end -0.1778 0.2794)
						)
						(arc
							(start 0.1778 0.2794)
							(mid 0.249642 0.249642)
							(end 0.2794 0.1778)
						)
						(arc
							(start 0.2794 -0.1778)
							(mid 0.249642 -0.249642)
							(end 0.1778 -0.2794)
						)
					)
					(width 0)
					(fill yes)
				)
			)
		)
		(pad "2" smd custom
			(at 0 0.4445 270)
			(size 0.1397 0.1397)
			(layers "F.Cu" "F.Mask" "F.Paste")
			(net "SW_HDD6_N")
			(options
				(clearance outline)
				(anchor circle)
			)
			(primitives
				(gr_poly
					(pts
						(arc
							(start -0.1778 -0.2794)
							(mid -0.249642 -0.249642)
							(end -0.2794 -0.1778)
						)
						(arc
							(start -0.2794 0.1778)
							(mid -0.249642 0.249642)
							(end -0.1778 0.2794)
						)
						(arc
							(start 0.1778 0.2794)
							(mid 0.249642 0.249642)
							(end 0.2794 0.1778)
						)
						(arc
							(start 0.2794 -0.1778)
							(mid 0.249642 -0.249642)
							(end 0.1778 -0.2794)
						)
					)
					(width 0)
					(fill yes)
				)
			)
		)
	)
	(footprint ""
		(layer "F.Cu")
		(at 12.699746 -500.1387 180)
		(property "Reference" "PR35"
			(at 0 0 180)
			(layer "F.SilkS")
			(hide yes)
			(effects
				(font
					(size 1.27 1.27)
				)
			)
		)
		(property "Value" "0R3J-0-U-GP"
			(at -0.0254 -2.5146 180)
			(unlocked yes)
			(layer "F.Fab")
			(hide yes)
			(effects
				(font
					(size 1.016 1.016)
					(thickness 0.1524)
				)
			)
		)
		(property "Device Type" "R603H22"
			(at -0.0254 -4.0386 180)
			(unlocked yes)
			(layer "F.Fab")
			(hide yes)
			(effects
				(font
					(size 1.016 1.016)
					(thickness 0.1524)
				)
			)
		)
		(duplicate_pad_numbers_are_jumpers no)
		(fp_line
			(start 0.2032 0)
			(end 0.4826 0)
			(stroke
				(width 0.2032)
				(type default)
			)
			(layer "F.SilkS")
		)
		(fp_line
			(start -0.4826 0)
			(end -0.2032 0)
			(stroke
				(width 0.2032)
				(type default)
			)
			(layer "F.SilkS")
		)
		(fp_rect
			(start -0.5842 1.3335)
			(end 0.5842 -1.3335)
			(stroke
				(width 0)
				(type default)
			)
			(fill no)
			(layer "F.CrtYd")
		)
		(fp_rect
			(start -0.5842 1.3335)
			(end 0.5842 -1.3335)
			(stroke
				(width 0)
				(type default)
			)
			(fill no)
			(layer "F.Fab")
		)
		(pad "1" smd custom
			(at 0 -0.762 180)
			(size 0.2159 0.2159)
			(layers "F.Cu" "F.Mask" "F.Paste")
			(net "P5VC_12VIN")
			(options
				(clearance outline)
				(anchor circle)
			)
			(primitives
				(gr_poly
					(pts
						(arc
							(start -0.3302 -0.4318)
							(mid -0.402042 -0.402042)
							(end -0.4318 -0.3302)
						)
						(arc
							(start -0.4318 0.3302)
							(mid -0.402042 0.402042)
							(end -0.3302 0.4318)
						)
						(arc
							(start 0.3302 0.4318)
							(mid 0.402042 0.402042)
							(end 0.4318 0.3302)
						)
						(arc
							(start 0.4318 -0.3302)
							(mid 0.402042 -0.402042)
							(end 0.3302 -0.4318)
						)
					)
					(width 0)
					(fill yes)
				)
			)
		)
		(pad "2" smd custom
			(at 0 0.762 180)
			(size 0.2159 0.2159)
			(layers "F.Cu" "F.Mask" "F.Paste")
			(net "P5VC_VDD")
			(options
				(clearance outline)
				(anchor circle)
			)
			(primitives
				(gr_poly
					(pts
						(arc
							(start -0.3302 -0.4318)
							(mid -0.402042 -0.402042)
							(end -0.4318 -0.3302)
						)
						(arc
							(start -0.4318 0.3302)
							(mid -0.402042 0.402042)
							(end -0.3302 0.4318)
						)
						(arc
							(start 0.3302 0.4318)
							(mid 0.402042 0.402042)
							(end 0.4318 0.3302)
						)
						(arc
							(start 0.4318 -0.3302)
							(mid 0.402042 -0.402042)
							(end 0.3302 -0.4318)
						)
					)
					(width 0)
					(fill yes)
				)
			)
		)
	)
	(footprint ""
		(layer "F.Cu")
		(at 68.999608 -170.999912)
		(property "Reference" "H4"
			(at 0 0 0)
			(layer "F.SilkS")
			(hide yes)
			(effects
				(font
					(size 1.27 1.27)
				)
			)
		)
		(property "Value" "HOLE315R140"
			(at 0 -7.5692 0)
			(unlocked yes)
			(layer "F.Fab")
			(hide yes)
			(effects
				(font
					(size 1.016 1.016)
					(thickness 0.1524)
				)
			)
		)
		(property "Device Type" "HOLE315R140"
			(at 0 -9.0932 0)
			(unlocked yes)
			(layer "F.Fab")
			(hide yes)
			(effects
				(font
					(size 1.016 1.016)
					(thickness 0.1524)
				)
			)
		)
		(duplicate_pad_numbers_are_jumpers no)
		(fp_poly
			(pts
				(arc
					(start 4.3053 0)
					(mid -4.3053 0)
					(end 4.3053 0)
				)
			)
			(stroke
				(width 0)
				(type default)
			)
			(fill no)
			(layer "F.CrtYd")
		)
		(fp_poly
			(pts
				(arc
					(start 4.3053 0)
					(mid -4.3053 0)
					(end 4.3053 0)
				)
			)
			(stroke
				(width 0)
				(type default)
			)
			(fill no)
			(layer "F.Fab")
		)
		(pad "1" thru_hole circle
			(at 0.00127 0.00127)
			(size 8.001 8.001)
			(drill 3.556)
			(layers "*.Cu" "*.Mask")
			(remove_unused_layers no)
			(net "GND")
			(clearance -1.7145)
			(thermal_gap 0.3048)
			(padstack
				(mode front_inner_back)
				(layer "Inner"
					(shape circle)
					(size 3.9624 3.9624)
					(clearance 0.3048)
				)
				(layer "B.Cu"
					(shape circle)
					(size 8.001 8.001)
					(clearance -1.7145)
				)
			)
		)
	)
	(footprint ""
		(layer "F.Cu")
		(at 43.942 -234.3658 90)
		(property "Reference" "R400"
			(at 0 0 90)
			(layer "F.SilkS")
			(hide yes)
			(effects
				(font
					(size 1.27 1.27)
				)
			)
		)
		(property "Value" "0R2J-2-GP"
			(at 0.064008 -3.993896 90)
			(unlocked yes)
			(layer "F.Fab")
			(hide yes)
			(effects
				(font
					(size 1.016 1.016)
					(thickness 0.1524)
				)
			)
		)
		(property "Device Type" "R402H16"
			(at 0.064008 -5.517896 90)
			(unlocked yes)
			(layer "F.Fab")
			(hide yes)
			(effects
				(font
					(size 1.016 1.016)
					(thickness 0.1524)
				)
			)
		)
		(duplicate_pad_numbers_are_jumpers no)
		(fp_line
			(start 0.508 -0.9398)
			(end -0.508 -0.9398)
			(stroke
				(width 0.1524)
				(type default)
			)
			(layer "F.SilkS")
		)
		(fp_line
			(start -0.508 -0.9398)
			(end -0.508 0.9398)
			(stroke
				(width 0.1524)
				(type default)
			)
			(layer "F.SilkS")
		)
		(fp_rect
			(start -0.508 0.9398)
			(end 0.508 -0.9398)
			(stroke
				(width 0)
				(type default)
			)
			(fill no)
			(layer "F.CrtYd")
		)
		(fp_rect
			(start -0.508 0.9398)
			(end 0.508 -0.9398)
			(stroke
				(width 0)
				(type default)
			)
			(fill no)
			(layer "F.Fab")
		)
		(pad "1" smd custom
			(at 0 -0.4445 90)
			(size 0.1397 0.1397)
			(layers "F.Cu" "F.Mask" "F.Paste")
			(net "HDD_PRSNT_NET12")
			(options
				(clearance outline)
				(anchor circle)
			)
			(primitives
				(gr_poly
					(pts
						(arc
							(start -0.1778 -0.2794)
							(mid -0.249642 -0.249642)
							(end -0.2794 -0.1778)
						)
						(arc
							(start -0.2794 0.1778)
							(mid -0.249642 0.249642)
							(end -0.1778 0.2794)
						)
						(arc
							(start 0.1778 0.2794)
							(mid 0.249642 0.249642)
							(end 0.2794 0.1778)
						)
						(arc
							(start 0.2794 -0.1778)
							(mid 0.249642 -0.249642)
							(end 0.1778 -0.2794)
						)
					)
					(width 0)
					(fill yes)
				)
			)
		)
		(pad "2" smd custom
			(at 0 0.4445 90)
			(size 0.1397 0.1397)
			(layers "F.Cu" "F.Mask" "F.Paste")
			(net "HDD12_LED_B")
			(options
				(clearance outline)
				(anchor circle)
			)
			(primitives
				(gr_poly
					(pts
						(arc
							(start -0.1778 -0.2794)
							(mid -0.249642 -0.249642)
							(end -0.2794 -0.1778)
						)
						(arc
							(start -0.2794 0.1778)
							(mid -0.249642 0.249642)
							(end -0.1778 0.2794)
						)
						(arc
							(start 0.1778 0.2794)
							(mid 0.249642 0.249642)
							(end 0.2794 0.1778)
						)
						(arc
							(start 0.2794 -0.1778)
							(mid 0.249642 -0.249642)
							(end 0.1778 -0.2794)
						)
					)
					(width 0)
					(fill yes)
				)
			)
		)
	)
	(footprint ""
		(layer "F.Cu")
		(at 9.4234 -153.2128 90)
		(property "Reference" "R548"
			(at 0 0 90)
			(layer "F.SilkS")
			(hide yes)
			(effects
				(font
					(size 1.27 1.27)
				)
			)
		)
		(property "Value" "0R2J-2-GP"
			(at 0.064008 -3.993896 90)
			(unlocked yes)
			(layer "F.Fab")
			(hide yes)
			(effects
				(font
					(size 1.016 1.016)
					(thickness 0.1524)
				)
			)
		)
		(property "Device Type" "R402H16"
			(at 0.064008 -5.517896 90)
			(unlocked yes)
			(layer "F.Fab")
			(hide yes)
			(effects
				(font
					(size 1.016 1.016)
					(thickness 0.1524)
				)
			)
		)
		(duplicate_pad_numbers_are_jumpers no)
		(fp_line
			(start 0.508 -0.9398)
			(end -0.508 -0.9398)
			(stroke
				(width 0.1524)
				(type default)
			)
			(layer "F.SilkS")
		)
		(fp_line
			(start -0.508 -0.9398)
			(end -0.508 0.9398)
			(stroke
				(width 0.1524)
				(type default)
			)
			(layer "F.SilkS")
		)
		(fp_rect
			(start -0.508 0.9398)
			(end 0.508 -0.9398)
			(stroke
				(width 0)
				(type default)
			)
			(fill no)
			(layer "F.CrtYd")
		)
		(fp_rect
			(start -0.508 0.9398)
			(end 0.508 -0.9398)
			(stroke
				(width 0)
				(type default)
			)
			(fill no)
			(layer "F.Fab")
		)
		(pad "1" smd custom
			(at 0 -0.4445 90)
			(size 0.1397 0.1397)
			(layers "F.Cu" "F.Mask" "F.Paste")
			(net "I2C_D_SCL_DAMP_B")
			(options
				(clearance outline)
				(anchor circle)
			)
			(primitives
				(gr_poly
					(pts
						(arc
							(start -0.1778 -0.2794)
							(mid -0.249642 -0.249642)
							(end -0.2794 -0.1778)
						)
						(arc
							(start -0.2794 0.1778)
							(mid -0.249642 0.249642)
							(end -0.1778 0.2794)
						)
						(arc
							(start 0.1778 0.2794)
							(mid 0.249642 0.249642)
							(end 0.2794 0.1778)
						)
						(arc
							(start 0.2794 -0.1778)
							(mid 0.249642 -0.249642)
							(end 0.1778 -0.2794)
						)
					)
					(width 0)
					(fill yes)
				)
			)
		)
		(pad "2" smd custom
			(at 0 0.4445 90)
			(size 0.1397 0.1397)
			(layers "F.Cu" "F.Mask" "F.Paste")
			(net "I2C_D_SCL")
			(options
				(clearance outline)
				(anchor circle)
			)
			(primitives
				(gr_poly
					(pts
						(arc
							(start -0.1778 -0.2794)
							(mid -0.249642 -0.249642)
							(end -0.2794 -0.1778)
						)
						(arc
							(start -0.2794 0.1778)
							(mid -0.249642 0.249642)
							(end -0.1778 0.2794)
						)
						(arc
							(start 0.1778 0.2794)
							(mid 0.249642 0.249642)
							(end 0.2794 0.1778)
						)
						(arc
							(start 0.2794 -0.1778)
							(mid 0.249642 -0.249642)
							(end 0.1778 -0.2794)
						)
					)
					(width 0)
					(fill yes)
				)
			)
		)
	)
	(footprint ""
		(layer "F.Cu")
		(at 217.122756 -481.358702)
		(property "Reference" "R111"
			(at 0 0 0)
			(layer "F.SilkS")
			(hide yes)
			(effects
				(font
					(size 1.27 1.27)
				)
			)
		)
		(property "Value" "220R3F-1-GP"
			(at -0.0254 -2.5146 0)
			(unlocked yes)
			(layer "F.Fab")
			(hide yes)
			(effects
				(font
					(size 1.016 1.016)
					(thickness 0.1524)
				)
			)
		)
		(property "Device Type" "R603H22"
			(at -0.0254 -4.0386 0)
			(unlocked yes)
			(layer "F.Fab")
			(hide yes)
			(effects
				(font
					(size 1.016 1.016)
					(thickness 0.1524)
				)
			)
		)
		(duplicate_pad_numbers_are_jumpers no)
		(fp_line
			(start -0.4826 0)
			(end -0.2032 0)
			(stroke
				(width 0.2032)
				(type default)
			)
			(layer "F.SilkS")
		)
		(fp_line
			(start 0.2032 0)
			(end 0.4826 0)
			(stroke
				(width 0.2032)
				(type default)
			)
			(layer "F.SilkS")
		)
		(fp_rect
			(start -0.5842 1.3335)
			(end 0.5842 -1.3335)
			(stroke
				(width 0)
				(type default)
			)
			(fill no)
			(layer "F.CrtYd")
		)
		(fp_rect
			(start -0.5842 1.3335)
			(end 0.5842 -1.3335)
			(stroke
				(width 0)
				(type default)
			)
			(fill no)
			(layer "F.Fab")
		)
		(pad "1" smd custom
			(at 0 -0.762)
			(size 0.2159 0.2159)
			(layers "F.Cu" "F.Mask" "F.Paste")
			(net "HDD_PRSNT_NET0")
			(options
				(clearance outline)
				(anchor circle)
			)
			(primitives
				(gr_poly
					(pts
						(arc
							(start -0.3302 -0.4318)
							(mid -0.402042 -0.402042)
							(end -0.4318 -0.3302)
						)
						(arc
							(start -0.4318 0.3302)
							(mid -0.402042 0.402042)
							(end -0.3302 0.4318)
						)
						(arc
							(start 0.3302 0.4318)
							(mid 0.402042 0.402042)
							(end 0.4318 0.3302)
						)
						(arc
							(start 0.4318 -0.3302)
							(mid 0.402042 -0.402042)
							(end 0.3302 -0.4318)
						)
					)
					(width 0)
					(fill yes)
				)
			)
		)
		(pad "2" smd custom
			(at 0 0.762)
			(size 0.2159 0.2159)
			(layers "F.Cu" "F.Mask" "F.Paste")
			(net "HDD_PRSNT0")
			(options
				(clearance outline)
				(anchor circle)
			)
			(primitives
				(gr_poly
					(pts
						(arc
							(start -0.3302 -0.4318)
							(mid -0.402042 -0.402042)
							(end -0.4318 -0.3302)
						)
						(arc
							(start -0.4318 0.3302)
							(mid -0.402042 0.402042)
							(end -0.3302 0.4318)
						)
						(arc
							(start 0.3302 0.4318)
							(mid 0.402042 0.402042)
							(end 0.4318 0.3302)
						)
						(arc
							(start 0.4318 -0.3302)
							(mid 0.402042 -0.402042)
							(end 0.3302 -0.4318)
						)
					)
					(width 0)
					(fill yes)
				)
			)
		)
	)
	(footprint ""
		(layer "F.Cu")
		(at 79.629 -500.888 180)
		(property "Reference" "R554"
			(at 0 0 180)
			(layer "F.SilkS")
			(hide yes)
			(effects
				(font
					(size 1.27 1.27)
				)
			)
		)
		(property "Value" "200KR2F-L-GP"
			(at 0.064008 -3.993896 180)
			(unlocked yes)
			(layer "F.Fab")
			(hide yes)
			(effects
				(font
					(size 1.016 1.016)
					(thickness 0.1524)
				)
			)
		)
		(property "Device Type" "R402H16"
			(at 0.064008 -5.517896 180)
			(unlocked yes)
			(layer "F.Fab")
			(hide yes)
			(effects
				(font
					(size 1.016 1.016)
					(thickness 0.1524)
				)
			)
		)
		(duplicate_pad_numbers_are_jumpers no)
		(fp_line
			(start 0.508 -0.9398)
			(end -0.508 -0.9398)
			(stroke
				(width 0.1524)
				(type default)
			)
			(layer "F.SilkS")
		)
		(fp_line
			(start -0.508 -0.9398)
			(end -0.508 0.9398)
			(stroke
				(width 0.1524)
				(type default)
			)
			(layer "F.SilkS")
		)
		(fp_rect
			(start -0.508 0.9398)
			(end 0.508 -0.9398)
			(stroke
				(width 0)
				(type default)
			)
			(fill no)
			(layer "F.CrtYd")
		)
		(fp_rect
			(start -0.508 0.9398)
			(end 0.508 -0.9398)
			(stroke
				(width 0)
				(type default)
			)
			(fill no)
			(layer "F.Fab")
		)
		(pad "1" smd custom
			(at 0 -0.4445 180)
			(size 0.1397 0.1397)
			(layers "F.Cu" "F.Mask" "F.Paste")
			(net "SW_HDD5_R")
			(options
				(clearance outline)
				(anchor circle)
			)
			(primitives
				(gr_poly
					(pts
						(arc
							(start -0.1778 -0.2794)
							(mid -0.249642 -0.249642)
							(end -0.2794 -0.1778)
						)
						(arc
							(start -0.2794 0.1778)
							(mid -0.249642 0.249642)
							(end -0.1778 0.2794)
						)
						(arc
							(start 0.1778 0.2794)
							(mid 0.249642 0.249642)
							(end 0.2794 0.1778)
						)
						(arc
							(start 0.2794 -0.1778)
							(mid 0.249642 -0.249642)
							(end 0.1778 -0.2794)
						)
					)
					(width 0)
					(fill yes)
				)
			)
		)
		(pad "2" smd custom
			(at 0 0.4445 180)
			(size 0.1397 0.1397)
			(layers "F.Cu" "F.Mask" "F.Paste")
			(net "SW_HDD5_N")
			(options
				(clearance outline)
				(anchor circle)
			)
			(primitives
				(gr_poly
					(pts
						(arc
							(start -0.1778 -0.2794)
							(mid -0.249642 -0.249642)
							(end -0.2794 -0.1778)
						)
						(arc
							(start -0.2794 0.1778)
							(mid -0.249642 0.249642)
							(end -0.1778 0.2794)
						)
						(arc
							(start 0.1778 0.2794)
							(mid 0.249642 0.249642)
							(end 0.2794 0.1778)
						)
						(arc
							(start 0.2794 -0.1778)
							(mid 0.249642 -0.249642)
							(end 0.1778 -0.2794)
						)
					)
					(width 0)
					(fill yes)
				)
			)
		)
	)
	(footprint ""
		(layer "F.Cu")
		(at 227.499926 -273.670014 90)
		(property "Reference" "SKT3"
			(at 0 0 90)
			(layer "F.SilkS")
			(hide yes)
			(effects
				(font
					(size 1.27 1.27)
				)
			)
		)
		(property "Value" "SKT-SATA14P-15P-12-GP"
			(at -22.6187 8.1788 90)
			(unlocked yes)
			(layer "F.Fab")
			(hide yes)
			(effects
				(font
					(size 1.016 1.016)
					(thickness 0.1524)
				)
			)
		)
		(property "Device Type" "87945-1001"
			(at -22.6187 6.6548 90)
			(unlocked yes)
			(layer "F.Fab")
			(hide yes)
			(effects
				(font
					(size 1.016 1.016)
					(thickness 0.1524)
				)
			)
		)
		(duplicate_pad_numbers_are_jumpers no)
		(fp_line
			(start -15.3924 -5.8547)
			(end -16.3576 -5.8547)
			(stroke
				(width 0.3302)
				(type default)
			)
			(layer "F.SilkS")
		)
		(fp_line
			(start 20.4724 -5.7658)
			(end 20.4724 -2.3114)
			(stroke
				(width 0.1524)
				(type default)
			)
			(layer "F.SilkS")
		)
		(fp_line
			(start -20.4724 -5.7658)
			(end 20.4724 -5.7658)
			(stroke
				(width 0.1524)
				(type default)
			)
			(layer "F.SilkS")
		)
		(fp_line
			(start 23.7617 -2.3114)
			(end 23.7617 2.3114)
			(stroke
				(width 0.1524)
				(type default)
			)
			(layer "F.SilkS")
		)
		(fp_line
			(start 20.4724 -2.3114)
			(end 23.7617 -2.3114)
			(stroke
				(width 0.1524)
				(type default)
			)
			(layer "F.SilkS")
		)
		(fp_line
			(start -20.4724 -2.3114)
			(end -20.4724 -5.7658)
			(stroke
				(width 0.1524)
				(type default)
			)
			(layer "F.SilkS")
		)
		(fp_line
			(start -23.7617 -2.3114)
			(end -20.4724 -2.3114)
			(stroke
				(width 0.1524)
				(type default)
			)
			(layer "F.SilkS")
		)
		(fp_line
			(start 23.117556 -0.5461)
			(end 23.117556 0.5461)
			(stroke
				(width 0.3048)
				(type default)
			)
			(layer "F.SilkS")
		)
		(fp_line
			(start -20.882356 -0.5461)
			(end -20.882356 0.5461)
			(stroke
				(width 0.3048)
				(type default)
			)
			(layer "F.SilkS")
		)
		(fp_line
			(start 20.882356 0.5461)
			(end 20.882356 -0.5461)
			(stroke
				(width 0.3048)
				(type default)
			)
			(layer "F.SilkS")
		)
		(fp_line
			(start -23.117556 0.5461)
			(end -23.117556 -0.5461)
			(stroke
				(width 0.3048)
				(type default)
			)
			(layer "F.SilkS")
		)
		(fp_line
			(start 23.7617 2.3114)
			(end 20.4724 2.3114)
			(stroke
				(width 0.1524)
				(type default)
			)
			(layer "F.SilkS")
		)
		(fp_line
			(start 20.4724 2.3114)
			(end 20.4724 9.652)
			(stroke
				(width 0.1524)
				(type default)
			)
			(layer "F.SilkS")
		)
		(fp_line
			(start -20.4724 2.3114)
			(end -23.7617 2.3114)
			(stroke
				(width 0.1524)
				(type default)
			)
			(layer "F.SilkS")
		)
		(fp_line
			(start -23.7617 2.3114)
			(end -23.7617 -2.3114)
			(stroke
				(width 0.1524)
				(type default)
			)
			(layer "F.SilkS")
		)
		(fp_line
			(start 17.8435 7.9502)
			(end -17.8435 7.9502)
			(stroke
				(width 0.1524)
				(type default)
			)
			(layer "F.SilkS")
		)
		(fp_line
			(start -17.8435 7.9502)
			(end -17.8435 9.652)
			(stroke
				(width 0.1524)
				(type default)
			)
			(layer "F.SilkS")
		)
		(fp_line
			(start 20.4724 9.652)
			(end 17.8435 9.652)
			(stroke
				(width 0.1524)
				(type default)
			)
			(layer "F.SilkS")
		)
		(fp_line
			(start 17.8435 9.652)
			(end 17.8435 7.9502)
			(stroke
				(width 0.1524)
				(type default)
			)
			(layer "F.SilkS")
		)
		(fp_line
			(start -17.8435 9.652)
			(end -20.4724 9.652)
			(stroke
				(width 0.1524)
				(type default)
			)
			(layer "F.SilkS")
		)
		(fp_line
			(start -20.4724 9.652)
			(end -20.4724 2.3114)
			(stroke
				(width 0.1524)
				(type default)
			)
			(layer "F.SilkS")
		)
		(fp_arc
			(start 20.882356 -0.5461)
			(mid 21.999956 -1.6637)
			(end 23.117556 -0.5461)
			(stroke
				(width 0.3048)
				(type default)
			)
			(layer "F.SilkS")
		)
		(fp_arc
			(start -23.117556 -0.5461)
			(mid -21.999956 -1.6637)
			(end -20.882356 -0.5461)
			(stroke
				(width 0.3048)
				(type default)
			)
			(layer "F.SilkS")
		)
		(fp_arc
			(start 23.117556 0.5461)
			(mid 21.999956 1.6637)
			(end 20.882356 0.5461)
			(stroke
				(width 0.3048)
				(type default)
			)
			(layer "F.SilkS")
		)
		(fp_arc
			(start -20.882356 0.5461)
			(mid -21.999956 1.6637)
			(end -23.117556 0.5461)
			(stroke
				(width 0.3048)
				(type default)
			)
			(layer "F.SilkS")
		)
		(fp_poly
			(pts
				(xy -15.87119 -5.838698) (xy -15.23619 -6.473698) (xy -16.50619 -6.473698)
			)
			(stroke
				(width 0)
				(type default)
			)
			(fill yes)
			(layer "F.SilkS")
		)
		(fp_poly
			(pts
				(xy -20.2184 -5.5118) (xy 20.2184 -5.5118) (xy 20.2184 -2.0574) (xy 23.5077 -2.0574) (xy 23.5077 2.0574)
				(xy 20.2184 2.0574) (xy 20.2184 9.398) (xy 18.0975 9.398) (xy 18.0975 7.6962) (xy -18.0975 7.6962)
				(xy -18.0975 9.398) (xy -20.2184 9.398) (xy -20.2184 2.0574) (xy -23.5077 2.0574) (xy -23.5077 -2.0574)
				(xy -20.2184 -2.0574)
			)
			(stroke
				(width 0)
				(type default)
			)
			(fill no)
			(layer "F.CrtYd")
		)
		(fp_poly
			(pts
				(xy -20.2184 -5.5118) (xy -20.2184 -6.0198) (xy -20.7264 -6.0198) (xy -20.7264 -2.5654) (xy -24.0157 -2.5654)
				(xy -24.0157 2.5654) (xy -20.7264 2.5654) (xy -20.7264 9.906) (xy -17.5895 9.906) (xy -17.5895 8.2042)
				(xy 17.5895 8.2042) (xy 17.5895 9.906) (xy 20.7264 9.906) (xy 20.7264 2.5654) (xy 24.0157 2.5654)
				(xy 24.0157 -2.5654) (xy 20.7264 -2.5654) (xy 20.7264 -6.0198) (xy -20.21586 -6.0198) (xy -20.21586 -5.5118)
				(xy 20.2184 -5.5118) (xy 20.2184 -2.0574) (xy 23.5077 -2.0574) (xy 23.5077 2.0574) (xy 20.2184 2.0574)
				(xy 20.2184 9.398) (xy 18.0975 9.398) (xy 18.0975 7.6962) (xy -18.0975 7.6962) (xy -18.0975 9.398)
				(xy -20.2184 9.398) (xy -20.2184 2.0574) (xy -23.5077 2.0574) (xy -23.5077 -2.0574) (xy -20.2184 -2.0574)
			)
			(stroke
				(width 0)
				(type default)
			)
			(fill no)
			(layer "F.CrtYd")
		)
		(fp_poly
			(pts
				(xy -20.7264 -6.0198) (xy -20.7264 -2.5654) (xy -24.0157 -2.5654) (xy -24.0157 2.5654) (xy -20.7264 2.5654)
				(xy -20.7264 9.906) (xy -17.5895 9.906) (xy -17.5895 8.2042) (xy 17.5895 8.2042) (xy 17.5895 9.906)
				(xy 20.7264 9.906) (xy 20.7264 2.5654) (xy 24.0157 2.5654) (xy 24.0157 -2.5654) (xy 20.7264 -2.5654)
				(xy 20.7264 -6.0198)
			)
			(stroke
				(width 0)
				(type default)
			)
			(fill no)
			(layer "F.Fab")
		)
		(pad "" np_thru_hole circle
			(at -18.999962 -2.350008 90)
			(size 0.254 0.254)
			(drill 1.8542)
			(layers "*.Cu" "*.Mask")
			(clearance 1.1557)
			(thermal_gap 1.1557)
		)
		(pad "" np_thru_hole circle
			(at 18.999962 -2.350008 90)
			(size 0.254 0.254)
			(drill 1.8542)
			(layers "*.Cu" "*.Mask")
			(clearance 1.1557)
			(thermal_gap 1.1557)
		)
		(pad "H1" thru_hole oval
			(at -21.999956 0 90)
			(size 1.524 2.6162)
			(drill oval 0.8128 1.905)
			(layers "*.Cu" "*.Mask")
			(remove_unused_layers no)
			(net "GND")
			(clearance 0.1524)
			(thermal_gap 0.1524)
		)
		(pad "H2" thru_hole oval
			(at 21.999956 0 90)
			(size 1.524 2.6162)
			(drill oval 0.8128 1.905)
			(layers "*.Cu" "*.Mask")
			(remove_unused_layers no)
			(net "GND")
			(clearance 0.1524)
			(thermal_gap 0.1524)
		)
		(pad "P1" smd rect
			(at -1.89992 -4.249928 90)
			(size 0.6604 2.3876)
			(layers "F.Cu" "F.Mask" "F.Paste")
			(net "Net_35")
		)
		(pad "P2" smd rect
			(at -0.62992 -4.249928 90)
			(size 0.6604 2.3876)
			(layers "F.Cu" "F.Mask" "F.Paste")
			(net "Net_34")
		)
		(pad "P3" smd rect
			(at 0.64008 -4.249928 90)
			(size 0.6604 2.3876)
			(layers "F.Cu" "F.Mask" "F.Paste")
			(net "Net_33")
		)
		(pad "P4" smd rect
			(at 1.91008 -4.249928 90)
			(size 0.6604 2.3876)
			(layers "F.Cu" "F.Mask" "F.Paste")
			(net "GND")
		)
		(pad "P5" smd rect
			(at 3.18008 -4.249928 90)
			(size 0.6604 2.3876)
			(layers "F.Cu" "F.Mask" "F.Paste")
			(net "HDD_PRSNT_NET2")
		)
		(pad "P6" smd rect
			(at 4.45008 -4.249928 90)
			(size 0.6604 2.3876)
			(layers "F.Cu" "F.Mask" "F.Paste")
			(net "GND")
		)
		(pad "P7" smd rect
			(at 5.72008 -4.249928 90)
			(size 0.6604 2.3876)
			(layers "F.Cu" "F.Mask" "F.Paste")
			(net "5V_PRE_2")
		)
		(pad "P8" smd rect
			(at 6.99008 -4.249928 90)
			(size 0.6604 2.3876)
			(layers "F.Cu" "F.Mask" "F.Paste")
			(net "P5V_HDD2")
		)
		(pad "P9" smd rect
			(at 8.26008 -4.249928 90)
			(size 0.6604 2.3876)
			(layers "F.Cu" "F.Mask" "F.Paste")
			(net "P5V_HDD2")
		)
		(pad "P10" smd rect
			(at 9.53008 -4.249928 90)
			(size 0.6604 2.3876)
			(layers "F.Cu" "F.Mask" "F.Paste")
			(net "GND")
		)
		(pad "P11" smd rect
			(at 10.80008 -4.249928 90)
			(size 0.6604 2.3876)
			(layers "F.Cu" "F.Mask" "F.Paste")
			(net "ACT_HDD2")
		)
		(pad "P12" smd rect
			(at 12.07008 -4.249928 90)
			(size 0.6604 2.3876)
			(layers "F.Cu" "F.Mask" "F.Paste")
			(net "GND")
		)
		(pad "P13" smd rect
			(at 13.34008 -4.249928 90)
			(size 0.6604 2.3876)
			(layers "F.Cu" "F.Mask" "F.Paste")
			(net "12V_PRE_2")
		)
		(pad "P14" smd rect
			(at 14.61008 -4.249928 90)
			(size 0.6604 2.3876)
			(layers "F.Cu" "F.Mask" "F.Paste")
			(net "P12V_HDD2")
		)
		(pad "P15" smd rect
			(at 15.88008 -4.249928 90)
			(size 0.6604 2.3876)
			(layers "F.Cu" "F.Mask" "F.Paste")
			(net "P12V_HDD2")
		)
		(pad "S1" smd rect
			(at -15.86992 -4.249928 90)
			(size 0.6604 2.3876)
			(layers "F.Cu" "F.Mask" "F.Paste")
			(net "GND")
		)
		(pad "S2" smd rect
			(at -14.59992 -4.249928 90)
			(size 0.6604 2.3876)
			(layers "F.Cu" "F.Mask" "F.Paste")
			(net "SAS2X28_A_HDD2_TX_+")
		)
		(pad "S3" smd rect
			(at -13.32992 -4.249928 90)
			(size 0.6604 2.3876)
			(layers "F.Cu" "F.Mask" "F.Paste")
			(net "SAS2X28_A_HDD2_TX_-")
		)
		(pad "S4" smd rect
			(at -12.05992 -4.249928 90)
			(size 0.6604 2.3876)
			(layers "F.Cu" "F.Mask" "F.Paste")
			(net "GND")
		)
		(pad "S5" smd rect
			(at -10.78992 -4.249928 90)
			(size 0.6604 2.3876)
			(layers "F.Cu" "F.Mask" "F.Paste")
			(net "SAS2X28_DRIVE_RX_N_A2")
		)
		(pad "S6" smd rect
			(at -9.51992 -4.249928 90)
			(size 0.6604 2.3876)
			(layers "F.Cu" "F.Mask" "F.Paste")
			(net "SAS2X28_DRIVE_RX_P_A2")
		)
		(pad "S7" smd rect
			(at -8.24992 -4.249928 90)
			(size 0.6604 2.3876)
			(layers "F.Cu" "F.Mask" "F.Paste")
			(net "GND")
		)
		(pad "S8" smd rect
			(at -7.480046 -2.100072 90)
			(size 0.508 1.905)
			(layers "F.Cu" "F.Mask" "F.Paste")
			(net "GND")
		)
		(pad "S9" smd rect
			(at -6.679946 -2.100072 90)
			(size 0.508 1.905)
			(layers "F.Cu" "F.Mask" "F.Paste")
			(net "SAS2X28_B_HDD2_TX_+")
		)
		(pad "S10" smd rect
			(at -5.8801 -2.100072 90)
			(size 0.508 1.905)
			(layers "F.Cu" "F.Mask" "F.Paste")
			(net "SAS2X28_B_HDD2_TX_-")
		)
		(pad "S11" smd rect
			(at -5.08 -2.100072 90)
			(size 0.508 1.905)
			(layers "F.Cu" "F.Mask" "F.Paste")
			(net "GND")
		)
		(pad "S12" smd rect
			(at -4.2799 -2.100072 90)
			(size 0.508 1.905)
			(layers "F.Cu" "F.Mask" "F.Paste")
			(net "SAS2X28_DRIVE_RX_N_B2")
		)
		(pad "S13" smd rect
			(at -3.480054 -2.100072 90)
			(size 0.508 1.905)
			(layers "F.Cu" "F.Mask" "F.Paste")
			(net "SAS2X28_DRIVE_RX_P_B2")
		)
		(pad "S14" smd rect
			(at -2.679954 -2.100072 90)
			(size 0.508 1.905)
			(layers "F.Cu" "F.Mask" "F.Paste")
			(net "GND")
		)
		(zone
			(layers "F.Cu" "B.Cu" "In1.Cu" "In2.Cu" "In3.Cu" "In4.Cu" "In5.Cu" "In6.Cu")
			(hatch none 0.5)
			(connect_pads
				(clearance 0)
			)
			(min_thickness 0.25)
			(keepout
				(tracks not_allowed)
				(vias allowed)
				(pads allowed)
				(copperpour not_allowed)
				(footprints allowed)
			)
			(placement
				(enabled no)
				(sheetname "")
			)
			(fill
				(thermal_gap 0.5)
				(thermal_bridge_width 0.5)
				(island_removal_mode 0)
			)
			(polygon
				(pts
					(arc
						(start 226.381818 -292.669976)
						(mid 223.918018 -292.669976)
						(end 226.381818 -292.669976)
					)
				)
			)
		)
		(zone
			(layers "F.Cu" "B.Cu" "In1.Cu" "In2.Cu" "In3.Cu" "In4.Cu" "In5.Cu" "In6.Cu")
			(hatch none 0.5)
			(connect_pads
				(clearance 0)
			)
			(min_thickness 0.25)
			(keepout
				(tracks not_allowed)
				(vias allowed)
				(pads allowed)
				(copperpour not_allowed)
				(footprints allowed)
			)
			(placement
				(enabled no)
				(sheetname "")
			)
			(fill
				(thermal_gap 0.5)
				(thermal_bridge_width 0.5)
				(island_removal_mode 0)
			)
			(polygon
				(pts
					(arc
						(start 226.381818 -254.670052)
						(mid 223.918018 -254.670052)
						(end 226.381818 -254.670052)
					)
				)
			)
		)
	)
	(footprint ""
		(layer "F.Cu")
		(at 29.971746 -292.8112 180)
		(property "Reference" "R209"
			(at 0 0 180)
			(layer "F.SilkS")
			(hide yes)
			(effects
				(font
					(size 1.27 1.27)
				)
			)
		)
		(property "Value" "2R2010J-1-GP"
			(at 0.254 -8.0772 180)
			(unlocked yes)
			(layer "F.Fab")
			(hide yes)
			(effects
				(font
					(size 1.016 1.016)
					(thickness 0.1524)
				)
			)
		)
		(property "Device Type" "R2010H28"
			(at 0.254 -9.6774 180)
			(unlocked yes)
			(layer "F.Fab")
			(hide yes)
			(effects
				(font
					(size 1.016 1.016)
					(thickness 0.1524)
				)
			)
		)
		(duplicate_pad_numbers_are_jumpers no)
		(fp_line
			(start 1.651 3.302)
			(end 1.651 -3.302)
			(stroke
				(width 0.1524)
				(type default)
			)
			(layer "F.SilkS")
		)
		(fp_line
			(start 1.651 -3.302)
			(end -1.651 -3.302)
			(stroke
				(width 0.1524)
				(type default)
			)
			(layer "F.SilkS")
		)
		(fp_line
			(start -1.651 3.302)
			(end 1.651 3.302)
			(stroke
				(width 0.1524)
				(type default)
			)
			(layer "F.SilkS")
		)
		(fp_line
			(start -1.651 -3.302)
			(end -1.651 3.302)
			(stroke
				(width 0.1524)
				(type default)
			)
			(layer "F.SilkS")
		)
		(fp_rect
			(start -1.7272 -3.3782)
			(end 1.7272 3.3782)
			(stroke
				(width 0)
				(type default)
			)
			(fill no)
			(layer "F.CrtYd")
		)
		(fp_poly
			(pts
				(xy 1.7272 3.3782) (xy 1.7272 -3.3782) (xy -1.7272 -3.3782) (xy -1.7272 3.3782)
			)
			(stroke
				(width 0)
				(type default)
			)
			(fill no)
			(layer "F.Fab")
		)
		(pad "1" smd rect
			(at 0 -2.3495 180)
			(size 2.794 1.143)
			(layers "F.Cu" "F.Mask" "F.Paste")
			(net "12V_PRE_7")
		)
		(pad "2" smd rect
			(at 0 2.3495 180)
			(size 2.794 1.143)
			(layers "F.Cu" "F.Mask" "F.Paste")
			(net "P12V_HDD7")
		)
	)
	(footprint ""
		(layer "F.Cu")
		(at 26.02103 -139.061952 90)
		(property "Reference" "C311"
			(at 0 0 90)
			(layer "F.SilkS")
			(hide yes)
			(effects
				(font
					(size 1.27 1.27)
				)
			)
		)
		(property "Value" "SCD01U50V2KX-1GP"
			(at 1.1811 -2.7051 90)
			(unlocked yes)
			(layer "F.Fab")
			(hide yes)
			(effects
				(font
					(size 1.016 1.016)
					(thickness 0.1524)
				)
			)
		)
		(property "Device Type" "C402H22"
			(at 1.1811 -4.2291 90)
			(unlocked yes)
			(layer "F.Fab")
			(hide yes)
			(effects
				(font
					(size 1.016 1.016)
					(thickness 0.1524)
				)
			)
		)
		(duplicate_pad_numbers_are_jumpers no)
		(fp_rect
			(start -0.4318 0.9525)
			(end 0.4318 -0.9525)
			(stroke
				(width 0)
				(type default)
			)
			(fill no)
			(layer "F.CrtYd")
		)
		(fp_rect
			(start -0.4318 0.9525)
			(end 0.4318 -0.9525)
			(stroke
				(width 0)
				(type default)
			)
			(fill no)
			(layer "F.Fab")
		)
		(pad "1" smd custom
			(at 0 -0.4445 90)
			(size 0.1524 0.1524)
			(layers "F.Cu" "F.Mask" "F.Paste")
			(net "SAS2X28_DRIVE_RX_P_A13")
			(options
				(clearance outline)
				(anchor circle)
			)
			(primitives
				(gr_poly
					(pts
						(arc
							(start 0.3048 -0.2032)
							(mid 0.275042 -0.275042)
							(end 0.2032 -0.3048)
						)
						(arc
							(start -0.2032 -0.3048)
							(mid -0.275042 -0.275042)
							(end -0.3048 -0.2032)
						)
						(arc
							(start -0.3048 0.2032)
							(mid -0.275042 0.275042)
							(end -0.2032 0.3048)
						)
						(arc
							(start 0.2032 0.3048)
							(mid 0.275042 0.275042)
							(end 0.3048 0.2032)
						)
					)
					(width 0)
					(fill yes)
				)
			)
		)
		(pad "2" smd custom
			(at 0 0.4445 90)
			(size 0.1524 0.1524)
			(layers "F.Cu" "F.Mask" "F.Paste")
			(net "SAS2X28_A_HDD13_RX_+")
			(options
				(clearance outline)
				(anchor circle)
			)
			(primitives
				(gr_poly
					(pts
						(arc
							(start 0.3048 -0.2032)
							(mid 0.275042 -0.275042)
							(end 0.2032 -0.3048)
						)
						(arc
							(start -0.2032 -0.3048)
							(mid -0.275042 -0.275042)
							(end -0.3048 -0.2032)
						)
						(arc
							(start -0.3048 0.2032)
							(mid -0.275042 0.275042)
							(end -0.2032 0.3048)
						)
						(arc
							(start 0.2032 0.3048)
							(mid 0.275042 0.275042)
							(end 0.3048 0.2032)
						)
					)
					(width 0)
					(fill yes)
				)
			)
		)
	)
	(footprint ""
		(layer "F.Cu")
		(at 30.225746 -387.4897)
		(property "Reference" "TP31"
			(at 0 0 0)
			(layer "F.SilkS")
			(hide yes)
			(effects
				(font
					(size 1.27 1.27)
				)
			)
		)
		(property "Value" "TPAD32-GP"
			(at 0 -3.166364 0)
			(unlocked yes)
			(layer "F.Fab")
			(hide yes)
			(effects
				(font
					(size 1.016 1.016)
					(thickness 0.1524)
				)
			)
		)
		(property "Device Type" "TPAD32"
			(at 0 -4.690618 0)
			(unlocked yes)
			(layer "F.Fab")
			(hide yes)
			(effects
				(font
					(size 1.016 1.016)
					(thickness 0.1524)
				)
			)
		)
		(duplicate_pad_numbers_are_jumpers no)
		(fp_poly
			(pts
				(arc
					(start 0.4064 0)
					(mid -0.4064 0)
					(end 0.4064 0)
				)
			)
			(stroke
				(width 0)
				(type default)
			)
			(fill no)
			(layer "F.CrtYd")
		)
		(fp_poly
			(pts
				(arc
					(start 0.7112 0)
					(mid -0.7112 0)
					(end 0.7112 0)
				)
			)
			(stroke
				(width 0)
				(type default)
			)
			(fill no)
			(layer "F.Fab")
		)
		(pad "1" smd circle
			(at 0 0)
			(size 0.8128 0.8128)
			(layers "F.Cu" "F.Mask" "F.Paste")
			(net "ACT_HDD6")
		)
	)
	(footprint ""
		(layer "F.Cu")
		(at 30.608778 -336.091784)
		(property "Reference" "R465"
			(at 0 0 0)
			(layer "F.SilkS")
			(hide yes)
			(effects
				(font
					(size 1.27 1.27)
				)
			)
		)
		(property "Value" "4K7R2J-2-GP"
			(at 0.064008 -3.993896 0)
			(unlocked yes)
			(layer "F.Fab")
			(hide yes)
			(effects
				(font
					(size 1.016 1.016)
					(thickness 0.1524)
				)
			)
		)
		(property "Device Type" "R402H16"
			(at 0.064008 -5.517896 0)
			(unlocked yes)
			(layer "F.Fab")
			(hide yes)
			(effects
				(font
					(size 1.016 1.016)
					(thickness 0.1524)
				)
			)
		)
		(duplicate_pad_numbers_are_jumpers no)
		(fp_line
			(start -0.508 -0.9398)
			(end -0.508 0.9398)
			(stroke
				(width 0.1524)
				(type default)
			)
			(layer "F.SilkS")
		)
		(fp_line
			(start 0.508 -0.9398)
			(end -0.508 -0.9398)
			(stroke
				(width 0.1524)
				(type default)
			)
			(layer "F.SilkS")
		)
		(fp_rect
			(start -0.508 0.9398)
			(end 0.508 -0.9398)
			(stroke
				(width 0)
				(type default)
			)
			(fill no)
			(layer "F.CrtYd")
		)
		(fp_rect
			(start -0.508 0.9398)
			(end 0.508 -0.9398)
			(stroke
				(width 0)
				(type default)
			)
			(fill no)
			(layer "F.Fab")
		)
		(pad "1" smd custom
			(at 0 -0.4445)
			(size 0.1397 0.1397)
			(layers "F.Cu" "F.Mask" "F.Paste")
			(net "P3V3")
			(options
				(clearance outline)
				(anchor circle)
			)
			(primitives
				(gr_poly
					(pts
						(arc
							(start -0.1778 -0.2794)
							(mid -0.249642 -0.249642)
							(end -0.2794 -0.1778)
						)
						(arc
							(start -0.2794 0.1778)
							(mid -0.249642 0.249642)
							(end -0.1778 0.2794)
						)
						(arc
							(start 0.1778 0.2794)
							(mid 0.249642 0.249642)
							(end 0.2794 0.1778)
						)
						(arc
							(start 0.2794 -0.1778)
							(mid 0.249642 -0.249642)
							(end 0.1778 -0.2794)
						)
					)
					(width 0)
					(fill yes)
				)
			)
		)
		(pad "2" smd custom
			(at 0 0.4445)
			(size 0.1397 0.1397)
			(layers "F.Cu" "F.Mask" "F.Paste")
			(net "SAS2X28_B_HDD11_FLT")
			(options
				(clearance outline)
				(anchor circle)
			)
			(primitives
				(gr_poly
					(pts
						(arc
							(start -0.1778 -0.2794)
							(mid -0.249642 -0.249642)
							(end -0.2794 -0.1778)
						)
						(arc
							(start -0.2794 0.1778)
							(mid -0.249642 0.249642)
							(end -0.1778 0.2794)
						)
						(arc
							(start 0.1778 0.2794)
							(mid 0.249642 0.249642)
							(end 0.2794 0.1778)
						)
						(arc
							(start 0.2794 -0.1778)
							(mid 0.249642 -0.249642)
							(end 0.1778 -0.2794)
						)
					)
					(width 0)
					(fill yes)
				)
			)
		)
	)
	(footprint ""
		(layer "F.Cu")
		(at 210.819746 -42.4307 -90)
		(property "Reference" "R341"
			(at 0 0 270)
			(layer "F.SilkS")
			(hide yes)
			(effects
				(font
					(size 1.27 1.27)
				)
			)
		)
		(property "Value" "4K7R2J-2-GP"
			(at 0.064008 -3.993896 270)
			(unlocked yes)
			(layer "F.Fab")
			(hide yes)
			(effects
				(font
					(size 1.016 1.016)
					(thickness 0.1524)
				)
			)
		)
		(property "Device Type" "R402H16"
			(at 0.064008 -5.517896 270)
			(unlocked yes)
			(layer "F.Fab")
			(hide yes)
			(effects
				(font
					(size 1.016 1.016)
					(thickness 0.1524)
				)
			)
		)
		(duplicate_pad_numbers_are_jumpers no)
		(fp_line
			(start -0.508 -0.9398)
			(end -0.508 0.9398)
			(stroke
				(width 0.1524)
				(type default)
			)
			(layer "F.SilkS")
		)
		(fp_line
			(start 0.508 -0.9398)
			(end -0.508 -0.9398)
			(stroke
				(width 0.1524)
				(type default)
			)
			(layer "F.SilkS")
		)
		(fp_rect
			(start -0.508 0.9398)
			(end 0.508 -0.9398)
			(stroke
				(width 0)
				(type default)
			)
			(fill no)
			(layer "F.CrtYd")
		)
		(fp_rect
			(start -0.508 0.9398)
			(end 0.508 -0.9398)
			(stroke
				(width 0)
				(type default)
			)
			(fill no)
			(layer "F.Fab")
		)
		(pad "1" smd custom
			(at 0 -0.4445 270)
			(size 0.1397 0.1397)
			(layers "F.Cu" "F.Mask" "F.Paste")
			(net "I2C_B_TMP4_A0")
			(options
				(clearance outline)
				(anchor circle)
			)
			(primitives
				(gr_poly
					(pts
						(arc
							(start -0.1778 -0.2794)
							(mid -0.249642 -0.249642)
							(end -0.2794 -0.1778)
						)
						(arc
							(start -0.2794 0.1778)
							(mid -0.249642 0.249642)
							(end -0.1778 0.2794)
						)
						(arc
							(start 0.1778 0.2794)
							(mid 0.249642 0.249642)
							(end 0.2794 0.1778)
						)
						(arc
							(start 0.2794 -0.1778)
							(mid 0.249642 -0.249642)
							(end 0.1778 -0.2794)
						)
					)
					(width 0)
					(fill yes)
				)
			)
		)
		(pad "2" smd custom
			(at 0 0.4445 270)
			(size 0.1397 0.1397)
			(layers "F.Cu" "F.Mask" "F.Paste")
			(net "GND")
			(options
				(clearance outline)
				(anchor circle)
			)
			(primitives
				(gr_poly
					(pts
						(arc
							(start -0.1778 -0.2794)
							(mid -0.249642 -0.249642)
							(end -0.2794 -0.1778)
						)
						(arc
							(start -0.2794 0.1778)
							(mid -0.249642 0.249642)
							(end -0.1778 0.2794)
						)
						(arc
							(start 0.1778 0.2794)
							(mid 0.249642 0.249642)
							(end 0.2794 0.1778)
						)
						(arc
							(start 0.2794 -0.1778)
							(mid 0.249642 -0.249642)
							(end 0.1778 -0.2794)
						)
					)
					(width 0)
					(fill yes)
				)
			)
		)
	)
	(footprint ""
		(layer "F.Cu")
		(at 27.2923 -342.4174 -90)
		(property "Reference" "C39"
			(at 0 0 270)
			(layer "F.SilkS")
			(hide yes)
			(effects
				(font
					(size 1.27 1.27)
				)
			)
		)
		(property "Value" "SCD01U50V2KX-1GP"
			(at 1.1811 -2.7051 270)
			(unlocked yes)
			(layer "F.Fab")
			(hide yes)
			(effects
				(font
					(size 1.016 1.016)
					(thickness 0.1524)
				)
			)
		)
		(property "Device Type" "C402H22"
			(at 1.1811 -4.2291 270)
			(unlocked yes)
			(layer "F.Fab")
			(hide yes)
			(effects
				(font
					(size 1.016 1.016)
					(thickness 0.1524)
				)
			)
		)
		(duplicate_pad_numbers_are_jumpers no)
		(fp_rect
			(start -0.4318 0.9525)
			(end 0.4318 -0.9525)
			(stroke
				(width 0)
				(type default)
			)
			(fill no)
			(layer "F.CrtYd")
		)
		(fp_rect
			(start -0.4318 0.9525)
			(end 0.4318 -0.9525)
			(stroke
				(width 0)
				(type default)
			)
			(fill no)
			(layer "F.Fab")
		)
		(pad "1" smd custom
			(at 0 -0.4445 270)
			(size 0.1524 0.1524)
			(layers "F.Cu" "F.Mask" "F.Paste")
			(net "SEB_AB_TX-")
			(options
				(clearance outline)
				(anchor circle)
			)
			(primitives
				(gr_poly
					(pts
						(arc
							(start 0.3048 -0.2032)
							(mid 0.275042 -0.275042)
							(end 0.2032 -0.3048)
						)
						(arc
							(start -0.2032 -0.3048)
							(mid -0.275042 -0.275042)
							(end -0.3048 -0.2032)
						)
						(arc
							(start -0.3048 0.2032)
							(mid -0.275042 0.275042)
							(end -0.2032 0.3048)
						)
						(arc
							(start 0.2032 0.3048)
							(mid 0.275042 0.275042)
							(end 0.3048 0.2032)
						)
					)
					(width 0)
					(fill yes)
				)
			)
		)
		(pad "2" smd custom
			(at 0 0.4445 270)
			(size 0.1524 0.1524)
			(layers "F.Cu" "F.Mask" "F.Paste")
			(net "SEB_AB_RX-")
			(options
				(clearance outline)
				(anchor circle)
			)
			(primitives
				(gr_poly
					(pts
						(arc
							(start 0.3048 -0.2032)
							(mid 0.275042 -0.275042)
							(end 0.2032 -0.3048)
						)
						(arc
							(start -0.2032 -0.3048)
							(mid -0.275042 -0.275042)
							(end -0.3048 -0.2032)
						)
						(arc
							(start -0.3048 0.2032)
							(mid -0.275042 0.275042)
							(end -0.2032 0.3048)
						)
						(arc
							(start 0.2032 0.3048)
							(mid 0.275042 0.275042)
							(end 0.3048 0.2032)
						)
					)
					(width 0)
					(fill yes)
				)
			)
		)
	)
	(footprint ""
		(layer "F.Cu")
		(at 211.454746 -491.6297)
		(property "Reference" "C112"
			(at 0 0 0)
			(layer "F.SilkS")
			(hide yes)
			(effects
				(font
					(size 1.27 1.27)
				)
			)
		)
		(property "Value" "SC10U25V6KX-1GP"
			(at -0.0762 -5.1308 0)
			(unlocked yes)
			(layer "F.Fab")
			(hide yes)
			(effects
				(font
					(size 1.016 1.016)
					(thickness 0.1524)
				)
			)
		)
		(property "Device Type" "C1206H71"
			(at -0.127 -6.6548 0)
			(unlocked yes)
			(layer "F.Fab")
			(hide yes)
			(effects
				(font
					(size 1.016 1.016)
					(thickness 0.1524)
				)
			)
		)
		(duplicate_pad_numbers_are_jumpers no)
		(fp_line
			(start -1.016 -2.2352)
			(end 1.016 -2.2352)
			(stroke
				(width 0.1524)
				(type default)
			)
			(layer "F.SilkS")
		)
		(fp_line
			(start -1.016 -0.8382)
			(end -1.016 -2.2352)
			(stroke
				(width 0.1524)
				(type default)
			)
			(layer "F.SilkS")
		)
		(fp_line
			(start -1.016 2.2352)
			(end -1.016 0.8382)
			(stroke
				(width 0.1524)
				(type default)
			)
			(layer "F.SilkS")
		)
		(fp_line
			(start 1.016 -2.2352)
			(end 1.016 -0.8382)
			(stroke
				(width 0.1524)
				(type default)
			)
			(layer "F.SilkS")
		)
		(fp_line
			(start 1.016 0.8382)
			(end 1.016 2.2352)
			(stroke
				(width 0.1524)
				(type default)
			)
			(layer "F.SilkS")
		)
		(fp_line
			(start 1.016 2.2352)
			(end -1.016 2.2352)
			(stroke
				(width 0.1524)
				(type default)
			)
			(layer "F.SilkS")
		)
		(fp_rect
			(start -1.0922 2.3114)
			(end 1.0922 -2.3114)
			(stroke
				(width 0)
				(type default)
			)
			(fill no)
			(layer "F.CrtYd")
		)
		(fp_poly
			(pts
				(xy 1.0922 -2.3114) (xy 1.0922 2.3114) (xy -1.0922 2.3114) (xy -1.0922 -2.3114)
			)
			(stroke
				(width 0)
				(type default)
			)
			(fill no)
			(layer "F.Fab")
		)
		(pad "1" smd rect
			(at 0 -1.397)
			(size 1.651 1.27)
			(layers "F.Cu" "F.Mask" "F.Paste")
			(net "P12V_HDD0")
		)
		(pad "2" smd rect
			(at 0 1.397)
			(size 1.651 1.27)
			(layers "F.Cu" "F.Mask" "F.Paste")
			(net "GND")
		)
	)
	(footprint ""
		(layer "F.Cu")
		(at 73.405746 -183.7817)
		(property "Reference" "TP33"
			(at 0 0 0)
			(layer "F.SilkS")
			(hide yes)
			(effects
				(font
					(size 1.27 1.27)
				)
			)
		)
		(property "Value" "TPAD32-GP"
			(at 0 -3.166364 0)
			(unlocked yes)
			(layer "F.Fab")
			(hide yes)
			(effects
				(font
					(size 1.016 1.016)
					(thickness 0.1524)
				)
			)
		)
		(property "Device Type" "TPAD32"
			(at 0 -4.690618 0)
			(unlocked yes)
			(layer "F.Fab")
			(hide yes)
			(effects
				(font
					(size 1.016 1.016)
					(thickness 0.1524)
				)
			)
		)
		(duplicate_pad_numbers_are_jumpers no)
		(fp_poly
			(pts
				(arc
					(start 0.4064 0)
					(mid -0.4064 0)
					(end 0.4064 0)
				)
			)
			(stroke
				(width 0)
				(type default)
			)
			(fill no)
			(layer "F.CrtYd")
		)
		(fp_poly
			(pts
				(arc
					(start 0.7112 0)
					(mid -0.7112 0)
					(end 0.7112 0)
				)
			)
			(stroke
				(width 0)
				(type default)
			)
			(fill no)
			(layer "F.Fab")
		)
		(pad "1" smd circle
			(at 0 0)
			(size 0.8128 0.8128)
			(layers "F.Cu" "F.Mask" "F.Paste")
			(net "ACT_HDD8")
		)
	)
	(footprint ""
		(layer "F.Cu")
		(at 200.024746 -184.2897)
		(property "Reference" "U10"
			(at 0 0 0)
			(layer "F.SilkS")
			(hide yes)
			(effects
				(font
					(size 1.27 1.27)
				)
			)
		)
		(property "Value" "74LVC1G08GW-1-GP"
			(at -2.3368 -8.6868 0)
			(unlocked yes)
			(layer "F.Fab")
			(hide yes)
			(effects
				(font
					(size 1.016 1.016)
					(thickness 0.1524)
				)
			)
		)
		(property "Device Type" "SC70-5H44"
			(at -2.3114 -10.414 0)
			(unlocked yes)
			(layer "F.Fab")
			(hide yes)
			(effects
				(font
					(size 1.016 1.016)
					(thickness 0.1524)
				)
			)
		)
		(duplicate_pad_numbers_are_jumpers no)
		(fp_line
			(start -1.27 -1.7018)
			(end 1.27 -1.7018)
			(stroke
				(width 0.1524)
				(type default)
			)
			(layer "F.SilkS")
		)
		(fp_line
			(start -1.27 1.7018)
			(end -1.27 -1.7018)
			(stroke
				(width 0.1524)
				(type default)
			)
			(layer "F.SilkS")
		)
		(fp_line
			(start 0.6604 -1.8034)
			(end 1.3843 -1.8034)
			(stroke
				(width 0.3302)
				(type default)
			)
			(layer "F.SilkS")
		)
		(fp_line
			(start 1.27 -1.7018)
			(end 1.27 1.7018)
			(stroke
				(width 0.1524)
				(type default)
			)
			(layer "F.SilkS")
		)
		(fp_line
			(start 1.27 1.7018)
			(end -1.27 1.7018)
			(stroke
				(width 0.1524)
				(type default)
			)
			(layer "F.SilkS")
		)
		(fp_line
			(start 1.3843 -1.8034)
			(end 1.3843 -1.1176)
			(stroke
				(width 0.3302)
				(type default)
			)
			(layer "F.SilkS")
		)
		(fp_rect
			(start -1.524 1.9558)
			(end 1.524 -1.9558)
			(stroke
				(width 0)
				(type default)
			)
			(fill no)
			(layer "F.CrtYd")
		)
		(fp_poly
			(pts
				(xy -1.524 -1.9558) (xy 1.524 -1.9558) (xy 1.524 1.9558) (xy -1.524 1.9558)
			)
			(stroke
				(width 0)
				(type default)
			)
			(fill no)
			(layer "F.Fab")
		)
		(pad "1" smd rect
			(at 0.65024 -0.8255)
			(size 0.4064 1.2192)
			(layers "F.Cu" "F.Mask" "F.Paste")
			(net "SAS2X28_B_HDD3_FLT")
		)
		(pad "2" smd rect
			(at 0 -0.8255)
			(size 0.4064 1.2192)
			(layers "F.Cu" "F.Mask" "F.Paste")
			(net "SAS2X28_A_HDD3_FLT")
		)
		(pad "3" smd rect
			(at -0.65024 -0.8255)
			(size 0.4064 1.2192)
			(layers "F.Cu" "F.Mask" "F.Paste")
			(net "GND")
		)
		(pad "4" smd rect
			(at -0.65024 0.8255)
			(size 0.4064 1.2192)
			(layers "F.Cu" "F.Mask" "F.Paste")
			(net "FLT_HDD3_DRIVE")
		)
		(pad "5" smd rect
			(at 0.65024 0.8255)
			(size 0.4064 1.2192)
			(layers "F.Cu" "F.Mask" "F.Paste")
			(net "P3V3")
		)
	)
	(footprint ""
		(layer "F.Cu")
		(at 62.1284 -70.8152)
		(property "Reference" "Q64"
			(at 0 0 0)
			(layer "F.SilkS")
			(hide yes)
			(effects
				(font
					(size 1.27 1.27)
				)
			)
		)
		(property "Value" "2N7002DW-7F-GP"
			(at -2.3622 -8.2042 0)
			(unlocked yes)
			(layer "F.Fab")
			(hide yes)
			(effects
				(font
					(size 1.016 1.016)
					(thickness 0.1524)
				)
			)
		)
		(property "Device Type" "SOT-363H44"
			(at -2.3622 -10.1092 0)
			(unlocked yes)
			(layer "F.Fab")
			(hide yes)
			(effects
				(font
					(size 1.016 1.016)
					(thickness 0.1524)
				)
			)
		)
		(duplicate_pad_numbers_are_jumpers no)
		(fp_line
			(start -1.4478 -1.7018)
			(end -1.4478 1.7018)
			(stroke
				(width 0.1524)
				(type default)
			)
			(layer "F.SilkS")
		)
		(fp_line
			(start -1.4478 1.7018)
			(end 1.4478 1.7018)
			(stroke
				(width 0.1524)
				(type default)
			)
			(layer "F.SilkS")
		)
		(fp_line
			(start -1.27 1.524)
			(end -1.27 0.6604)
			(stroke
				(width 0.4826)
				(type default)
			)
			(layer "F.SilkS")
		)
		(fp_line
			(start 1.4478 -1.7018)
			(end -1.4478 -1.7018)
			(stroke
				(width 0.1524)
				(type default)
			)
			(layer "F.SilkS")
		)
		(fp_line
			(start 1.4478 1.7018)
			(end 1.4478 -1.7018)
			(stroke
				(width 0.1524)
				(type default)
			)
			(layer "F.SilkS")
		)
		(fp_poly
			(pts
				(xy -1.524 -1.778) (xy 1.524 -1.778) (xy 1.524 1.778) (xy -1.524 1.778)
			)
			(stroke
				(width 0)
				(type default)
			)
			(fill no)
			(layer "F.CrtYd")
		)
		(fp_poly
			(pts
				(xy -1.524 -1.778) (xy 1.524 -1.778) (xy 1.524 1.778) (xy -1.524 1.778)
			)
			(stroke
				(width 0)
				(type default)
			)
			(fill no)
			(layer "F.Fab")
		)
		(pad "1" smd rect
			(at -0.65024 0.9398)
			(size 0.4064 1.016)
			(layers "F.Cu" "F.Mask" "F.Paste")
			(net "P3V3_HDD9_LED")
		)
		(pad "2" smd rect
			(at 0 0.9398)
			(size 0.4064 1.016)
			(layers "F.Cu" "F.Mask" "F.Paste")
			(net "HDD9_LED_G")
		)
		(pad "3" smd rect
			(at 0.65024 0.9398)
			(size 0.4064 1.016)
			(layers "F.Cu" "F.Mask" "F.Paste")
			(net "P5VB")
		)
		(pad "4" smd rect
			(at 0.65024 -0.9398)
			(size 0.4064 1.016)
			(layers "F.Cu" "F.Mask" "F.Paste")
			(net "P5VB_HDD9_LED")
		)
		(pad "5" smd rect
			(at 0 -0.9398)
			(size 0.4064 1.016)
			(layers "F.Cu" "F.Mask" "F.Paste")
			(net "HDD9_LED_G")
		)
		(pad "6" smd rect
			(at -0.65024 -0.9398)
			(size 0.4064 1.016)
			(layers "F.Cu" "F.Mask" "F.Paste")
			(net "P3V3")
		)
	)
	(footprint ""
		(layer "F.Cu")
		(at 25.907746 -276.4917)
		(property "Reference" "R211"
			(at 0 0 0)
			(layer "F.SilkS")
			(hide yes)
			(effects
				(font
					(size 1.27 1.27)
				)
			)
		)
		(property "Value" "0R2J-2-GP"
			(at 0.064008 -3.993896 0)
			(unlocked yes)
			(layer "F.Fab")
			(hide yes)
			(effects
				(font
					(size 1.016 1.016)
					(thickness 0.1524)
				)
			)
		)
		(property "Device Type" "R402H16"
			(at 0.064008 -5.517896 0)
			(unlocked yes)
			(layer "F.Fab")
			(hide yes)
			(effects
				(font
					(size 1.016 1.016)
					(thickness 0.1524)
				)
			)
		)
		(duplicate_pad_numbers_are_jumpers no)
		(fp_line
			(start -0.508 -0.9398)
			(end -0.508 0.9398)
			(stroke
				(width 0.1524)
				(type default)
			)
			(layer "F.SilkS")
		)
		(fp_line
			(start 0.508 -0.9398)
			(end -0.508 -0.9398)
			(stroke
				(width 0.1524)
				(type default)
			)
			(layer "F.SilkS")
		)
		(fp_rect
			(start -0.508 0.9398)
			(end 0.508 -0.9398)
			(stroke
				(width 0)
				(type default)
			)
			(fill no)
			(layer "F.CrtYd")
		)
		(fp_rect
			(start -0.508 0.9398)
			(end 0.508 -0.9398)
			(stroke
				(width 0)
				(type default)
			)
			(fill no)
			(layer "F.Fab")
		)
		(pad "1" smd custom
			(at 0 -0.4445)
			(size 0.1397 0.1397)
			(layers "F.Cu" "F.Mask" "F.Paste")
			(net "DRIVE_PWR7")
			(options
				(clearance outline)
				(anchor circle)
			)
			(primitives
				(gr_poly
					(pts
						(arc
							(start -0.1778 -0.2794)
							(mid -0.249642 -0.249642)
							(end -0.2794 -0.1778)
						)
						(arc
							(start -0.2794 0.1778)
							(mid -0.249642 0.249642)
							(end -0.1778 0.2794)
						)
						(arc
							(start 0.1778 0.2794)
							(mid 0.249642 0.249642)
							(end 0.2794 0.1778)
						)
						(arc
							(start 0.2794 -0.1778)
							(mid 0.249642 -0.249642)
							(end 0.1778 -0.2794)
						)
					)
					(width 0)
					(fill yes)
				)
			)
		)
		(pad "2" smd custom
			(at 0 0.4445)
			(size 0.1397 0.1397)
			(layers "F.Cu" "F.Mask" "F.Paste")
			(net "SW_PWR_HDD7")
			(options
				(clearance outline)
				(anchor circle)
			)
			(primitives
				(gr_poly
					(pts
						(arc
							(start -0.1778 -0.2794)
							(mid -0.249642 -0.249642)
							(end -0.2794 -0.1778)
						)
						(arc
							(start -0.2794 0.1778)
							(mid -0.249642 0.249642)
							(end -0.1778 0.2794)
						)
						(arc
							(start 0.1778 0.2794)
							(mid 0.249642 0.249642)
							(end 0.2794 0.1778)
						)
						(arc
							(start 0.2794 -0.1778)
							(mid 0.249642 -0.249642)
							(end 0.1778 -0.2794)
						)
					)
					(width 0)
					(fill yes)
				)
			)
		)
	)
	(footprint ""
		(layer "F.Cu")
		(at 41.147746 -110.645702 -90)
		(property "Reference" "Q28"
			(at 0 0 270)
			(layer "F.SilkS")
			(hide yes)
			(effects
				(font
					(size 1.27 1.27)
				)
			)
		)
		(property "Value" "2N7002DW-7F-GP"
			(at -2.3622 -8.2042 270)
			(unlocked yes)
			(layer "F.Fab")
			(hide yes)
			(effects
				(font
					(size 1.016 1.016)
					(thickness 0.1524)
				)
			)
		)
		(property "Device Type" "SOT-363H44"
			(at -2.3622 -10.1092 270)
			(unlocked yes)
			(layer "F.Fab")
			(hide yes)
			(effects
				(font
					(size 1.016 1.016)
					(thickness 0.1524)
				)
			)
		)
		(duplicate_pad_numbers_are_jumpers no)
		(fp_line
			(start -1.4478 1.7018)
			(end 1.4478 1.7018)
			(stroke
				(width 0.1524)
				(type default)
			)
			(layer "F.SilkS")
		)
		(fp_line
			(start 1.4478 1.7018)
			(end 1.4478 -1.7018)
			(stroke
				(width 0.1524)
				(type default)
			)
			(layer "F.SilkS")
		)
		(fp_line
			(start -1.27 1.524)
			(end -1.27 0.6604)
			(stroke
				(width 0.4826)
				(type default)
			)
			(layer "F.SilkS")
		)
		(fp_line
			(start -1.4478 -1.7018)
			(end -1.4478 1.7018)
			(stroke
				(width 0.1524)
				(type default)
			)
			(layer "F.SilkS")
		)
		(fp_line
			(start 1.4478 -1.7018)
			(end -1.4478 -1.7018)
			(stroke
				(width 0.1524)
				(type default)
			)
			(layer "F.SilkS")
		)
		(fp_poly
			(pts
				(xy -1.524 -1.778) (xy 1.524 -1.778) (xy 1.524 1.778) (xy -1.524 1.778)
			)
			(stroke
				(width 0)
				(type default)
			)
			(fill no)
			(layer "F.CrtYd")
		)
		(fp_poly
			(pts
				(xy -1.524 -1.778) (xy 1.524 -1.778) (xy 1.524 1.778) (xy -1.524 1.778)
			)
			(stroke
				(width 0)
				(type default)
			)
			(fill no)
			(layer "F.Fab")
		)
		(pad "1" smd rect
			(at -0.65024 0.9398 270)
			(size 0.4064 1.016)
			(layers "F.Cu" "F.Mask" "F.Paste")
			(net "GND")
		)
		(pad "2" smd rect
			(at 0 0.9398 270)
			(size 0.4064 1.016)
			(layers "F.Cu" "F.Mask" "F.Paste")
			(net "SW_PWR_R_HDD13")
		)
		(pad "3" smd rect
			(at 0.65024 0.9398 270)
			(size 0.4064 1.016)
			(layers "F.Cu" "F.Mask" "F.Paste")
			(net "SW_HDD13_P")
		)
		(pad "4" smd rect
			(at 0.65024 -0.9398 270)
			(size 0.4064 1.016)
			(layers "F.Cu" "F.Mask" "F.Paste")
			(net "GND")
		)
		(pad "5" smd rect
			(at 0 -0.9398 270)
			(size 0.4064 1.016)
			(layers "F.Cu" "F.Mask" "F.Paste")
			(net "SW_HDD13_G")
		)
		(pad "6" smd rect
			(at -0.65024 -0.9398 270)
			(size 0.4064 1.016)
			(layers "F.Cu" "F.Mask" "F.Paste")
			(net "SW_HDD13_R")
		)
	)
	(footprint ""
		(layer "F.Cu")
		(at 191.472058 -392.505184 180)
		(property "Reference" "R126"
			(at 0 0 180)
			(layer "F.SilkS")
			(hide yes)
			(effects
				(font
					(size 1.27 1.27)
				)
			)
		)
		(property "Value" "0R2J-2-GP"
			(at 0.064008 -3.993896 180)
			(unlocked yes)
			(layer "F.Fab")
			(hide yes)
			(effects
				(font
					(size 1.016 1.016)
					(thickness 0.1524)
				)
			)
		)
		(property "Device Type" "R402H16"
			(at 0.064008 -5.517896 180)
			(unlocked yes)
			(layer "F.Fab")
			(hide yes)
			(effects
				(font
					(size 1.016 1.016)
					(thickness 0.1524)
				)
			)
		)
		(duplicate_pad_numbers_are_jumpers no)
		(fp_line
			(start 0.508 -0.9398)
			(end -0.508 -0.9398)
			(stroke
				(width 0.1524)
				(type default)
			)
			(layer "F.SilkS")
		)
		(fp_line
			(start -0.508 -0.9398)
			(end -0.508 0.9398)
			(stroke
				(width 0.1524)
				(type default)
			)
			(layer "F.SilkS")
		)
		(fp_rect
			(start -0.508 0.9398)
			(end 0.508 -0.9398)
			(stroke
				(width 0)
				(type default)
			)
			(fill no)
			(layer "F.CrtYd")
		)
		(fp_rect
			(start -0.508 0.9398)
			(end 0.508 -0.9398)
			(stroke
				(width 0)
				(type default)
			)
			(fill no)
			(layer "F.Fab")
		)
		(pad "1" smd custom
			(at 0 -0.4445 180)
			(size 0.1397 0.1397)
			(layers "F.Cu" "F.Mask" "F.Paste")
			(net "SW_PWR_HDD1")
			(options
				(clearance outline)
				(anchor circle)
			)
			(primitives
				(gr_poly
					(pts
						(arc
							(start -0.1778 -0.2794)
							(mid -0.249642 -0.249642)
							(end -0.2794 -0.1778)
						)
						(arc
							(start -0.2794 0.1778)
							(mid -0.249642 0.249642)
							(end -0.1778 0.2794)
						)
						(arc
							(start 0.1778 0.2794)
							(mid 0.249642 0.249642)
							(end 0.2794 0.1778)
						)
						(arc
							(start 0.2794 -0.1778)
							(mid 0.249642 -0.249642)
							(end 0.1778 -0.2794)
						)
					)
					(width 0)
					(fill yes)
				)
			)
		)
		(pad "2" smd custom
			(at 0 0.4445 180)
			(size 0.1397 0.1397)
			(layers "F.Cu" "F.Mask" "F.Paste")
			(net "SW_PWR_R_HDD1")
			(options
				(clearance outline)
				(anchor circle)
			)
			(primitives
				(gr_poly
					(pts
						(arc
							(start -0.1778 -0.2794)
							(mid -0.249642 -0.249642)
							(end -0.2794 -0.1778)
						)
						(arc
							(start -0.2794 0.1778)
							(mid -0.249642 0.249642)
							(end -0.1778 0.2794)
						)
						(arc
							(start 0.1778 0.2794)
							(mid 0.249642 0.249642)
							(end 0.2794 0.1778)
						)
						(arc
							(start 0.2794 -0.1778)
							(mid 0.249642 -0.249642)
							(end 0.1778 -0.2794)
						)
					)
					(width 0)
					(fill yes)
				)
			)
		)
	)
	(footprint ""
		(layer "F.Cu")
		(at 214.933784 -173.198028 90)
		(property "Reference" "R150"
			(at 0 0 90)
			(layer "F.SilkS")
			(hide yes)
			(effects
				(font
					(size 1.27 1.27)
				)
			)
		)
		(property "Value" "4K7R2J-2-GP"
			(at 0.064008 -3.993896 90)
			(unlocked yes)
			(layer "F.Fab")
			(hide yes)
			(effects
				(font
					(size 1.016 1.016)
					(thickness 0.1524)
				)
			)
		)
		(property "Device Type" "R402H16"
			(at 0.064008 -5.517896 90)
			(unlocked yes)
			(layer "F.Fab")
			(hide yes)
			(effects
				(font
					(size 1.016 1.016)
					(thickness 0.1524)
				)
			)
		)
		(duplicate_pad_numbers_are_jumpers no)
		(fp_line
			(start 0.508 -0.9398)
			(end -0.508 -0.9398)
			(stroke
				(width 0.1524)
				(type default)
			)
			(layer "F.SilkS")
		)
		(fp_line
			(start -0.508 -0.9398)
			(end -0.508 0.9398)
			(stroke
				(width 0.1524)
				(type default)
			)
			(layer "F.SilkS")
		)
		(fp_rect
			(start -0.508 0.9398)
			(end 0.508 -0.9398)
			(stroke
				(width 0)
				(type default)
			)
			(fill no)
			(layer "F.CrtYd")
		)
		(fp_rect
			(start -0.508 0.9398)
			(end 0.508 -0.9398)
			(stroke
				(width 0)
				(type default)
			)
			(fill no)
			(layer "F.Fab")
		)
		(pad "1" smd custom
			(at 0 -0.4445 90)
			(size 0.1397 0.1397)
			(layers "F.Cu" "F.Mask" "F.Paste")
			(net "P3V3")
			(options
				(clearance outline)
				(anchor circle)
			)
			(primitives
				(gr_poly
					(pts
						(arc
							(start -0.1778 -0.2794)
							(mid -0.249642 -0.249642)
							(end -0.2794 -0.1778)
						)
						(arc
							(start -0.2794 0.1778)
							(mid -0.249642 0.249642)
							(end -0.1778 0.2794)
						)
						(arc
							(start 0.1778 0.2794)
							(mid 0.249642 0.249642)
							(end 0.2794 0.1778)
						)
						(arc
							(start 0.2794 -0.1778)
							(mid 0.249642 -0.249642)
							(end 0.1778 -0.2794)
						)
					)
					(width 0)
					(fill yes)
				)
			)
		)
		(pad "2" smd custom
			(at 0 0.4445 90)
			(size 0.1397 0.1397)
			(layers "F.Cu" "F.Mask" "F.Paste")
			(net "HDD_PRSNT_NET3")
			(options
				(clearance outline)
				(anchor circle)
			)
			(primitives
				(gr_poly
					(pts
						(arc
							(start -0.1778 -0.2794)
							(mid -0.249642 -0.249642)
							(end -0.2794 -0.1778)
						)
						(arc
							(start -0.2794 0.1778)
							(mid -0.249642 0.249642)
							(end -0.1778 0.2794)
						)
						(arc
							(start 0.1778 0.2794)
							(mid 0.249642 0.249642)
							(end 0.2794 0.1778)
						)
						(arc
							(start 0.2794 -0.1778)
							(mid 0.249642 -0.249642)
							(end 0.1778 -0.2794)
						)
					)
					(width 0)
					(fill yes)
				)
			)
		)
	)
	(footprint ""
		(layer "F.Cu")
		(at 46.017688 -21.989288 -90)
		(property "Reference" "PR32"
			(at 0 0 270)
			(layer "F.SilkS")
			(hide yes)
			(effects
				(font
					(size 1.27 1.27)
				)
			)
		)
		(property "Value" "0R2J-2-GP"
			(at 0.064008 -3.993896 270)
			(unlocked yes)
			(layer "F.Fab")
			(hide yes)
			(effects
				(font
					(size 1.016 1.016)
					(thickness 0.1524)
				)
			)
		)
		(property "Device Type" "R402H16"
			(at 0.064008 -5.517896 270)
			(unlocked yes)
			(layer "F.Fab")
			(hide yes)
			(effects
				(font
					(size 1.016 1.016)
					(thickness 0.1524)
				)
			)
		)
		(duplicate_pad_numbers_are_jumpers no)
		(fp_line
			(start -0.508 -0.9398)
			(end -0.508 0.9398)
			(stroke
				(width 0.1524)
				(type default)
			)
			(layer "F.SilkS")
		)
		(fp_line
			(start 0.508 -0.9398)
			(end -0.508 -0.9398)
			(stroke
				(width 0.1524)
				(type default)
			)
			(layer "F.SilkS")
		)
		(fp_rect
			(start -0.508 0.9398)
			(end 0.508 -0.9398)
			(stroke
				(width 0)
				(type default)
			)
			(fill no)
			(layer "F.CrtYd")
		)
		(fp_rect
			(start -0.508 0.9398)
			(end 0.508 -0.9398)
			(stroke
				(width 0)
				(type default)
			)
			(fill no)
			(layer "F.Fab")
		)
		(pad "1" smd custom
			(at 0 -0.4445 270)
			(size 0.1397 0.1397)
			(layers "F.Cu" "F.Mask" "F.Paste")
			(net "P5VB_ROVP")
			(options
				(clearance outline)
				(anchor circle)
			)
			(primitives
				(gr_poly
					(pts
						(arc
							(start -0.1778 -0.2794)
							(mid -0.249642 -0.249642)
							(end -0.2794 -0.1778)
						)
						(arc
							(start -0.2794 0.1778)
							(mid -0.249642 0.249642)
							(end -0.1778 0.2794)
						)
						(arc
							(start 0.1778 0.2794)
							(mid 0.249642 0.249642)
							(end 0.2794 0.1778)
						)
						(arc
							(start 0.2794 -0.1778)
							(mid 0.249642 -0.249642)
							(end 0.1778 -0.2794)
						)
					)
					(width 0)
					(fill yes)
				)
			)
		)
		(pad "2" smd custom
			(at 0 0.4445 270)
			(size 0.1397 0.1397)
			(layers "F.Cu" "F.Mask" "F.Paste")
			(net "P5VB_AGND")
			(options
				(clearance outline)
				(anchor circle)
			)
			(primitives
				(gr_poly
					(pts
						(arc
							(start -0.1778 -0.2794)
							(mid -0.249642 -0.249642)
							(end -0.2794 -0.1778)
						)
						(arc
							(start -0.2794 0.1778)
							(mid -0.249642 0.249642)
							(end -0.1778 0.2794)
						)
						(arc
							(start 0.1778 0.2794)
							(mid 0.249642 0.249642)
							(end 0.2794 0.1778)
						)
						(arc
							(start 0.2794 -0.1778)
							(mid 0.249642 -0.249642)
							(end 0.1778 -0.2794)
						)
					)
					(width 0)
					(fill yes)
				)
			)
		)
	)
	(footprint ""
		(layer "F.Cu")
		(at 33.02 -345.694 -90)
		(property "Reference" "R255"
			(at 0 0 270)
			(layer "F.SilkS")
			(hide yes)
			(effects
				(font
					(size 1.27 1.27)
				)
			)
		)
		(property "Value" "402R2F-GP"
			(at 0.064008 -3.993896 270)
			(unlocked yes)
			(layer "F.Fab")
			(hide yes)
			(effects
				(font
					(size 1.016 1.016)
					(thickness 0.1524)
				)
			)
		)
		(property "Device Type" "R402H16"
			(at 0.064008 -5.517896 270)
			(unlocked yes)
			(layer "F.Fab")
			(hide yes)
			(effects
				(font
					(size 1.016 1.016)
					(thickness 0.1524)
				)
			)
		)
		(duplicate_pad_numbers_are_jumpers no)
		(fp_line
			(start -0.508 -0.9398)
			(end -0.508 0.9398)
			(stroke
				(width 0.1524)
				(type default)
			)
			(layer "F.SilkS")
		)
		(fp_line
			(start 0.508 -0.9398)
			(end -0.508 -0.9398)
			(stroke
				(width 0.1524)
				(type default)
			)
			(layer "F.SilkS")
		)
		(fp_rect
			(start -0.508 0.9398)
			(end 0.508 -0.9398)
			(stroke
				(width 0)
				(type default)
			)
			(fill no)
			(layer "F.CrtYd")
		)
		(fp_rect
			(start -0.508 0.9398)
			(end 0.508 -0.9398)
			(stroke
				(width 0)
				(type default)
			)
			(fill no)
			(layer "F.Fab")
		)
		(pad "1" smd custom
			(at 0 -0.4445 270)
			(size 0.1397 0.1397)
			(layers "F.Cu" "F.Mask" "F.Paste")
			(net "P5VC_HDD11_LED")
			(options
				(clearance outline)
				(anchor circle)
			)
			(primitives
				(gr_poly
					(pts
						(arc
							(start -0.1778 -0.2794)
							(mid -0.249642 -0.249642)
							(end -0.2794 -0.1778)
						)
						(arc
							(start -0.2794 0.1778)
							(mid -0.249642 0.249642)
							(end -0.1778 0.2794)
						)
						(arc
							(start 0.1778 0.2794)
							(mid 0.249642 0.249642)
							(end 0.2794 0.1778)
						)
						(arc
							(start 0.2794 -0.1778)
							(mid 0.249642 -0.249642)
							(end 0.1778 -0.2794)
						)
					)
					(width 0)
					(fill yes)
				)
			)
		)
		(pad "2" smd custom
			(at 0 0.4445 270)
			(size 0.1397 0.1397)
			(layers "F.Cu" "F.Mask" "F.Paste")
			(net "DRV_ACT_11")
			(options
				(clearance outline)
				(anchor circle)
			)
			(primitives
				(gr_poly
					(pts
						(arc
							(start -0.1778 -0.2794)
							(mid -0.249642 -0.249642)
							(end -0.2794 -0.1778)
						)
						(arc
							(start -0.2794 0.1778)
							(mid -0.249642 0.249642)
							(end -0.1778 0.2794)
						)
						(arc
							(start 0.1778 0.2794)
							(mid 0.249642 0.249642)
							(end 0.2794 0.1778)
						)
						(arc
							(start 0.2794 -0.1778)
							(mid 0.249642 -0.249642)
							(end 0.1778 -0.2794)
						)
					)
					(width 0)
					(fill yes)
				)
			)
		)
	)
	(footprint ""
		(layer "F.Cu")
		(at 41.401746 -217.325702)
		(property "Reference" "C307"
			(at 0 0 0)
			(layer "F.SilkS")
			(hide yes)
			(effects
				(font
					(size 1.27 1.27)
				)
			)
		)
		(property "Value" "SC1U25V3KX-1-GP"
			(at 0 -2.8194 0)
			(unlocked yes)
			(layer "F.Fab")
			(hide yes)
			(effects
				(font
					(size 1.016 1.016)
					(thickness 0.1524)
				)
			)
		)
		(property "Device Type" "C603H36"
			(at 0 -4.3434 0)
			(unlocked yes)
			(layer "F.Fab")
			(hide yes)
			(effects
				(font
					(size 1.016 1.016)
					(thickness 0.1524)
				)
			)
		)
		(duplicate_pad_numbers_are_jumpers no)
		(fp_line
			(start 0.508 0)
			(end -0.508 0)
			(stroke
				(width 0.2032)
				(type default)
			)
			(layer "F.SilkS")
		)
		(fp_rect
			(start -0.5842 1.3335)
			(end 0.5842 -1.3335)
			(stroke
				(width 0)
				(type default)
			)
			(fill no)
			(layer "F.CrtYd")
		)
		(fp_rect
			(start -0.5842 1.3335)
			(end 0.5842 -1.3335)
			(stroke
				(width 0)
				(type default)
			)
			(fill no)
			(layer "F.Fab")
		)
		(pad "1" smd custom
			(at 0 -0.762)
			(size 0.2159 0.2159)
			(layers "F.Cu" "F.Mask" "F.Paste")
			(net "P12V_HDD12")
			(options
				(clearance outline)
				(anchor circle)
			)
			(primitives
				(gr_poly
					(pts
						(arc
							(start -0.3302 -0.4318)
							(mid -0.402042 -0.402042)
							(end -0.4318 -0.3302)
						)
						(arc
							(start -0.4318 0.3302)
							(mid -0.402042 0.402042)
							(end -0.3302 0.4318)
						)
						(arc
							(start 0.3302 0.4318)
							(mid 0.402042 0.402042)
							(end 0.4318 0.3302)
						)
						(arc
							(start 0.4318 -0.3302)
							(mid 0.402042 -0.402042)
							(end 0.3302 -0.4318)
						)
					)
					(width 0)
					(fill yes)
				)
			)
		)
		(pad "2" smd custom
			(at 0 0.762)
			(size 0.2159 0.2159)
			(layers "F.Cu" "F.Mask" "F.Paste")
			(net "GND")
			(options
				(clearance outline)
				(anchor circle)
			)
			(primitives
				(gr_poly
					(pts
						(arc
							(start -0.3302 -0.4318)
							(mid -0.402042 -0.402042)
							(end -0.4318 -0.3302)
						)
						(arc
							(start -0.4318 0.3302)
							(mid -0.402042 0.402042)
							(end -0.3302 0.4318)
						)
						(arc
							(start 0.3302 0.4318)
							(mid 0.402042 0.402042)
							(end 0.4318 0.3302)
						)
						(arc
							(start 0.4318 -0.3302)
							(mid 0.402042 -0.402042)
							(end 0.3302 -0.4318)
						)
					)
					(width 0)
					(fill yes)
				)
			)
		)
	)
	(footprint ""
		(layer "F.Cu")
		(at 194.31 -498.475 180)
		(property "Reference" "R563"
			(at 0 0 180)
			(layer "F.SilkS")
			(hide yes)
			(effects
				(font
					(size 1.27 1.27)
				)
			)
		)
		(property "Value" "300KR2F-GP"
			(at 0.064008 -3.993896 180)
			(unlocked yes)
			(layer "F.Fab")
			(hide yes)
			(effects
				(font
					(size 1.016 1.016)
					(thickness 0.1524)
				)
			)
		)
		(property "Device Type" "R402H16"
			(at 0.064008 -5.517896 180)
			(unlocked yes)
			(layer "F.Fab")
			(hide yes)
			(effects
				(font
					(size 1.016 1.016)
					(thickness 0.1524)
				)
			)
		)
		(duplicate_pad_numbers_are_jumpers no)
		(fp_line
			(start 0.508 -0.9398)
			(end -0.508 -0.9398)
			(stroke
				(width 0.1524)
				(type default)
			)
			(layer "F.SilkS")
		)
		(fp_line
			(start -0.508 -0.9398)
			(end -0.508 0.9398)
			(stroke
				(width 0.1524)
				(type default)
			)
			(layer "F.SilkS")
		)
		(fp_rect
			(start -0.508 0.9398)
			(end 0.508 -0.9398)
			(stroke
				(width 0)
				(type default)
			)
			(fill no)
			(layer "F.CrtYd")
		)
		(fp_rect
			(start -0.508 0.9398)
			(end 0.508 -0.9398)
			(stroke
				(width 0)
				(type default)
			)
			(fill no)
			(layer "F.Fab")
		)
		(pad "1" smd custom
			(at 0 -0.4445 180)
			(size 0.1397 0.1397)
			(layers "F.Cu" "F.Mask" "F.Paste")
			(net "SW_HDD0_N")
			(options
				(clearance outline)
				(anchor circle)
			)
			(primitives
				(gr_poly
					(pts
						(arc
							(start -0.1778 -0.2794)
							(mid -0.249642 -0.249642)
							(end -0.2794 -0.1778)
						)
						(arc
							(start -0.2794 0.1778)
							(mid -0.249642 0.249642)
							(end -0.1778 0.2794)
						)
						(arc
							(start 0.1778 0.2794)
							(mid 0.249642 0.249642)
							(end 0.2794 0.1778)
						)
						(arc
							(start 0.2794 -0.1778)
							(mid 0.249642 -0.249642)
							(end 0.1778 -0.2794)
						)
					)
					(width 0)
					(fill yes)
				)
			)
		)
		(pad "2" smd custom
			(at 0 0.4445 180)
			(size 0.1397 0.1397)
			(layers "F.Cu" "F.Mask" "F.Paste")
			(net "P12V")
			(options
				(clearance outline)
				(anchor circle)
			)
			(primitives
				(gr_poly
					(pts
						(arc
							(start -0.1778 -0.2794)
							(mid -0.249642 -0.249642)
							(end -0.2794 -0.1778)
						)
						(arc
							(start -0.2794 0.1778)
							(mid -0.249642 0.249642)
							(end -0.1778 0.2794)
						)
						(arc
							(start 0.1778 0.2794)
							(mid 0.249642 0.249642)
							(end 0.2794 0.1778)
						)
						(arc
							(start 0.2794 -0.1778)
							(mid 0.249642 -0.249642)
							(end 0.1778 -0.2794)
						)
					)
					(width 0)
					(fill yes)
				)
			)
		)
	)
	(footprint ""
		(layer "F.Cu")
		(at 46.2534 -236.6264 90)
		(property "Reference" "R401"
			(at 0 0 90)
			(layer "F.SilkS")
			(hide yes)
			(effects
				(font
					(size 1.27 1.27)
				)
			)
		)
		(property "Value" "10KR2F-2-GP"
			(at 0.064008 -3.993896 90)
			(unlocked yes)
			(layer "F.Fab")
			(hide yes)
			(effects
				(font
					(size 1.016 1.016)
					(thickness 0.1524)
				)
			)
		)
		(property "Device Type" "R402H16"
			(at 0.064008 -5.517896 90)
			(unlocked yes)
			(layer "F.Fab")
			(hide yes)
			(effects
				(font
					(size 1.016 1.016)
					(thickness 0.1524)
				)
			)
		)
		(duplicate_pad_numbers_are_jumpers no)
		(fp_line
			(start 0.508 -0.9398)
			(end -0.508 -0.9398)
			(stroke
				(width 0.1524)
				(type default)
			)
			(layer "F.SilkS")
		)
		(fp_line
			(start -0.508 -0.9398)
			(end -0.508 0.9398)
			(stroke
				(width 0.1524)
				(type default)
			)
			(layer "F.SilkS")
		)
		(fp_rect
			(start -0.508 0.9398)
			(end 0.508 -0.9398)
			(stroke
				(width 0)
				(type default)
			)
			(fill no)
			(layer "F.CrtYd")
		)
		(fp_rect
			(start -0.508 0.9398)
			(end 0.508 -0.9398)
			(stroke
				(width 0)
				(type default)
			)
			(fill no)
			(layer "F.Fab")
		)
		(pad "1" smd custom
			(at 0 -0.4445 90)
			(size 0.1397 0.1397)
			(layers "F.Cu" "F.Mask" "F.Paste")
			(net "P12V")
			(options
				(clearance outline)
				(anchor circle)
			)
			(primitives
				(gr_poly
					(pts
						(arc
							(start -0.1778 -0.2794)
							(mid -0.249642 -0.249642)
							(end -0.2794 -0.1778)
						)
						(arc
							(start -0.2794 0.1778)
							(mid -0.249642 0.249642)
							(end -0.1778 0.2794)
						)
						(arc
							(start 0.1778 0.2794)
							(mid 0.249642 0.249642)
							(end 0.2794 0.1778)
						)
						(arc
							(start 0.2794 -0.1778)
							(mid 0.249642 -0.249642)
							(end 0.1778 -0.2794)
						)
					)
					(width 0)
					(fill yes)
				)
			)
		)
		(pad "2" smd custom
			(at 0 0.4445 90)
			(size 0.1397 0.1397)
			(layers "F.Cu" "F.Mask" "F.Paste")
			(net "HDD12_LED_G")
			(options
				(clearance outline)
				(anchor circle)
			)
			(primitives
				(gr_poly
					(pts
						(arc
							(start -0.1778 -0.2794)
							(mid -0.249642 -0.249642)
							(end -0.2794 -0.1778)
						)
						(arc
							(start -0.2794 0.1778)
							(mid -0.249642 0.249642)
							(end -0.1778 0.2794)
						)
						(arc
							(start 0.1778 0.2794)
							(mid 0.249642 0.249642)
							(end 0.2794 0.1778)
						)
						(arc
							(start 0.2794 -0.1778)
							(mid 0.249642 -0.249642)
							(end 0.1778 -0.2794)
						)
					)
					(width 0)
					(fill yes)
				)
			)
		)
	)
	(footprint ""
		(layer "F.Cu")
		(at 8.381746 -156.4767 90)
		(property "Reference" "R359"
			(at 0 0 90)
			(layer "F.SilkS")
			(hide yes)
			(effects
				(font
					(size 1.27 1.27)
				)
			)
		)
		(property "Value" "10KR2F-2-GP"
			(at 0.064008 -3.993896 90)
			(unlocked yes)
			(layer "F.Fab")
			(hide yes)
			(effects
				(font
					(size 1.016 1.016)
					(thickness 0.1524)
				)
			)
		)
		(property "Device Type" "R402H16"
			(at 0.064008 -5.517896 90)
			(unlocked yes)
			(layer "F.Fab")
			(hide yes)
			(effects
				(font
					(size 1.016 1.016)
					(thickness 0.1524)
				)
			)
		)
		(duplicate_pad_numbers_are_jumpers no)
		(fp_line
			(start 0.508 -0.9398)
			(end -0.508 -0.9398)
			(stroke
				(width 0.1524)
				(type default)
			)
			(layer "F.SilkS")
		)
		(fp_line
			(start -0.508 -0.9398)
			(end -0.508 0.9398)
			(stroke
				(width 0.1524)
				(type default)
			)
			(layer "F.SilkS")
		)
		(fp_rect
			(start -0.508 0.9398)
			(end 0.508 -0.9398)
			(stroke
				(width 0)
				(type default)
			)
			(fill no)
			(layer "F.CrtYd")
		)
		(fp_rect
			(start -0.508 0.9398)
			(end 0.508 -0.9398)
			(stroke
				(width 0)
				(type default)
			)
			(fill no)
			(layer "F.Fab")
		)
		(pad "1" smd custom
			(at 0 -0.4445 90)
			(size 0.1397 0.1397)
			(layers "F.Cu" "F.Mask" "F.Paste")
			(net "TEMP_SENSOR_B_ADDR0&ID")
			(options
				(clearance outline)
				(anchor circle)
			)
			(primitives
				(gr_poly
					(pts
						(arc
							(start -0.1778 -0.2794)
							(mid -0.249642 -0.249642)
							(end -0.2794 -0.1778)
						)
						(arc
							(start -0.2794 0.1778)
							(mid -0.249642 0.249642)
							(end -0.1778 0.2794)
						)
						(arc
							(start 0.1778 0.2794)
							(mid 0.249642 0.249642)
							(end 0.2794 0.1778)
						)
						(arc
							(start 0.2794 -0.1778)
							(mid 0.249642 -0.249642)
							(end 0.1778 -0.2794)
						)
					)
					(width 0)
					(fill yes)
				)
			)
		)
		(pad "2" smd custom
			(at 0 0.4445 90)
			(size 0.1397 0.1397)
			(layers "F.Cu" "F.Mask" "F.Paste")
			(net "GND")
			(options
				(clearance outline)
				(anchor circle)
			)
			(primitives
				(gr_poly
					(pts
						(arc
							(start -0.1778 -0.2794)
							(mid -0.249642 -0.249642)
							(end -0.2794 -0.1778)
						)
						(arc
							(start -0.2794 0.1778)
							(mid -0.249642 0.249642)
							(end -0.1778 0.2794)
						)
						(arc
							(start 0.1778 0.2794)
							(mid 0.249642 0.249642)
							(end 0.2794 0.1778)
						)
						(arc
							(start 0.2794 -0.1778)
							(mid 0.249642 -0.249642)
							(end 0.1778 -0.2794)
						)
					)
					(width 0)
					(fill yes)
				)
			)
		)
	)
	(footprint ""
		(layer "F.Cu")
		(at 191.256412 -83.546696 -90)
		(property "Reference" "R169"
			(at 0 0 270)
			(layer "F.SilkS")
			(hide yes)
			(effects
				(font
					(size 1.27 1.27)
				)
			)
		)
		(property "Value" "0R2J-2-GP"
			(at 0.064008 -3.993896 270)
			(unlocked yes)
			(layer "F.Fab")
			(hide yes)
			(effects
				(font
					(size 1.016 1.016)
					(thickness 0.1524)
				)
			)
		)
		(property "Device Type" "R402H16"
			(at 0.064008 -5.517896 270)
			(unlocked yes)
			(layer "F.Fab")
			(hide yes)
			(effects
				(font
					(size 1.016 1.016)
					(thickness 0.1524)
				)
			)
		)
		(duplicate_pad_numbers_are_jumpers no)
		(fp_line
			(start -0.508 -0.9398)
			(end -0.508 0.9398)
			(stroke
				(width 0.1524)
				(type default)
			)
			(layer "F.SilkS")
		)
		(fp_line
			(start 0.508 -0.9398)
			(end -0.508 -0.9398)
			(stroke
				(width 0.1524)
				(type default)
			)
			(layer "F.SilkS")
		)
		(fp_rect
			(start -0.508 0.9398)
			(end 0.508 -0.9398)
			(stroke
				(width 0)
				(type default)
			)
			(fill no)
			(layer "F.CrtYd")
		)
		(fp_rect
			(start -0.508 0.9398)
			(end 0.508 -0.9398)
			(stroke
				(width 0)
				(type default)
			)
			(fill no)
			(layer "F.Fab")
		)
		(pad "1" smd custom
			(at 0 -0.4445 270)
			(size 0.1397 0.1397)
			(layers "F.Cu" "F.Mask" "F.Paste")
			(net "DRIVE_PWR4")
			(options
				(clearance outline)
				(anchor circle)
			)
			(primitives
				(gr_poly
					(pts
						(arc
							(start -0.1778 -0.2794)
							(mid -0.249642 -0.249642)
							(end -0.2794 -0.1778)
						)
						(arc
							(start -0.2794 0.1778)
							(mid -0.249642 0.249642)
							(end -0.1778 0.2794)
						)
						(arc
							(start 0.1778 0.2794)
							(mid 0.249642 0.249642)
							(end 0.2794 0.1778)
						)
						(arc
							(start 0.2794 -0.1778)
							(mid 0.249642 -0.249642)
							(end 0.1778 -0.2794)
						)
					)
					(width 0)
					(fill yes)
				)
			)
		)
		(pad "2" smd custom
			(at 0 0.4445 270)
			(size 0.1397 0.1397)
			(layers "F.Cu" "F.Mask" "F.Paste")
			(net "SW_PWR_HDD4")
			(options
				(clearance outline)
				(anchor circle)
			)
			(primitives
				(gr_poly
					(pts
						(arc
							(start -0.1778 -0.2794)
							(mid -0.249642 -0.249642)
							(end -0.2794 -0.1778)
						)
						(arc
							(start -0.2794 0.1778)
							(mid -0.249642 0.249642)
							(end -0.1778 0.2794)
						)
						(arc
							(start 0.1778 0.2794)
							(mid 0.249642 0.249642)
							(end 0.2794 0.1778)
						)
						(arc
							(start 0.2794 -0.1778)
							(mid 0.249642 -0.249642)
							(end 0.1778 -0.2794)
						)
					)
					(width 0)
					(fill yes)
				)
			)
		)
	)
	(footprint ""
		(layer "F.Cu")
		(at 209.422746 -452.6407 180)
		(property "Reference" "R329"
			(at 0 0 180)
			(layer "F.SilkS")
			(hide yes)
			(effects
				(font
					(size 1.27 1.27)
				)
			)
		)
		(property "Value" "4K7R2J-2-GP"
			(at 0.064008 -3.993896 180)
			(unlocked yes)
			(layer "F.Fab")
			(hide yes)
			(effects
				(font
					(size 1.016 1.016)
					(thickness 0.1524)
				)
			)
		)
		(property "Device Type" "R402H16"
			(at 0.064008 -5.517896 180)
			(unlocked yes)
			(layer "F.Fab")
			(hide yes)
			(effects
				(font
					(size 1.016 1.016)
					(thickness 0.1524)
				)
			)
		)
		(duplicate_pad_numbers_are_jumpers no)
		(fp_line
			(start 0.508 -0.9398)
			(end -0.508 -0.9398)
			(stroke
				(width 0.1524)
				(type default)
			)
			(layer "F.SilkS")
		)
		(fp_line
			(start -0.508 -0.9398)
			(end -0.508 0.9398)
			(stroke
				(width 0.1524)
				(type default)
			)
			(layer "F.SilkS")
		)
		(fp_rect
			(start -0.508 0.9398)
			(end 0.508 -0.9398)
			(stroke
				(width 0)
				(type default)
			)
			(fill no)
			(layer "F.CrtYd")
		)
		(fp_rect
			(start -0.508 0.9398)
			(end 0.508 -0.9398)
			(stroke
				(width 0)
				(type default)
			)
			(fill no)
			(layer "F.Fab")
		)
		(pad "1" smd custom
			(at 0 -0.4445 180)
			(size 0.1397 0.1397)
			(layers "F.Cu" "F.Mask" "F.Paste")
			(net "P3V3")
			(options
				(clearance outline)
				(anchor circle)
			)
			(primitives
				(gr_poly
					(pts
						(arc
							(start -0.1778 -0.2794)
							(mid -0.249642 -0.249642)
							(end -0.2794 -0.1778)
						)
						(arc
							(start -0.2794 0.1778)
							(mid -0.249642 0.249642)
							(end -0.1778 0.2794)
						)
						(arc
							(start 0.1778 0.2794)
							(mid 0.249642 0.249642)
							(end 0.2794 0.1778)
						)
						(arc
							(start 0.2794 -0.1778)
							(mid 0.249642 -0.249642)
							(end 0.1778 -0.2794)
						)
					)
					(width 0)
					(fill yes)
				)
			)
		)
		(pad "2" smd custom
			(at 0 0.4445 180)
			(size 0.1397 0.1397)
			(layers "F.Cu" "F.Mask" "F.Paste")
			(net "I2C_B_TMP3_A1")
			(options
				(clearance outline)
				(anchor circle)
			)
			(primitives
				(gr_poly
					(pts
						(arc
							(start -0.1778 -0.2794)
							(mid -0.249642 -0.249642)
							(end -0.2794 -0.1778)
						)
						(arc
							(start -0.2794 0.1778)
							(mid -0.249642 0.249642)
							(end -0.1778 0.2794)
						)
						(arc
							(start 0.1778 0.2794)
							(mid 0.249642 0.249642)
							(end 0.2794 0.1778)
						)
						(arc
							(start 0.2794 -0.1778)
							(mid 0.249642 -0.249642)
							(end 0.1778 -0.2794)
						)
					)
					(width 0)
					(fill yes)
				)
			)
		)
	)
	(footprint ""
		(layer "F.Cu")
		(at 218.142058 -366.851184 -90)
		(property "Reference" "C119"
			(at 0 0 270)
			(layer "F.SilkS")
			(hide yes)
			(effects
				(font
					(size 1.27 1.27)
				)
			)
		)
		(property "Value" "SCD01U50V2KX-1GP"
			(at 1.1811 -2.7051 270)
			(unlocked yes)
			(layer "F.Fab")
			(hide yes)
			(effects
				(font
					(size 1.016 1.016)
					(thickness 0.1524)
				)
			)
		)
		(property "Device Type" "C402H22"
			(at 1.1811 -4.2291 270)
			(unlocked yes)
			(layer "F.Fab")
			(hide yes)
			(effects
				(font
					(size 1.016 1.016)
					(thickness 0.1524)
				)
			)
		)
		(duplicate_pad_numbers_are_jumpers no)
		(fp_rect
			(start -0.4318 0.9525)
			(end 0.4318 -0.9525)
			(stroke
				(width 0)
				(type default)
			)
			(fill no)
			(layer "F.CrtYd")
		)
		(fp_rect
			(start -0.4318 0.9525)
			(end 0.4318 -0.9525)
			(stroke
				(width 0)
				(type default)
			)
			(fill no)
			(layer "F.Fab")
		)
		(pad "1" smd custom
			(at 0 -0.4445 270)
			(size 0.1524 0.1524)
			(layers "F.Cu" "F.Mask" "F.Paste")
			(net "SAS2X28_DRIVE_RX_P_A1")
			(options
				(clearance outline)
				(anchor circle)
			)
			(primitives
				(gr_poly
					(pts
						(arc
							(start 0.3048 -0.2032)
							(mid 0.275042 -0.275042)
							(end 0.2032 -0.3048)
						)
						(arc
							(start -0.2032 -0.3048)
							(mid -0.275042 -0.275042)
							(end -0.3048 -0.2032)
						)
						(arc
							(start -0.3048 0.2032)
							(mid -0.275042 0.275042)
							(end -0.2032 0.3048)
						)
						(arc
							(start 0.2032 0.3048)
							(mid 0.275042 0.275042)
							(end 0.3048 0.2032)
						)
					)
					(width 0)
					(fill yes)
				)
			)
		)
		(pad "2" smd custom
			(at 0 0.4445 270)
			(size 0.1524 0.1524)
			(layers "F.Cu" "F.Mask" "F.Paste")
			(net "SAS2X28_A_HDD1_RX_+")
			(options
				(clearance outline)
				(anchor circle)
			)
			(primitives
				(gr_poly
					(pts
						(arc
							(start 0.3048 -0.2032)
							(mid 0.275042 -0.275042)
							(end 0.2032 -0.3048)
						)
						(arc
							(start -0.2032 -0.3048)
							(mid -0.275042 -0.275042)
							(end -0.3048 -0.2032)
						)
						(arc
							(start -0.3048 0.2032)
							(mid -0.275042 0.275042)
							(end -0.2032 0.3048)
						)
						(arc
							(start 0.2032 0.3048)
							(mid 0.275042 0.275042)
							(end 0.3048 0.2032)
						)
					)
					(width 0)
					(fill yes)
				)
			)
		)
	)
	(footprint ""
		(layer "F.Cu")
		(at 73.242932 -496.145312)
		(property "Reference" "R443"
			(at 0 0 0)
			(layer "F.SilkS")
			(hide yes)
			(effects
				(font
					(size 1.27 1.27)
				)
			)
		)
		(property "Value" "4K7R2J-2-GP"
			(at 0.064008 -3.993896 0)
			(unlocked yes)
			(layer "F.Fab")
			(hide yes)
			(effects
				(font
					(size 1.016 1.016)
					(thickness 0.1524)
				)
			)
		)
		(property "Device Type" "R402H16"
			(at 0.064008 -5.517896 0)
			(unlocked yes)
			(layer "F.Fab")
			(hide yes)
			(effects
				(font
					(size 1.016 1.016)
					(thickness 0.1524)
				)
			)
		)
		(duplicate_pad_numbers_are_jumpers no)
		(fp_line
			(start -0.508 -0.9398)
			(end -0.508 0.9398)
			(stroke
				(width 0.1524)
				(type default)
			)
			(layer "F.SilkS")
		)
		(fp_line
			(start 0.508 -0.9398)
			(end -0.508 -0.9398)
			(stroke
				(width 0.1524)
				(type default)
			)
			(layer "F.SilkS")
		)
		(fp_rect
			(start -0.508 0.9398)
			(end 0.508 -0.9398)
			(stroke
				(width 0)
				(type default)
			)
			(fill no)
			(layer "F.CrtYd")
		)
		(fp_rect
			(start -0.508 0.9398)
			(end 0.508 -0.9398)
			(stroke
				(width 0)
				(type default)
			)
			(fill no)
			(layer "F.Fab")
		)
		(pad "1" smd custom
			(at 0 -0.4445)
			(size 0.1397 0.1397)
			(layers "F.Cu" "F.Mask" "F.Paste")
			(net "P3V3")
			(options
				(clearance outline)
				(anchor circle)
			)
			(primitives
				(gr_poly
					(pts
						(arc
							(start -0.1778 -0.2794)
							(mid -0.249642 -0.249642)
							(end -0.2794 -0.1778)
						)
						(arc
							(start -0.2794 0.1778)
							(mid -0.249642 0.249642)
							(end -0.1778 0.2794)
						)
						(arc
							(start 0.1778 0.2794)
							(mid 0.249642 0.249642)
							(end 0.2794 0.1778)
						)
						(arc
							(start 0.2794 -0.1778)
							(mid 0.249642 -0.249642)
							(end 0.1778 -0.2794)
						)
					)
					(width 0)
					(fill yes)
				)
			)
		)
		(pad "2" smd custom
			(at 0 0.4445)
			(size 0.1397 0.1397)
			(layers "F.Cu" "F.Mask" "F.Paste")
			(net "SAS2X28_B_HDD5_FLT")
			(options
				(clearance outline)
				(anchor circle)
			)
			(primitives
				(gr_poly
					(pts
						(arc
							(start -0.1778 -0.2794)
							(mid -0.249642 -0.249642)
							(end -0.2794 -0.1778)
						)
						(arc
							(start -0.2794 0.1778)
							(mid -0.249642 0.249642)
							(end -0.1778 0.2794)
						)
						(arc
							(start 0.1778 0.2794)
							(mid 0.249642 0.249642)
							(end 0.2794 0.1778)
						)
						(arc
							(start 0.2794 -0.1778)
							(mid 0.249642 -0.249642)
							(end 0.1778 -0.2794)
						)
					)
					(width 0)
					(fill yes)
				)
			)
		)
	)
	(footprint ""
		(layer "F.Cu")
		(at 21.226272 -500.446548 180)
		(property "Reference" "PC35"
			(at 0 0 180)
			(layer "F.SilkS")
			(hide yes)
			(effects
				(font
					(size 1.27 1.27)
				)
			)
		)
		(property "Value" "SC22U25V5MX-GP"
			(at -0.0762 -6.1214 180)
			(unlocked yes)
			(layer "F.Fab")
			(hide yes)
			(effects
				(font
					(size 1.016 1.016)
					(thickness 0.1524)
				)
			)
		)
		(property "Device Type" "C805H58"
			(at -0.0762 -8.1534 180)
			(unlocked yes)
			(layer "F.Fab")
			(hide yes)
			(effects
				(font
					(size 1.016 1.016)
					(thickness 0.1524)
				)
			)
		)
		(duplicate_pad_numbers_are_jumpers no)
		(fp_line
			(start 0.635 0)
			(end -0.635 0)
			(stroke
				(width 0.508)
				(type default)
			)
			(layer "F.SilkS")
		)
		(fp_rect
			(start -0.9652 1.778)
			(end 0.9652 -1.778)
			(stroke
				(width 0)
				(type default)
			)
			(fill no)
			(layer "F.CrtYd")
		)
		(fp_poly
			(pts
				(xy -0.9652 -1.778) (xy 0.9652 -1.778) (xy 0.9652 1.778) (xy -0.9652 1.778)
			)
			(stroke
				(width 0)
				(type default)
			)
			(fill no)
			(layer "F.Fab")
		)
		(pad "1" smd rect
			(at 0 -0.9652 180)
			(size 1.397 1.143)
			(layers "F.Cu" "F.Mask" "F.Paste")
			(net "P5VC_12VIN")
		)
		(pad "2" smd rect
			(at 0 0.9652 180)
			(size 1.397 1.143)
			(layers "F.Cu" "F.Mask" "F.Paste")
			(net "GND")
		)
	)
	(footprint ""
		(layer "F.Cu")
		(at 71.754746 -187.2107)
		(property "Reference" "U25"
			(at 0 0 0)
			(layer "F.SilkS")
			(hide yes)
			(effects
				(font
					(size 1.27 1.27)
				)
			)
		)
		(property "Value" "74LVC1G08GW-1-GP"
			(at -2.3368 -8.6868 0)
			(unlocked yes)
			(layer "F.Fab")
			(hide yes)
			(effects
				(font
					(size 1.016 1.016)
					(thickness 0.1524)
				)
			)
		)
		(property "Device Type" "SC70-5H44"
			(at -2.3114 -10.414 0)
			(unlocked yes)
			(layer "F.Fab")
			(hide yes)
			(effects
				(font
					(size 1.016 1.016)
					(thickness 0.1524)
				)
			)
		)
		(duplicate_pad_numbers_are_jumpers no)
		(fp_line
			(start -1.27 -1.7018)
			(end 1.27 -1.7018)
			(stroke
				(width 0.1524)
				(type default)
			)
			(layer "F.SilkS")
		)
		(fp_line
			(start -1.27 1.7018)
			(end -1.27 -1.7018)
			(stroke
				(width 0.1524)
				(type default)
			)
			(layer "F.SilkS")
		)
		(fp_line
			(start 0.6604 -1.8034)
			(end 1.3843 -1.8034)
			(stroke
				(width 0.3302)
				(type default)
			)
			(layer "F.SilkS")
		)
		(fp_line
			(start 1.27 -1.7018)
			(end 1.27 1.7018)
			(stroke
				(width 0.1524)
				(type default)
			)
			(layer "F.SilkS")
		)
		(fp_line
			(start 1.27 1.7018)
			(end -1.27 1.7018)
			(stroke
				(width 0.1524)
				(type default)
			)
			(layer "F.SilkS")
		)
		(fp_line
			(start 1.3843 -1.8034)
			(end 1.3843 -1.1176)
			(stroke
				(width 0.3302)
				(type default)
			)
			(layer "F.SilkS")
		)
		(fp_rect
			(start -1.524 1.9558)
			(end 1.524 -1.9558)
			(stroke
				(width 0)
				(type default)
			)
			(fill no)
			(layer "F.CrtYd")
		)
		(fp_poly
			(pts
				(xy -1.524 -1.9558) (xy 1.524 -1.9558) (xy 1.524 1.9558) (xy -1.524 1.9558)
			)
			(stroke
				(width 0)
				(type default)
			)
			(fill no)
			(layer "F.Fab")
		)
		(pad "1" smd rect
			(at 0.65024 -0.8255)
			(size 0.4064 1.2192)
			(layers "F.Cu" "F.Mask" "F.Paste")
			(net "SAS2X28_B_HDD8_FLT")
		)
		(pad "2" smd rect
			(at 0 -0.8255)
			(size 0.4064 1.2192)
			(layers "F.Cu" "F.Mask" "F.Paste")
			(net "SAS2X28_A_HDD8_FLT")
		)
		(pad "3" smd rect
			(at -0.65024 -0.8255)
			(size 0.4064 1.2192)
			(layers "F.Cu" "F.Mask" "F.Paste")
			(net "GND")
		)
		(pad "4" smd rect
			(at -0.65024 0.8255)
			(size 0.4064 1.2192)
			(layers "F.Cu" "F.Mask" "F.Paste")
			(net "FLT_HDD8_DRIVE")
		)
		(pad "5" smd rect
			(at 0.65024 0.8255)
			(size 0.4064 1.2192)
			(layers "F.Cu" "F.Mask" "F.Paste")
			(net "P3V3")
		)
	)
	(footprint ""
		(layer "F.Cu")
		(at 58.166 -396.9004 180)
		(property "Reference" "C209"
			(at 0 0 180)
			(layer "F.SilkS")
			(hide yes)
			(effects
				(font
					(size 1.27 1.27)
				)
			)
		)
		(property "Value" "SC10U25V6KX-1GP"
			(at -0.0762 -5.1308 180)
			(unlocked yes)
			(layer "F.Fab")
			(hide yes)
			(effects
				(font
					(size 1.016 1.016)
					(thickness 0.1524)
				)
			)
		)
		(property "Device Type" "C1206H71"
			(at -0.127 -6.6548 180)
			(unlocked yes)
			(layer "F.Fab")
			(hide yes)
			(effects
				(font
					(size 1.016 1.016)
					(thickness 0.1524)
				)
			)
		)
		(duplicate_pad_numbers_are_jumpers no)
		(fp_line
			(start 1.016 2.2352)
			(end -1.016 2.2352)
			(stroke
				(width 0.1524)
				(type default)
			)
			(layer "F.SilkS")
		)
		(fp_line
			(start 1.016 0.8382)
			(end 1.016 2.2352)
			(stroke
				(width 0.1524)
				(type default)
			)
			(layer "F.SilkS")
		)
		(fp_line
			(start 1.016 -2.2352)
			(end 1.016 -0.8382)
			(stroke
				(width 0.1524)
				(type default)
			)
			(layer "F.SilkS")
		)
		(fp_line
			(start -1.016 2.2352)
			(end -1.016 0.8382)
			(stroke
				(width 0.1524)
				(type default)
			)
			(layer "F.SilkS")
		)
		(fp_line
			(start -1.016 -0.8382)
			(end -1.016 -2.2352)
			(stroke
				(width 0.1524)
				(type default)
			)
			(layer "F.SilkS")
		)
		(fp_line
			(start -1.016 -2.2352)
			(end 1.016 -2.2352)
			(stroke
				(width 0.1524)
				(type default)
			)
			(layer "F.SilkS")
		)
		(fp_rect
			(start -1.0922 2.3114)
			(end 1.0922 -2.3114)
			(stroke
				(width 0)
				(type default)
			)
			(fill no)
			(layer "F.CrtYd")
		)
		(fp_poly
			(pts
				(xy 1.0922 -2.3114) (xy 1.0922 2.3114) (xy -1.0922 2.3114) (xy -1.0922 -2.3114)
			)
			(stroke
				(width 0)
				(type default)
			)
			(fill no)
			(layer "F.Fab")
		)
		(pad "1" smd rect
			(at 0 -1.397 180)
			(size 1.651 1.27)
			(layers "F.Cu" "F.Mask" "F.Paste")
			(net "P12V_HDD6")
		)
		(pad "2" smd rect
			(at 0 1.397 180)
			(size 1.651 1.27)
			(layers "F.Cu" "F.Mask" "F.Paste")
			(net "GND")
		)
	)
	(footprint ""
		(layer "F.Cu")
		(at 43.815 -429.5648 -90)
		(property "Reference" "R397"
			(at 0 0 270)
			(layer "F.SilkS")
			(hide yes)
			(effects
				(font
					(size 1.27 1.27)
				)
			)
		)
		(property "Value" "10KR2F-2-GP"
			(at 0.064008 -3.993896 270)
			(unlocked yes)
			(layer "F.Fab")
			(hide yes)
			(effects
				(font
					(size 1.016 1.016)
					(thickness 0.1524)
				)
			)
		)
		(property "Device Type" "R402H16"
			(at 0.064008 -5.517896 270)
			(unlocked yes)
			(layer "F.Fab")
			(hide yes)
			(effects
				(font
					(size 1.016 1.016)
					(thickness 0.1524)
				)
			)
		)
		(duplicate_pad_numbers_are_jumpers no)
		(fp_line
			(start -0.508 -0.9398)
			(end -0.508 0.9398)
			(stroke
				(width 0.1524)
				(type default)
			)
			(layer "F.SilkS")
		)
		(fp_line
			(start 0.508 -0.9398)
			(end -0.508 -0.9398)
			(stroke
				(width 0.1524)
				(type default)
			)
			(layer "F.SilkS")
		)
		(fp_rect
			(start -0.508 0.9398)
			(end 0.508 -0.9398)
			(stroke
				(width 0)
				(type default)
			)
			(fill no)
			(layer "F.CrtYd")
		)
		(fp_rect
			(start -0.508 0.9398)
			(end 0.508 -0.9398)
			(stroke
				(width 0)
				(type default)
			)
			(fill no)
			(layer "F.Fab")
		)
		(pad "1" smd custom
			(at 0 -0.4445 270)
			(size 0.1397 0.1397)
			(layers "F.Cu" "F.Mask" "F.Paste")
			(net "P12V")
			(options
				(clearance outline)
				(anchor circle)
			)
			(primitives
				(gr_poly
					(pts
						(arc
							(start -0.1778 -0.2794)
							(mid -0.249642 -0.249642)
							(end -0.2794 -0.1778)
						)
						(arc
							(start -0.2794 0.1778)
							(mid -0.249642 0.249642)
							(end -0.1778 0.2794)
						)
						(arc
							(start 0.1778 0.2794)
							(mid 0.249642 0.249642)
							(end 0.2794 0.1778)
						)
						(arc
							(start 0.2794 -0.1778)
							(mid 0.249642 -0.249642)
							(end 0.1778 -0.2794)
						)
					)
					(width 0)
					(fill yes)
				)
			)
		)
		(pad "2" smd custom
			(at 0 0.4445 270)
			(size 0.1397 0.1397)
			(layers "F.Cu" "F.Mask" "F.Paste")
			(net "HDD10_LED_G")
			(options
				(clearance outline)
				(anchor circle)
			)
			(primitives
				(gr_poly
					(pts
						(arc
							(start -0.1778 -0.2794)
							(mid -0.249642 -0.249642)
							(end -0.2794 -0.1778)
						)
						(arc
							(start -0.2794 0.1778)
							(mid -0.249642 0.249642)
							(end -0.1778 0.2794)
						)
						(arc
							(start 0.1778 0.2794)
							(mid 0.249642 0.249642)
							(end 0.2794 0.1778)
						)
						(arc
							(start 0.2794 -0.1778)
							(mid 0.249642 -0.249642)
							(end 0.1778 -0.2794)
						)
					)
					(width 0)
					(fill yes)
				)
			)
		)
	)
	(footprint ""
		(layer "F.Cu")
		(at 50.0634 -209.042 90)
		(property "Reference" "R420"
			(at 0 0 90)
			(layer "F.SilkS")
			(hide yes)
			(effects
				(font
					(size 1.27 1.27)
				)
			)
		)
		(property "Value" "0R2J-2-GP"
			(at 0.064008 -3.993896 90)
			(unlocked yes)
			(layer "F.Fab")
			(hide yes)
			(effects
				(font
					(size 1.016 1.016)
					(thickness 0.1524)
				)
			)
		)
		(property "Device Type" "R402H16"
			(at 0.064008 -5.517896 90)
			(unlocked yes)
			(layer "F.Fab")
			(hide yes)
			(effects
				(font
					(size 1.016 1.016)
					(thickness 0.1524)
				)
			)
		)
		(duplicate_pad_numbers_are_jumpers no)
		(fp_line
			(start 0.508 -0.9398)
			(end -0.508 -0.9398)
			(stroke
				(width 0.1524)
				(type default)
			)
			(layer "F.SilkS")
		)
		(fp_line
			(start -0.508 -0.9398)
			(end -0.508 0.9398)
			(stroke
				(width 0.1524)
				(type default)
			)
			(layer "F.SilkS")
		)
		(fp_rect
			(start -0.508 0.9398)
			(end 0.508 -0.9398)
			(stroke
				(width 0)
				(type default)
			)
			(fill no)
			(layer "F.CrtYd")
		)
		(fp_rect
			(start -0.508 0.9398)
			(end 0.508 -0.9398)
			(stroke
				(width 0)
				(type default)
			)
			(fill no)
			(layer "F.Fab")
		)
		(pad "1" smd custom
			(at 0 -0.4445 90)
			(size 0.1397 0.1397)
			(layers "F.Cu" "F.Mask" "F.Paste")
			(net "SW_HDD12_G")
			(options
				(clearance outline)
				(anchor circle)
			)
			(primitives
				(gr_poly
					(pts
						(arc
							(start -0.1778 -0.2794)
							(mid -0.249642 -0.249642)
							(end -0.2794 -0.1778)
						)
						(arc
							(start -0.2794 0.1778)
							(mid -0.249642 0.249642)
							(end -0.1778 0.2794)
						)
						(arc
							(start 0.1778 0.2794)
							(mid 0.249642 0.249642)
							(end 0.2794 0.1778)
						)
						(arc
							(start 0.2794 -0.1778)
							(mid 0.249642 -0.249642)
							(end 0.1778 -0.2794)
						)
					)
					(width 0)
					(fill yes)
				)
			)
		)
		(pad "2" smd custom
			(at 0 0.4445 90)
			(size 0.1397 0.1397)
			(layers "F.Cu" "F.Mask" "F.Paste")
			(net "SW_HDD12_R")
			(options
				(clearance outline)
				(anchor circle)
			)
			(primitives
				(gr_poly
					(pts
						(arc
							(start -0.1778 -0.2794)
							(mid -0.249642 -0.249642)
							(end -0.2794 -0.1778)
						)
						(arc
							(start -0.2794 0.1778)
							(mid -0.249642 0.249642)
							(end -0.1778 0.2794)
						)
						(arc
							(start 0.1778 0.2794)
							(mid 0.249642 0.249642)
							(end 0.2794 0.1778)
						)
						(arc
							(start 0.2794 -0.1778)
							(mid 0.249642 -0.249642)
							(end 0.1778 -0.2794)
						)
					)
					(width 0)
					(fill yes)
				)
			)
		)
	)
	(footprint ""
		(layer "F.Cu")
		(at 215.195912 -73.691496 -90)
		(property "Reference" "R161"
			(at 0 0 270)
			(layer "F.SilkS")
			(hide yes)
			(effects
				(font
					(size 1.27 1.27)
				)
			)
		)
		(property "Value" "2R2010J-1-GP"
			(at 0.254 -8.0772 270)
			(unlocked yes)
			(layer "F.Fab")
			(hide yes)
			(effects
				(font
					(size 1.016 1.016)
					(thickness 0.1524)
				)
			)
		)
		(property "Device Type" "R2010H28"
			(at 0.254 -9.6774 270)
			(unlocked yes)
			(layer "F.Fab")
			(hide yes)
			(effects
				(font
					(size 1.016 1.016)
					(thickness 0.1524)
				)
			)
		)
		(duplicate_pad_numbers_are_jumpers no)
		(fp_line
			(start -1.651 3.302)
			(end 1.651 3.302)
			(stroke
				(width 0.1524)
				(type default)
			)
			(layer "F.SilkS")
		)
		(fp_line
			(start 1.651 3.302)
			(end 1.651 -3.302)
			(stroke
				(width 0.1524)
				(type default)
			)
			(layer "F.SilkS")
		)
		(fp_line
			(start -1.651 -3.302)
			(end -1.651 3.302)
			(stroke
				(width 0.1524)
				(type default)
			)
			(layer "F.SilkS")
		)
		(fp_line
			(start 1.651 -3.302)
			(end -1.651 -3.302)
			(stroke
				(width 0.1524)
				(type default)
			)
			(layer "F.SilkS")
		)
		(fp_rect
			(start -1.7272 -3.3782)
			(end 1.7272 3.3782)
			(stroke
				(width 0)
				(type default)
			)
			(fill no)
			(layer "F.CrtYd")
		)
		(fp_poly
			(pts
				(xy 1.7272 3.3782) (xy 1.7272 -3.3782) (xy -1.7272 -3.3782) (xy -1.7272 3.3782)
			)
			(stroke
				(width 0)
				(type default)
			)
			(fill no)
			(layer "F.Fab")
		)
		(pad "1" smd rect
			(at 0 -2.3495 270)
			(size 2.794 1.143)
			(layers "F.Cu" "F.Mask" "F.Paste")
			(net "5V_PRE_4")
		)
		(pad "2" smd rect
			(at 0 2.3495 270)
			(size 2.794 1.143)
			(layers "F.Cu" "F.Mask" "F.Paste")
			(net "P5V_HDD4")
		)
	)
	(footprint ""
		(layer "F.Cu")
		(at 27.812746 -304.828702 180)
		(property "Reference" "R466"
			(at 0 0 180)
			(layer "F.SilkS")
			(hide yes)
			(effects
				(font
					(size 1.27 1.27)
				)
			)
		)
		(property "Value" "4K7R2J-2-GP"
			(at 0.064008 -3.993896 180)
			(unlocked yes)
			(layer "F.Fab")
			(hide yes)
			(effects
				(font
					(size 1.016 1.016)
					(thickness 0.1524)
				)
			)
		)
		(property "Device Type" "R402H16"
			(at 0.064008 -5.517896 180)
			(unlocked yes)
			(layer "F.Fab")
			(hide yes)
			(effects
				(font
					(size 1.016 1.016)
					(thickness 0.1524)
				)
			)
		)
		(duplicate_pad_numbers_are_jumpers no)
		(fp_line
			(start 0.508 -0.9398)
			(end -0.508 -0.9398)
			(stroke
				(width 0.1524)
				(type default)
			)
			(layer "F.SilkS")
		)
		(fp_line
			(start -0.508 -0.9398)
			(end -0.508 0.9398)
			(stroke
				(width 0.1524)
				(type default)
			)
			(layer "F.SilkS")
		)
		(fp_rect
			(start -0.508 0.9398)
			(end 0.508 -0.9398)
			(stroke
				(width 0)
				(type default)
			)
			(fill no)
			(layer "F.CrtYd")
		)
		(fp_rect
			(start -0.508 0.9398)
			(end 0.508 -0.9398)
			(stroke
				(width 0)
				(type default)
			)
			(fill no)
			(layer "F.Fab")
		)
		(pad "1" smd custom
			(at 0 -0.4445 180)
			(size 0.1397 0.1397)
			(layers "F.Cu" "F.Mask" "F.Paste")
			(net "P3V3")
			(options
				(clearance outline)
				(anchor circle)
			)
			(primitives
				(gr_poly
					(pts
						(arc
							(start -0.1778 -0.2794)
							(mid -0.249642 -0.249642)
							(end -0.2794 -0.1778)
						)
						(arc
							(start -0.2794 0.1778)
							(mid -0.249642 0.249642)
							(end -0.1778 0.2794)
						)
						(arc
							(start 0.1778 0.2794)
							(mid 0.249642 0.249642)
							(end 0.2794 0.1778)
						)
						(arc
							(start 0.2794 -0.1778)
							(mid 0.249642 -0.249642)
							(end 0.1778 -0.2794)
						)
					)
					(width 0)
					(fill yes)
				)
			)
		)
		(pad "2" smd custom
			(at 0 0.4445 180)
			(size 0.1397 0.1397)
			(layers "F.Cu" "F.Mask" "F.Paste")
			(net "SAS_EXP_A_PWR11")
			(options
				(clearance outline)
				(anchor circle)
			)
			(primitives
				(gr_poly
					(pts
						(arc
							(start -0.1778 -0.2794)
							(mid -0.249642 -0.249642)
							(end -0.2794 -0.1778)
						)
						(arc
							(start -0.2794 0.1778)
							(mid -0.249642 0.249642)
							(end -0.1778 0.2794)
						)
						(arc
							(start 0.1778 0.2794)
							(mid 0.249642 0.249642)
							(end 0.2794 0.1778)
						)
						(arc
							(start 0.2794 -0.1778)
							(mid 0.249642 -0.249642)
							(end 0.1778 -0.2794)
						)
					)
					(width 0)
					(fill yes)
				)
			)
		)
	)
	(footprint ""
		(layer "F.Cu")
		(at 194.564 -191.262 180)
		(property "Reference" "R566"
			(at 0 0 180)
			(layer "F.SilkS")
			(hide yes)
			(effects
				(font
					(size 1.27 1.27)
				)
			)
		)
		(property "Value" "300KR2F-GP"
			(at 0.064008 -3.993896 180)
			(unlocked yes)
			(layer "F.Fab")
			(hide yes)
			(effects
				(font
					(size 1.016 1.016)
					(thickness 0.1524)
				)
			)
		)
		(property "Device Type" "R402H16"
			(at 0.064008 -5.517896 180)
			(unlocked yes)
			(layer "F.Fab")
			(hide yes)
			(effects
				(font
					(size 1.016 1.016)
					(thickness 0.1524)
				)
			)
		)
		(duplicate_pad_numbers_are_jumpers no)
		(fp_line
			(start 0.508 -0.9398)
			(end -0.508 -0.9398)
			(stroke
				(width 0.1524)
				(type default)
			)
			(layer "F.SilkS")
		)
		(fp_line
			(start -0.508 -0.9398)
			(end -0.508 0.9398)
			(stroke
				(width 0.1524)
				(type default)
			)
			(layer "F.SilkS")
		)
		(fp_rect
			(start -0.508 0.9398)
			(end 0.508 -0.9398)
			(stroke
				(width 0)
				(type default)
			)
			(fill no)
			(layer "F.CrtYd")
		)
		(fp_rect
			(start -0.508 0.9398)
			(end 0.508 -0.9398)
			(stroke
				(width 0)
				(type default)
			)
			(fill no)
			(layer "F.Fab")
		)
		(pad "1" smd custom
			(at 0 -0.4445 180)
			(size 0.1397 0.1397)
			(layers "F.Cu" "F.Mask" "F.Paste")
			(net "SW_HDD3_N")
			(options
				(clearance outline)
				(anchor circle)
			)
			(primitives
				(gr_poly
					(pts
						(arc
							(start -0.1778 -0.2794)
							(mid -0.249642 -0.249642)
							(end -0.2794 -0.1778)
						)
						(arc
							(start -0.2794 0.1778)
							(mid -0.249642 0.249642)
							(end -0.1778 0.2794)
						)
						(arc
							(start 0.1778 0.2794)
							(mid 0.249642 0.249642)
							(end 0.2794 0.1778)
						)
						(arc
							(start 0.2794 -0.1778)
							(mid 0.249642 -0.249642)
							(end 0.1778 -0.2794)
						)
					)
					(width 0)
					(fill yes)
				)
			)
		)
		(pad "2" smd custom
			(at 0 0.4445 180)
			(size 0.1397 0.1397)
			(layers "F.Cu" "F.Mask" "F.Paste")
			(net "P12V")
			(options
				(clearance outline)
				(anchor circle)
			)
			(primitives
				(gr_poly
					(pts
						(arc
							(start -0.1778 -0.2794)
							(mid -0.249642 -0.249642)
							(end -0.2794 -0.1778)
						)
						(arc
							(start -0.2794 0.1778)
							(mid -0.249642 0.249642)
							(end -0.1778 0.2794)
						)
						(arc
							(start 0.1778 0.2794)
							(mid 0.249642 0.249642)
							(end 0.2794 0.1778)
						)
						(arc
							(start 0.2794 -0.1778)
							(mid 0.249642 -0.249642)
							(end 0.1778 -0.2794)
						)
					)
					(width 0)
					(fill yes)
				)
			)
		)
	)
	(footprint ""
		(layer "F.Cu")
		(at 207.136746 -462.6737 90)
		(property "Reference" "R334"
			(at 0 0 90)
			(layer "F.SilkS")
			(hide yes)
			(effects
				(font
					(size 1.27 1.27)
				)
			)
		)
		(property "Value" "0R2J-2-GP"
			(at 0.064008 -3.993896 90)
			(unlocked yes)
			(layer "F.Fab")
			(hide yes)
			(effects
				(font
					(size 1.016 1.016)
					(thickness 0.1524)
				)
			)
		)
		(property "Device Type" "R402H16"
			(at 0.064008 -5.517896 90)
			(unlocked yes)
			(layer "F.Fab")
			(hide yes)
			(effects
				(font
					(size 1.016 1.016)
					(thickness 0.1524)
				)
			)
		)
		(duplicate_pad_numbers_are_jumpers no)
		(fp_line
			(start 0.508 -0.9398)
			(end -0.508 -0.9398)
			(stroke
				(width 0.1524)
				(type default)
			)
			(layer "F.SilkS")
		)
		(fp_line
			(start -0.508 -0.9398)
			(end -0.508 0.9398)
			(stroke
				(width 0.1524)
				(type default)
			)
			(layer "F.SilkS")
		)
		(fp_rect
			(start -0.508 0.9398)
			(end 0.508 -0.9398)
			(stroke
				(width 0)
				(type default)
			)
			(fill no)
			(layer "F.CrtYd")
		)
		(fp_rect
			(start -0.508 0.9398)
			(end 0.508 -0.9398)
			(stroke
				(width 0)
				(type default)
			)
			(fill no)
			(layer "F.Fab")
		)
		(pad "1" smd custom
			(at 0 -0.4445 90)
			(size 0.1397 0.1397)
			(layers "F.Cu" "F.Mask" "F.Paste")
			(net "I2C_B_SCL")
			(options
				(clearance outline)
				(anchor circle)
			)
			(primitives
				(gr_poly
					(pts
						(arc
							(start -0.1778 -0.2794)
							(mid -0.249642 -0.249642)
							(end -0.2794 -0.1778)
						)
						(arc
							(start -0.2794 0.1778)
							(mid -0.249642 0.249642)
							(end -0.1778 0.2794)
						)
						(arc
							(start 0.1778 0.2794)
							(mid 0.249642 0.249642)
							(end 0.2794 0.1778)
						)
						(arc
							(start 0.2794 -0.1778)
							(mid 0.249642 -0.249642)
							(end 0.1778 -0.2794)
						)
					)
					(width 0)
					(fill yes)
				)
			)
		)
		(pad "2" smd custom
			(at 0 0.4445 90)
			(size 0.1397 0.1397)
			(layers "F.Cu" "F.Mask" "F.Paste")
			(net "TMP3_SCL")
			(options
				(clearance outline)
				(anchor circle)
			)
			(primitives
				(gr_poly
					(pts
						(arc
							(start -0.1778 -0.2794)
							(mid -0.249642 -0.249642)
							(end -0.2794 -0.1778)
						)
						(arc
							(start -0.2794 0.1778)
							(mid -0.249642 0.249642)
							(end -0.1778 0.2794)
						)
						(arc
							(start 0.1778 0.2794)
							(mid 0.249642 0.249642)
							(end 0.2794 0.1778)
						)
						(arc
							(start 0.2794 -0.1778)
							(mid 0.249642 -0.249642)
							(end 0.1778 -0.2794)
						)
					)
					(width 0)
					(fill yes)
				)
			)
		)
	)
	(footprint ""
		(layer "F.Cu")
		(at 224.154746 -32.2707 180)
		(property "Reference" "PTC1"
			(at 0 0 180)
			(layer "F.SilkS")
			(hide yes)
			(effects
				(font
					(size 1.27 1.27)
				)
			)
		)
		(property "Value" "ST330U10VDM-2GP"
			(at 0 -9.6012 180)
			(unlocked yes)
			(layer "F.Fab")
			(hide yes)
			(effects
				(font
					(size 1.016 1.016)
					(thickness 0.1524)
				)
			)
		)
		(property "Device Type" "CT7343H150"
			(at 0 -11.1252 180)
			(unlocked yes)
			(layer "F.Fab")
			(hide yes)
			(effects
				(font
					(size 1.016 1.016)
					(thickness 0.1524)
				)
			)
		)
		(duplicate_pad_numbers_are_jumpers no)
		(fp_line
			(start 2.286 4.8768)
			(end -2.286 4.8768)
			(stroke
				(width 0.1524)
				(type default)
			)
			(layer "F.SilkS")
		)
		(fp_line
			(start 2.286 2.032)
			(end 2.286 4.8768)
			(stroke
				(width 0.1524)
				(type default)
			)
			(layer "F.SilkS")
		)
		(fp_line
			(start 2.286 -2.032)
			(end 2.286 -4.8768)
			(stroke
				(width 0.1524)
				(type default)
			)
			(layer "F.SilkS")
		)
		(fp_line
			(start 2.286 -4.8768)
			(end -2.286 -4.8768)
			(stroke
				(width 0.1524)
				(type default)
			)
			(layer "F.SilkS")
		)
		(fp_line
			(start 2.1082 -4.699)
			(end -2.1082 -4.699)
			(stroke
				(width 0.508)
				(type default)
			)
			(layer "F.SilkS")
		)
		(fp_line
			(start -2.286 4.8768)
			(end -2.286 2.032)
			(stroke
				(width 0.1524)
				(type default)
			)
			(layer "F.SilkS")
		)
		(fp_line
			(start -2.286 -4.8768)
			(end -2.286 -2.032)
			(stroke
				(width 0.1524)
				(type default)
			)
			(layer "F.SilkS")
		)
		(fp_rect
			(start -2.1463 3.6449)
			(end 2.1463 -3.6449)
			(stroke
				(width 0)
				(type default)
			)
			(fill no)
			(layer "F.CrtYd")
		)
		(fp_poly
			(pts
				(xy -2.54 4.953) (xy -2.54 4.2926) (xy -3.81 4.2926) (xy -3.81 -4.2926) (xy -2.54 -4.2926) (xy -2.54 -4.953)
				(xy 2.54 -4.953) (xy 2.54 -4.2926) (xy 3.81 -4.2926) (xy 3.81 -1.6256) (xy 2.1463 -1.6256) (xy 2.1463 -3.6449)
				(xy -2.1463 -3.6449) (xy -2.1463 3.6449) (xy 2.1463 3.6449) (xy 2.1463 -1.6129) (xy 3.81 -1.6129)
				(xy 3.81 4.2926) (xy 2.54 4.2926) (xy 2.54 4.953)
			)
			(stroke
				(width 0)
				(type default)
			)
			(fill no)
			(layer "F.CrtYd")
		)
		(fp_rect
			(start 2.54 4.2926)
			(end 3.81 -4.2926)
			(stroke
				(width 0)
				(type default)
			)
			(fill no)
			(layer "F.Fab")
		)
		(fp_rect
			(start -2.54 4.953)
			(end 2.54 -4.953)
			(stroke
				(width 0)
				(type default)
			)
			(fill no)
			(layer "F.Fab")
		)
		(fp_rect
			(start -3.81 4.2926)
			(end -2.54 -4.2926)
			(stroke
				(width 0)
				(type default)
			)
			(fill no)
			(layer "F.Fab")
		)
		(pad "1" smd rect
			(at 0 -3.1496 180)
			(size 2.413 2.286)
			(layers "F.Cu" "F.Mask" "F.Paste")
			(net "P5VA")
		)
		(pad "2" smd rect
			(at 0 3.1496 180)
			(size 2.413 2.286)
			(layers "F.Cu" "F.Mask" "F.Paste")
			(net "GND")
		)
		(zone
			(layer "F.Cu")
			(hatch none 0.5)
			(connect_pads
				(clearance 0)
			)
			(min_thickness 0.25)
			(keepout
				(tracks allowed)
				(vias not_allowed)
				(pads allowed)
				(copperpour not_allowed)
				(footprints allowed)
			)
			(placement
				(enabled no)
				(sheetname "")
			)
			(fill
				(thermal_gap 0.5)
				(thermal_bridge_width 0.5)
				(island_removal_mode 0)
			)
			(polygon
				(pts
					(xy 222.643446 -30.5816) (xy 222.643446 -27.6733) (xy 225.666046 -27.6733) (xy 225.666046 -30.5689)
					(xy 225.666046 -30.8991) (xy 222.643446 -30.8991)
				)
			)
		)
		(zone
			(layer "F.Cu")
			(hatch none 0.5)
			(connect_pads
				(clearance 0)
			)
			(min_thickness 0.25)
			(keepout
				(tracks allowed)
				(vias not_allowed)
				(pads allowed)
				(copperpour not_allowed)
				(footprints allowed)
			)
			(placement
				(enabled no)
				(sheetname "")
			)
			(fill
				(thermal_gap 0.5)
				(thermal_bridge_width 0.5)
				(island_removal_mode 0)
			)
			(polygon
				(pts
					(xy 225.666046 -36.8681) (xy 222.643446 -36.8681) (xy 222.643446 -33.9725) (xy 222.643446 -33.6423)
					(xy 225.666046 -33.6423) (xy 225.666046 -33.9725)
				)
			)
		)
	)
	(footprint ""
		(layer "F.Cu")
		(at 38.353746 -112.296702)
		(property "Reference" "R294"
			(at 0 0 0)
			(layer "F.SilkS")
			(hide yes)
			(effects
				(font
					(size 1.27 1.27)
				)
			)
		)
		(property "Value" "0R2J-2-GP"
			(at 0.064008 -3.993896 0)
			(unlocked yes)
			(layer "F.Fab")
			(hide yes)
			(effects
				(font
					(size 1.016 1.016)
					(thickness 0.1524)
				)
			)
		)
		(property "Device Type" "R402H16"
			(at 0.064008 -5.517896 0)
			(unlocked yes)
			(layer "F.Fab")
			(hide yes)
			(effects
				(font
					(size 1.016 1.016)
					(thickness 0.1524)
				)
			)
		)
		(duplicate_pad_numbers_are_jumpers no)
		(fp_line
			(start -0.508 -0.9398)
			(end -0.508 0.9398)
			(stroke
				(width 0.1524)
				(type default)
			)
			(layer "F.SilkS")
		)
		(fp_line
			(start 0.508 -0.9398)
			(end -0.508 -0.9398)
			(stroke
				(width 0.1524)
				(type default)
			)
			(layer "F.SilkS")
		)
		(fp_rect
			(start -0.508 0.9398)
			(end 0.508 -0.9398)
			(stroke
				(width 0)
				(type default)
			)
			(fill no)
			(layer "F.CrtYd")
		)
		(fp_rect
			(start -0.508 0.9398)
			(end 0.508 -0.9398)
			(stroke
				(width 0)
				(type default)
			)
			(fill no)
			(layer "F.Fab")
		)
		(pad "1" smd custom
			(at 0 -0.4445)
			(size 0.1397 0.1397)
			(layers "F.Cu" "F.Mask" "F.Paste")
			(net "SW_PWR_HDD13")
			(options
				(clearance outline)
				(anchor circle)
			)
			(primitives
				(gr_poly
					(pts
						(arc
							(start -0.1778 -0.2794)
							(mid -0.249642 -0.249642)
							(end -0.2794 -0.1778)
						)
						(arc
							(start -0.2794 0.1778)
							(mid -0.249642 0.249642)
							(end -0.1778 0.2794)
						)
						(arc
							(start 0.1778 0.2794)
							(mid 0.249642 0.249642)
							(end 0.2794 0.1778)
						)
						(arc
							(start 0.2794 -0.1778)
							(mid 0.249642 -0.249642)
							(end 0.1778 -0.2794)
						)
					)
					(width 0)
					(fill yes)
				)
			)
		)
		(pad "2" smd custom
			(at 0 0.4445)
			(size 0.1397 0.1397)
			(layers "F.Cu" "F.Mask" "F.Paste")
			(net "SW_PWR_R_HDD13")
			(options
				(clearance outline)
				(anchor circle)
			)
			(primitives
				(gr_poly
					(pts
						(arc
							(start -0.1778 -0.2794)
							(mid -0.249642 -0.249642)
							(end -0.2794 -0.1778)
						)
						(arc
							(start -0.2794 0.1778)
							(mid -0.249642 0.249642)
							(end -0.1778 0.2794)
						)
						(arc
							(start 0.1778 0.2794)
							(mid 0.249642 0.249642)
							(end 0.2794 0.1778)
						)
						(arc
							(start 0.2794 -0.1778)
							(mid 0.249642 -0.249642)
							(end 0.1778 -0.2794)
						)
					)
					(width 0)
					(fill yes)
				)
			)
		)
	)
	(footprint ""
		(layer "F.Cu")
		(at 180.479446 -457.107036 180)
		(property "Reference" "R485"
			(at 0 0 180)
			(layer "F.SilkS")
			(hide yes)
			(effects
				(font
					(size 1.27 1.27)
				)
			)
		)
		(property "Value" "10KR2F-2-GP"
			(at 0.064008 -3.993896 180)
			(unlocked yes)
			(layer "F.Fab")
			(hide yes)
			(effects
				(font
					(size 1.016 1.016)
					(thickness 0.1524)
				)
			)
		)
		(property "Device Type" "R402H16"
			(at 0.064008 -5.517896 180)
			(unlocked yes)
			(layer "F.Fab")
			(hide yes)
			(effects
				(font
					(size 1.016 1.016)
					(thickness 0.1524)
				)
			)
		)
		(duplicate_pad_numbers_are_jumpers no)
		(fp_line
			(start 0.508 -0.9398)
			(end -0.508 -0.9398)
			(stroke
				(width 0.1524)
				(type default)
			)
			(layer "F.SilkS")
		)
		(fp_line
			(start -0.508 -0.9398)
			(end -0.508 0.9398)
			(stroke
				(width 0.1524)
				(type default)
			)
			(layer "F.SilkS")
		)
		(fp_rect
			(start -0.508 0.9398)
			(end 0.508 -0.9398)
			(stroke
				(width 0)
				(type default)
			)
			(fill no)
			(layer "F.CrtYd")
		)
		(fp_rect
			(start -0.508 0.9398)
			(end 0.508 -0.9398)
			(stroke
				(width 0)
				(type default)
			)
			(fill no)
			(layer "F.Fab")
		)
		(pad "1" smd custom
			(at 0 -0.4445 180)
			(size 0.1397 0.1397)
			(layers "F.Cu" "F.Mask" "F.Paste")
			(net "P5VC")
			(options
				(clearance outline)
				(anchor circle)
			)
			(primitives
				(gr_poly
					(pts
						(arc
							(start -0.1778 -0.2794)
							(mid -0.249642 -0.249642)
							(end -0.2794 -0.1778)
						)
						(arc
							(start -0.2794 0.1778)
							(mid -0.249642 0.249642)
							(end -0.1778 0.2794)
						)
						(arc
							(start 0.1778 0.2794)
							(mid 0.249642 0.249642)
							(end 0.2794 0.1778)
						)
						(arc
							(start 0.2794 -0.1778)
							(mid 0.249642 -0.249642)
							(end 0.1778 -0.2794)
						)
					)
					(width 0)
					(fill yes)
				)
			)
		)
		(pad "2" smd custom
			(at 0 0.4445 180)
			(size 0.1397 0.1397)
			(layers "F.Cu" "F.Mask" "F.Paste")
			(net "P5VC_DIV")
			(options
				(clearance outline)
				(anchor circle)
			)
			(primitives
				(gr_poly
					(pts
						(arc
							(start -0.1778 -0.2794)
							(mid -0.249642 -0.249642)
							(end -0.2794 -0.1778)
						)
						(arc
							(start -0.2794 0.1778)
							(mid -0.249642 0.249642)
							(end -0.1778 0.2794)
						)
						(arc
							(start 0.1778 0.2794)
							(mid 0.249642 0.249642)
							(end 0.2794 0.1778)
						)
						(arc
							(start 0.2794 -0.1778)
							(mid 0.249642 -0.249642)
							(end 0.1778 -0.2794)
						)
					)
					(width 0)
					(fill yes)
				)
			)
		)
	)
	(footprint ""
		(layer "F.Cu")
		(at 81.2546 -500.8626 -90)
		(property "Reference" "R413"
			(at 0 0 270)
			(layer "F.SilkS")
			(hide yes)
			(effects
				(font
					(size 1.27 1.27)
				)
			)
		)
		(property "Value" "0R2J-2-GP"
			(at 0.064008 -3.993896 270)
			(unlocked yes)
			(layer "F.Fab")
			(hide yes)
			(effects
				(font
					(size 1.016 1.016)
					(thickness 0.1524)
				)
			)
		)
		(property "Device Type" "R402H16"
			(at 0.064008 -5.517896 270)
			(unlocked yes)
			(layer "F.Fab")
			(hide yes)
			(effects
				(font
					(size 1.016 1.016)
					(thickness 0.1524)
				)
			)
		)
		(duplicate_pad_numbers_are_jumpers no)
		(fp_line
			(start -0.508 -0.9398)
			(end -0.508 0.9398)
			(stroke
				(width 0.1524)
				(type default)
			)
			(layer "F.SilkS")
		)
		(fp_line
			(start 0.508 -0.9398)
			(end -0.508 -0.9398)
			(stroke
				(width 0.1524)
				(type default)
			)
			(layer "F.SilkS")
		)
		(fp_rect
			(start -0.508 0.9398)
			(end 0.508 -0.9398)
			(stroke
				(width 0)
				(type default)
			)
			(fill no)
			(layer "F.CrtYd")
		)
		(fp_rect
			(start -0.508 0.9398)
			(end 0.508 -0.9398)
			(stroke
				(width 0)
				(type default)
			)
			(fill no)
			(layer "F.Fab")
		)
		(pad "1" smd custom
			(at 0 -0.4445 270)
			(size 0.1397 0.1397)
			(layers "F.Cu" "F.Mask" "F.Paste")
			(net "SW_HDD5_G")
			(options
				(clearance outline)
				(anchor circle)
			)
			(primitives
				(gr_poly
					(pts
						(arc
							(start -0.1778 -0.2794)
							(mid -0.249642 -0.249642)
							(end -0.2794 -0.1778)
						)
						(arc
							(start -0.2794 0.1778)
							(mid -0.249642 0.249642)
							(end -0.1778 0.2794)
						)
						(arc
							(start 0.1778 0.2794)
							(mid 0.249642 0.249642)
							(end 0.2794 0.1778)
						)
						(arc
							(start 0.2794 -0.1778)
							(mid 0.249642 -0.249642)
							(end 0.1778 -0.2794)
						)
					)
					(width 0)
					(fill yes)
				)
			)
		)
		(pad "2" smd custom
			(at 0 0.4445 270)
			(size 0.1397 0.1397)
			(layers "F.Cu" "F.Mask" "F.Paste")
			(net "SW_HDD5_R")
			(options
				(clearance outline)
				(anchor circle)
			)
			(primitives
				(gr_poly
					(pts
						(arc
							(start -0.1778 -0.2794)
							(mid -0.249642 -0.249642)
							(end -0.2794 -0.1778)
						)
						(arc
							(start -0.2794 0.1778)
							(mid -0.249642 0.249642)
							(end -0.1778 0.2794)
						)
						(arc
							(start 0.1778 0.2794)
							(mid 0.249642 0.249642)
							(end 0.2794 0.1778)
						)
						(arc
							(start 0.2794 -0.1778)
							(mid 0.249642 -0.249642)
							(end 0.1778 -0.2794)
						)
					)
					(width 0)
					(fill yes)
				)
			)
		)
	)
	(footprint ""
		(layer "F.Cu")
		(at 165.112446 -456.218036 90)
		(property "Reference" "R380"
			(at 0 0 90)
			(layer "F.SilkS")
			(hide yes)
			(effects
				(font
					(size 1.27 1.27)
				)
			)
		)
		(property "Value" "0R2J-2-GP"
			(at 0.064008 -3.993896 90)
			(unlocked yes)
			(layer "F.Fab")
			(hide yes)
			(effects
				(font
					(size 1.016 1.016)
					(thickness 0.1524)
				)
			)
		)
		(property "Device Type" "R402H16"
			(at 0.064008 -5.517896 90)
			(unlocked yes)
			(layer "F.Fab")
			(hide yes)
			(effects
				(font
					(size 1.016 1.016)
					(thickness 0.1524)
				)
			)
		)
		(duplicate_pad_numbers_are_jumpers no)
		(fp_line
			(start 0.508 -0.9398)
			(end -0.508 -0.9398)
			(stroke
				(width 0.1524)
				(type default)
			)
			(layer "F.SilkS")
		)
		(fp_line
			(start -0.508 -0.9398)
			(end -0.508 0.9398)
			(stroke
				(width 0.1524)
				(type default)
			)
			(layer "F.SilkS")
		)
		(fp_rect
			(start -0.508 0.9398)
			(end 0.508 -0.9398)
			(stroke
				(width 0)
				(type default)
			)
			(fill no)
			(layer "F.CrtYd")
		)
		(fp_rect
			(start -0.508 0.9398)
			(end 0.508 -0.9398)
			(stroke
				(width 0)
				(type default)
			)
			(fill no)
			(layer "F.Fab")
		)
		(pad "1" smd custom
			(at 0 -0.4445 90)
			(size 0.1397 0.1397)
			(layers "F.Cu" "F.Mask" "F.Paste")
			(net "P5VB_DIV")
			(options
				(clearance outline)
				(anchor circle)
			)
			(primitives
				(gr_poly
					(pts
						(arc
							(start -0.1778 -0.2794)
							(mid -0.249642 -0.249642)
							(end -0.2794 -0.1778)
						)
						(arc
							(start -0.2794 0.1778)
							(mid -0.249642 0.249642)
							(end -0.1778 0.2794)
						)
						(arc
							(start 0.1778 0.2794)
							(mid 0.249642 0.249642)
							(end 0.2794 0.1778)
						)
						(arc
							(start 0.2794 -0.1778)
							(mid 0.249642 -0.249642)
							(end 0.1778 -0.2794)
						)
					)
					(width 0)
					(fill yes)
				)
			)
		)
		(pad "2" smd custom
			(at 0 0.4445 90)
			(size 0.1397 0.1397)
			(layers "F.Cu" "F.Mask" "F.Paste")
			(net "P5VB_SENSE")
			(options
				(clearance outline)
				(anchor circle)
			)
			(primitives
				(gr_poly
					(pts
						(arc
							(start -0.1778 -0.2794)
							(mid -0.249642 -0.249642)
							(end -0.2794 -0.1778)
						)
						(arc
							(start -0.2794 0.1778)
							(mid -0.249642 0.249642)
							(end -0.1778 0.2794)
						)
						(arc
							(start 0.1778 0.2794)
							(mid 0.249642 0.249642)
							(end 0.2794 0.1778)
						)
						(arc
							(start 0.2794 -0.1778)
							(mid 0.249642 -0.249642)
							(end 0.1778 -0.2794)
						)
					)
					(width 0)
					(fill yes)
				)
			)
		)
	)
	(footprint ""
		(layer "F.Cu")
		(at 58.927746 -24.6507 90)
		(property "Reference" "PR30"
			(at 0 0 90)
			(layer "F.SilkS")
			(hide yes)
			(effects
				(font
					(size 1.27 1.27)
				)
			)
		)
		(property "Value" "115KR2F-GP"
			(at 0.064008 -3.993896 90)
			(unlocked yes)
			(layer "F.Fab")
			(hide yes)
			(effects
				(font
					(size 1.016 1.016)
					(thickness 0.1524)
				)
			)
		)
		(property "Device Type" "R402H16"
			(at 0.064008 -5.517896 90)
			(unlocked yes)
			(layer "F.Fab")
			(hide yes)
			(effects
				(font
					(size 1.016 1.016)
					(thickness 0.1524)
				)
			)
		)
		(duplicate_pad_numbers_are_jumpers no)
		(fp_line
			(start 0.508 -0.9398)
			(end -0.508 -0.9398)
			(stroke
				(width 0.1524)
				(type default)
			)
			(layer "F.SilkS")
		)
		(fp_line
			(start -0.508 -0.9398)
			(end -0.508 0.9398)
			(stroke
				(width 0.1524)
				(type default)
			)
			(layer "F.SilkS")
		)
		(fp_rect
			(start -0.508 0.9398)
			(end 0.508 -0.9398)
			(stroke
				(width 0)
				(type default)
			)
			(fill no)
			(layer "F.CrtYd")
		)
		(fp_rect
			(start -0.508 0.9398)
			(end 0.508 -0.9398)
			(stroke
				(width 0)
				(type default)
			)
			(fill no)
			(layer "F.Fab")
		)
		(pad "1" smd custom
			(at 0 -0.4445 90)
			(size 0.1397 0.1397)
			(layers "F.Cu" "F.Mask" "F.Paste")
			(net "P5VB_TRIP")
			(options
				(clearance outline)
				(anchor circle)
			)
			(primitives
				(gr_poly
					(pts
						(arc
							(start -0.1778 -0.2794)
							(mid -0.249642 -0.249642)
							(end -0.2794 -0.1778)
						)
						(arc
							(start -0.2794 0.1778)
							(mid -0.249642 0.249642)
							(end -0.1778 0.2794)
						)
						(arc
							(start 0.1778 0.2794)
							(mid 0.249642 0.249642)
							(end 0.2794 0.1778)
						)
						(arc
							(start 0.2794 -0.1778)
							(mid 0.249642 -0.249642)
							(end 0.1778 -0.2794)
						)
					)
					(width 0)
					(fill yes)
				)
			)
		)
		(pad "2" smd custom
			(at 0 0.4445 90)
			(size 0.1397 0.1397)
			(layers "F.Cu" "F.Mask" "F.Paste")
			(net "P5VB_AGND")
			(options
				(clearance outline)
				(anchor circle)
			)
			(primitives
				(gr_poly
					(pts
						(arc
							(start -0.1778 -0.2794)
							(mid -0.249642 -0.249642)
							(end -0.2794 -0.1778)
						)
						(arc
							(start -0.2794 0.1778)
							(mid -0.249642 0.249642)
							(end -0.1778 0.2794)
						)
						(arc
							(start 0.1778 0.2794)
							(mid 0.249642 0.249642)
							(end 0.2794 0.1778)
						)
						(arc
							(start 0.2794 -0.1778)
							(mid 0.249642 -0.249642)
							(end 0.1778 -0.2794)
						)
					)
					(width 0)
					(fill yes)
				)
			)
		)
	)
	(footprint ""
		(layer "F.Cu")
		(at 2.500122 -55.204614 -90)
		(property "Reference" "CN9"
			(at 0 0 270)
			(layer "F.SilkS")
			(hide yes)
			(effects
				(font
					(size 1.27 1.27)
				)
			)
		)
		(property "Value" "PCISLT36-27-GP"
			(at 5.281422 -7.491476 270)
			(unlocked yes)
			(layer "F.Fab")
			(hide yes)
			(effects
				(font
					(size 1.016 1.016)
					(thickness 0.1524)
				)
			)
		)
		(property "Device Type" "G630H3612248EU"
			(at 5.281422 -9.015476 270)
			(unlocked yes)
			(layer "F.Fab")
			(hide yes)
			(effects
				(font
					(size 1.016 1.016)
					(thickness 0.1524)
				)
			)
		)
		(duplicate_pad_numbers_are_jumpers no)
		(fp_line
			(start -14.899894 2.499868)
			(end -1.450086 2.499868)
			(stroke
				(width 0.1524)
				(type default)
			)
			(layer "F.SilkS")
		)
		(fp_line
			(start -1.450086 2.499868)
			(end -0.94996 1.999742)
			(stroke
				(width 0.1524)
				(type default)
			)
			(layer "F.SilkS")
		)
		(fp_line
			(start 1.450086 2.499868)
			(end 18.899886 2.499868)
			(stroke
				(width 0.1524)
				(type default)
			)
			(layer "F.SilkS")
		)
		(fp_line
			(start 18.899886 2.499868)
			(end 19.400012 1.999742)
			(stroke
				(width 0.1524)
				(type default)
			)
			(layer "F.SilkS")
		)
		(fp_line
			(start -15.40002 1.999742)
			(end -14.899894 2.499868)
			(stroke
				(width 0.1524)
				(type default)
			)
			(layer "F.SilkS")
		)
		(fp_line
			(start -0.94996 1.999742)
			(end -0.94996 -2.55016)
			(stroke
				(width 0.1524)
				(type default)
			)
			(layer "F.SilkS")
		)
		(fp_line
			(start 0.94996 1.999742)
			(end 1.450086 2.499868)
			(stroke
				(width 0.1524)
				(type default)
			)
			(layer "F.SilkS")
		)
		(fp_line
			(start 19.400012 1.999742)
			(end 19.400012 -4.064)
			(stroke
				(width 0.1524)
				(type default)
			)
			(layer "F.SilkS")
		)
		(fp_line
			(start 0.94996 -2.539746)
			(end 0.94996 1.999742)
			(stroke
				(width 0.1524)
				(type default)
			)
			(layer "F.SilkS")
		)
		(fp_line
			(start 0.94996 -2.55016)
			(end 0.94996 -2.539746)
			(stroke
				(width 0.1524)
				(type default)
			)
			(layer "F.SilkS")
		)
		(fp_line
			(start -15.40002 -4.064)
			(end -15.40002 1.999742)
			(stroke
				(width 0.1524)
				(type default)
			)
			(layer "F.SilkS")
		)
		(fp_line
			(start 19.400012 -4.064)
			(end -15.40002 -4.064)
			(stroke
				(width 0.1524)
				(type default)
			)
			(layer "F.SilkS")
		)
		(fp_line
			(start 11.6713 -4.1529)
			(end 11.2903 -4.1529)
			(stroke
				(width 0.3302)
				(type default)
			)
			(layer "F.SilkS")
		)
		(fp_arc
			(start -0.94996 -2.55016)
			(mid 0 -3.50012)
			(end 0.94996 -2.55016)
			(stroke
				(width 0.1524)
				(type default)
			)
			(layer "F.SilkS")
		)
		(fp_poly
			(pts
				(xy 11.474704 -4.1402) (xy 10.966704 -4.6482) (xy 11.982704 -4.6482)
			)
			(stroke
				(width 0)
				(type default)
			)
			(fill yes)
			(layer "F.SilkS")
		)
		(fp_poly
			(pts
				(xy -10.4902 14.986) (xy -10.4902 4.8006) (xy -15.3924 4.8006) (xy -15.3924 -3.81) (xy 19.4056 -3.81)
				(xy 19.4056 4.8006) (xy 14.5034 4.8006) (xy 14.5034 14.986)
			)
			(stroke
				(width 0)
				(type default)
			)
			(fill no)
			(layer "B.CrtYd")
		)
		(fp_poly
			(pts
				(xy -10.9982 15.494) (xy -10.9982 5.3086) (xy -15.9004 5.3086) (xy -15.9004 -4.318) (xy 19.9136 -4.318)
				(xy 19.9136 5.3086) (xy 15.0114 5.3086) (xy 15.0114 15.494) (xy 0.00254 15.494) (xy 0.00254 14.986)
				(xy 14.5034 14.986) (xy 14.5034 4.8006) (xy 19.4056 4.8006) (xy 19.4056 -3.81) (xy -15.3924 -3.81)
				(xy -15.3924 4.8006) (xy -10.4902 4.8006) (xy -10.4902 14.986) (xy -0.00254 14.986) (xy -0.00254 15.494)
			)
			(stroke
				(width 0)
				(type default)
			)
			(fill no)
			(layer "B.CrtYd")
		)
		(fp_poly
			(pts
				(xy -10.4902 14.986) (xy -10.4902 4.8006) (xy -15.3924 4.8006) (xy -15.3924 -3.81) (xy 19.4056 -3.81)
				(xy 19.4056 4.8006) (xy 14.5034 4.8006) (xy 14.5034 14.986)
			)
			(stroke
				(width 0)
				(type default)
			)
			(fill no)
			(layer "F.CrtYd")
		)
		(fp_poly
			(pts
				(xy -10.9982 15.494) (xy -10.9982 5.3086) (xy -15.9004 5.3086) (xy -15.9004 -4.318) (xy 19.9136 -4.318)
				(xy 19.9136 5.3086) (xy 15.0114 5.3086) (xy 15.0114 15.494) (xy 0.00254 15.494) (xy 0.00254 14.986)
				(xy 14.5034 14.986) (xy 14.5034 4.8006) (xy 19.4056 4.8006) (xy 19.4056 -3.81) (xy -15.3924 -3.81)
				(xy -15.3924 4.8006) (xy -10.4902 4.8006) (xy -10.4902 14.986) (xy -0.00254 14.986) (xy -0.00254 15.494)
			)
			(stroke
				(width 0)
				(type default)
			)
			(fill no)
			(layer "F.CrtYd")
		)
		(fp_poly
			(pts
				(xy -10.9982 15.494) (xy -10.9982 5.3086) (xy -15.9004 5.3086) (xy -15.9004 -4.318) (xy 19.9136 -4.318)
				(xy 19.9136 5.3086) (xy 15.0114 5.3086) (xy 15.0114 15.494)
			)
			(stroke
				(width 0)
				(type default)
			)
			(fill no)
			(layer "B.Fab")
		)
		(fp_poly
			(pts
				(xy -10.9982 15.494) (xy -10.9982 5.3086) (xy -15.9004 5.3086) (xy -15.9004 -4.318) (xy 19.9136 -4.318)
				(xy 19.9136 5.3086) (xy 15.0114 5.3086) (xy 15.0114 15.494)
			)
			(stroke
				(width 0)
				(type default)
			)
			(fill no)
			(layer "F.Fab")
		)
		(fp_text user "Slit"
			(at 1.9304 5.088636 270)
			(unlocked yes)
			(layer "F.SilkS")
			(effects
				(font
					(size 1.016 1.016)
					(thickness 0.1524)
				)
				(justify left)
			)
		)
		(pad "" np_thru_hole circle
			(at -12.300204 0 270)
			(size 0.254 0.254)
			(drill 2.3114)
			(layers "*.Cu" "*.Mask")
			(clearance 1.3843)
			(thermal_gap 1.3843)
		)
		(pad "" np_thru_hole circle
			(at 16.299942 0 270)
			(size 0.254 0.254)
			(drill 2.3114)
			(layers "*.Cu" "*.Mask")
			(clearance 1.3843)
			(thermal_gap 1.3843)
		)
		(pad "A1" smd rect
			(at 11.500104 -0.309118 270)
			(size 0.7112 3.6068)
			(drill
				(offset 0 -0.381)
			)
			(layers "F.Cu" "F.Mask" "F.Paste")
			(net "PRSNT_B")
		)
		(pad "A2" smd rect
			(at 10.500106 -0.309118 270)
			(size 0.7112 3.6068)
			(drill
				(offset 0 -0.381)
			)
			(layers "F.Cu" "F.Mask" "F.Paste")
			(net "P12V")
		)
		(pad "A3" smd rect
			(at 9.500108 -0.309118 270)
			(size 0.7112 3.6068)
			(drill
				(offset 0 -0.381)
			)
			(layers "F.Cu" "F.Mask" "F.Paste")
			(net "P12V")
		)
		(pad "A4" smd rect
			(at 8.50011 -0.309118 270)
			(size 0.7112 3.6068)
			(drill
				(offset 0 -0.381)
			)
			(layers "F.Cu" "F.Mask" "F.Paste")
			(net "P12V")
		)
		(pad "A5" smd rect
			(at 7.500112 -0.309118 270)
			(size 0.7112 3.6068)
			(drill
				(offset 0 -0.381)
			)
			(layers "F.Cu" "F.Mask" "F.Paste")
			(net "P12V")
		)
		(pad "A6" smd rect
			(at 6.500114 -0.309118 270)
			(size 0.7112 3.6068)
			(drill
				(offset 0 -0.381)
			)
			(layers "F.Cu" "F.Mask" "F.Paste")
			(net "P12V")
		)
		(pad "A7" smd rect
			(at 5.500116 -0.309118 270)
			(size 0.7112 3.6068)
			(drill
				(offset 0 -0.381)
			)
			(layers "F.Cu" "F.Mask" "F.Paste")
			(net "P12V")
		)
		(pad "A8" smd rect
			(at 4.500118 -0.309118 270)
			(size 0.7112 3.6068)
			(drill
				(offset 0 -0.381)
			)
			(layers "F.Cu" "F.Mask" "F.Paste")
			(net "P12V")
		)
		(pad "A9" smd rect
			(at 3.50012 -0.309118 270)
			(size 0.7112 3.6068)
			(drill
				(offset 0 -0.381)
			)
			(layers "F.Cu" "F.Mask" "F.Paste")
			(net "Net_87")
		)
		(pad "A10" smd rect
			(at 2.500122 -0.309118 270)
			(size 0.7112 3.6068)
			(drill
				(offset 0 -0.381)
			)
			(layers "F.Cu" "F.Mask" "F.Paste")
			(net "Net_86")
		)
		(pad "A11" smd rect
			(at 1.500124 -0.309118 270)
			(size 0.7112 3.6068)
			(drill
				(offset 0 -0.381)
			)
			(layers "F.Cu" "F.Mask" "F.Paste")
			(net "Net_85")
		)
		(pad "A12" smd rect
			(at -1.500124 -0.309118 270)
			(size 0.7112 3.6068)
			(drill
				(offset 0 -0.381)
			)
			(layers "F.Cu" "F.Mask" "F.Paste")
			(net "Net_94")
		)
		(pad "A13" smd rect
			(at -2.500122 -0.309118 270)
			(size 0.7112 3.6068)
			(drill
				(offset 0 -0.381)
			)
			(layers "F.Cu" "F.Mask" "F.Paste")
			(net "GND")
		)
		(pad "A14" smd rect
			(at -3.50012 -0.309118 270)
			(size 0.7112 3.6068)
			(drill
				(offset 0 -0.381)
			)
			(layers "F.Cu" "F.Mask" "F.Paste")
			(net "Net_93")
		)
		(pad "A15" smd rect
			(at -4.500118 -0.309118 270)
			(size 0.7112 3.6068)
			(drill
				(offset 0 -0.381)
			)
			(layers "F.Cu" "F.Mask" "F.Paste")
			(net "Net_92")
		)
		(pad "A16" smd rect
			(at -5.500116 -0.309118 270)
			(size 0.7112 3.6068)
			(drill
				(offset 0 -0.381)
			)
			(layers "F.Cu" "F.Mask" "F.Paste")
			(net "GND")
		)
		(pad "A17" smd rect
			(at -6.500114 -0.309118 270)
			(size 0.7112 3.6068)
			(drill
				(offset 0 -0.381)
			)
			(layers "F.Cu" "F.Mask" "F.Paste")
			(net "Net_97")
		)
		(pad "A18" smd rect
			(at -7.500112 -0.309118 270)
			(size 0.7112 3.6068)
			(drill
				(offset 0 -0.381)
			)
			(layers "F.Cu" "F.Mask" "F.Paste")
			(net "GND")
		)
		(pad "B1" smd rect
			(at 11.500104 -0.690118 270)
			(size 0.7112 3.6068)
			(layers "F.Cu" "F.Mask" "F.Paste")
			(net "GND")
		)
		(pad "B2" smd rect
			(at 10.500106 -0.690118 270)
			(size 0.7112 3.6068)
			(layers "F.Cu" "F.Mask" "F.Paste")
			(net "GND")
		)
		(pad "B3" smd rect
			(at 9.500108 -0.690118 270)
			(size 0.7112 3.6068)
			(layers "F.Cu" "F.Mask" "F.Paste")
			(net "GND")
		)
		(pad "B4" smd rect
			(at 8.50011 -0.690118 270)
			(size 0.7112 3.6068)
			(layers "F.Cu" "F.Mask" "F.Paste")
			(net "GND")
		)
		(pad "B5" smd rect
			(at 7.500112 -0.690118 270)
			(size 0.7112 3.6068)
			(layers "F.Cu" "F.Mask" "F.Paste")
			(net "GND")
		)
		(pad "B6" smd rect
			(at 6.500114 -0.690118 270)
			(size 0.7112 3.6068)
			(layers "F.Cu" "F.Mask" "F.Paste")
			(net "GND")
		)
		(pad "B7" smd rect
			(at 5.500116 -0.690118 270)
			(size 0.7112 3.6068)
			(layers "F.Cu" "F.Mask" "F.Paste")
			(net "GND")
		)
		(pad "B8" smd rect
			(at 4.500118 -0.690118 270)
			(size 0.7112 3.6068)
			(layers "F.Cu" "F.Mask" "F.Paste")
			(net "Net_91")
		)
		(pad "B9" smd rect
			(at 3.50012 -0.690118 270)
			(size 0.7112 3.6068)
			(layers "F.Cu" "F.Mask" "F.Paste")
			(net "Net_90")
		)
		(pad "B10" smd rect
			(at 2.500122 -0.690118 270)
			(size 0.7112 3.6068)
			(layers "F.Cu" "F.Mask" "F.Paste")
			(net "Net_89")
		)
		(pad "B11" smd rect
			(at 1.500124 -0.690118 270)
			(size 0.7112 3.6068)
			(layers "F.Cu" "F.Mask" "F.Paste")
			(net "Net_88")
		)
		(pad "B12" smd rect
			(at -1.500124 -0.690118 270)
			(size 0.7112 3.6068)
			(layers "F.Cu" "F.Mask" "F.Paste")
			(net "GND")
		)
		(pad "B13" smd rect
			(at -2.500122 -0.690118 270)
			(size 0.7112 3.6068)
			(layers "F.Cu" "F.Mask" "F.Paste")
			(net "Net_96")
		)
		(pad "B14" smd rect
			(at -3.50012 -0.690118 270)
			(size 0.7112 3.6068)
			(layers "F.Cu" "F.Mask" "F.Paste")
			(net "Net_95")
		)
		(pad "B15" smd rect
			(at -4.500118 -0.690118 270)
			(size 0.7112 3.6068)
			(layers "F.Cu" "F.Mask" "F.Paste")
			(net "GND")
		)
		(pad "B16" smd rect
			(at -5.500116 -0.690118 270)
			(size 0.7112 3.6068)
			(layers "F.Cu" "F.Mask" "F.Paste")
			(net "Net_99")
		)
		(pad "B17" smd rect
			(at -6.500114 -0.690118 270)
			(size 0.7112 3.6068)
			(layers "F.Cu" "F.Mask" "F.Paste")
			(net "Net_98")
		)
		(pad "B18" smd rect
			(at -7.500112 -0.690118 270)
			(size 0.7112 3.6068)
			(layers "F.Cu" "F.Mask" "F.Paste")
			(net "GND")
		)
		(zone
			(layers "F.Cu" "B.Cu" "In1.Cu" "In2.Cu" "In3.Cu" "In4.Cu" "In5.Cu" "In6.Cu")
			(hatch none 0.5)
			(connect_pads
				(clearance 0)
			)
			(min_thickness 0.25)
			(keepout
				(tracks not_allowed)
				(vias allowed)
				(pads allowed)
				(copperpour not_allowed)
				(footprints allowed)
			)
			(placement
				(enabled no)
				(sheetname "")
			)
			(fill
				(thermal_gap 0.5)
				(thermal_bridge_width 0.5)
				(island_removal_mode 0)
			)
			(polygon
				(pts
					(arc
						(start 3.960622 -67.504818)
						(mid 1.039622 -67.504818)
						(end 3.960622 -67.504818)
					)
				)
			)
		)
		(zone
			(layers "F.Cu" "B.Cu" "In1.Cu" "In2.Cu" "In3.Cu" "In4.Cu" "In5.Cu" "In6.Cu")
			(hatch none 0.5)
			(connect_pads
				(clearance 0)
			)
			(min_thickness 0.25)
			(keepout
				(tracks not_allowed)
				(vias allowed)
				(pads allowed)
				(copperpour not_allowed)
				(footprints allowed)
			)
			(placement
				(enabled no)
				(sheetname "")
			)
			(fill
				(thermal_gap 0.5)
				(thermal_bridge_width 0.5)
				(island_removal_mode 0)
			)
			(polygon
				(pts
					(arc
						(start 3.960622 -38.904672)
						(mid 1.039622 -38.904672)
						(end 3.960622 -38.904672)
					)
				)
			)
		)
	)
	(footprint ""
		(layer "F.Cu")
		(at 67.182746 -180.0987 -90)
		(property "Reference" "Q17"
			(at 0 0 270)
			(layer "F.SilkS")
			(hide yes)
			(effects
				(font
					(size 1.27 1.27)
				)
			)
		)
		(property "Value" "AO4406AL-GP"
			(at -3.707384 -1.5367 270)
			(unlocked yes)
			(layer "F.Fab")
			(hide yes)
			(effects
				(font
					(size 1.016 1.016)
					(thickness 0.1524)
				)
			)
		)
		(property "Device Type" "SOIC8H69"
			(at -3.707384 -3.0607 270)
			(unlocked yes)
			(layer "F.Fab")
			(hide yes)
			(effects
				(font
					(size 1.016 1.016)
					(thickness 0.1524)
				)
			)
		)
		(duplicate_pad_numbers_are_jumpers no)
		(fp_line
			(start -2.6289 3.4417)
			(end -2.6289 1.4732)
			(stroke
				(width 0.381)
				(type default)
			)
			(layer "F.SilkS")
		)
		(fp_line
			(start -2.7432 1.4224)
			(end -2.6416 1.4224)
			(stroke
				(width 0.1524)
				(type default)
			)
			(layer "F.SilkS")
		)
		(fp_line
			(start -2.7432 1.4224)
			(end 2.1336 1.4224)
			(stroke
				(width 0.1524)
				(type default)
			)
			(layer "F.SilkS")
		)
		(fp_line
			(start 2.1336 1.4224)
			(end 2.1336 -1.4224)
			(stroke
				(width 0.1524)
				(type default)
			)
			(layer "F.SilkS")
		)
		(fp_line
			(start -2.1844 -0.0508)
			(end -2.7178 0.508)
			(stroke
				(width 0.1524)
				(type default)
			)
			(layer "F.SilkS")
		)
		(fp_line
			(start -2.7178 -0.508)
			(end -2.1844 -0.0508)
			(stroke
				(width 0.1524)
				(type default)
			)
			(layer "F.SilkS")
		)
		(fp_line
			(start -2.7432 -1.4224)
			(end -2.7432 1.4224)
			(stroke
				(width 0.1524)
				(type default)
			)
			(layer "F.SilkS")
		)
		(fp_line
			(start 2.1336 -1.4224)
			(end -2.7432 -1.4224)
			(stroke
				(width 0.1524)
				(type default)
			)
			(layer "F.SilkS")
		)
		(fp_poly
			(pts
				(xy -2.2098 -1.4224) (xy -2.2098 1.4224) (xy 2.2098 1.4224) (xy 2.2098 -1.4224)
			)
			(stroke
				(width 0)
				(type default)
			)
			(fill yes)
			(layer "F.SilkS")
		)
		(fp_rect
			(start -2.450084 2.999994)
			(end 2.450084 -2.999994)
			(stroke
				(width 0)
				(type default)
			)
			(fill no)
			(layer "F.CrtYd")
		)
		(fp_poly
			(pts
				(xy -2.8194 3.6322) (xy -2.8194 -3.6322) (xy 2.8194 -3.6322) (xy 2.8194 1.18364) (xy 2.450084 1.18364)
				(xy 2.450084 -2.999994) (xy -2.450084 -2.999994) (xy -2.450084 2.999994) (xy 2.450084 2.999994)
				(xy 2.450084 1.18618) (xy 2.8194 1.18618) (xy 2.8194 3.6322)
			)
			(stroke
				(width 0)
				(type default)
			)
			(fill no)
			(layer "F.CrtYd")
		)
		(fp_rect
			(start -2.8194 3.6322)
			(end 2.8194 -3.6322)
			(stroke
				(width 0)
				(type default)
			)
			(fill no)
			(layer "F.Fab")
		)
		(pad "1" smd rect
			(at -1.905 2.54 270)
			(size 0.635 1.651)
			(layers "F.Cu" "F.Mask" "F.Paste")
			(net "P5V_HDD8")
		)
		(pad "2" smd rect
			(at -0.635 2.54 270)
			(size 0.635 1.651)
			(layers "F.Cu" "F.Mask" "F.Paste")
			(net "P5V_HDD8")
		)
		(pad "3" smd rect
			(at 0.635 2.54 270)
			(size 0.635 1.651)
			(layers "F.Cu" "F.Mask" "F.Paste")
			(net "P5V_HDD8")
		)
		(pad "4" smd rect
			(at 1.905 2.54 270)
			(size 0.635 1.651)
			(layers "F.Cu" "F.Mask" "F.Paste")
			(net "SW_HDD8_P")
		)
		(pad "5" smd rect
			(at 1.905 -2.54 270)
			(size 0.635 1.651)
			(layers "F.Cu" "F.Mask" "F.Paste")
			(net "P5VB")
		)
		(pad "6" smd rect
			(at 0.635 -2.54 270)
			(size 0.635 1.651)
			(layers "F.Cu" "F.Mask" "F.Paste")
			(net "P5VB")
		)
		(pad "7" smd rect
			(at -0.635 -2.54 270)
			(size 0.635 1.651)
			(layers "F.Cu" "F.Mask" "F.Paste")
			(net "P5VB")
		)
		(pad "8" smd rect
			(at -1.905 -2.54 270)
			(size 0.635 1.651)
			(layers "F.Cu" "F.Mask" "F.Paste")
			(net "P5VB")
		)
	)
	(footprint ""
		(layer "F.Cu")
		(at 241.934746 -27.9527 180)
		(property "Reference" "PR10"
			(at 0 0 180)
			(layer "F.SilkS")
			(hide yes)
			(effects
				(font
					(size 1.27 1.27)
				)
			)
		)
		(property "Value" "100KR2F-L1-GP"
			(at 0.064008 -3.993896 180)
			(unlocked yes)
			(layer "F.Fab")
			(hide yes)
			(effects
				(font
					(size 1.016 1.016)
					(thickness 0.1524)
				)
			)
		)
		(property "Device Type" "R402H16"
			(at 0.064008 -5.517896 180)
			(unlocked yes)
			(layer "F.Fab")
			(hide yes)
			(effects
				(font
					(size 1.016 1.016)
					(thickness 0.1524)
				)
			)
		)
		(duplicate_pad_numbers_are_jumpers no)
		(fp_line
			(start 0.508 -0.9398)
			(end -0.508 -0.9398)
			(stroke
				(width 0.1524)
				(type default)
			)
			(layer "F.SilkS")
		)
		(fp_line
			(start -0.508 -0.9398)
			(end -0.508 0.9398)
			(stroke
				(width 0.1524)
				(type default)
			)
			(layer "F.SilkS")
		)
		(fp_rect
			(start -0.508 0.9398)
			(end 0.508 -0.9398)
			(stroke
				(width 0)
				(type default)
			)
			(fill no)
			(layer "F.CrtYd")
		)
		(fp_rect
			(start -0.508 0.9398)
			(end 0.508 -0.9398)
			(stroke
				(width 0)
				(type default)
			)
			(fill no)
			(layer "F.Fab")
		)
		(pad "1" smd custom
			(at 0 -0.4445 180)
			(size 0.1397 0.1397)
			(layers "F.Cu" "F.Mask" "F.Paste")
			(net "P5VA_PGD")
			(options
				(clearance outline)
				(anchor circle)
			)
			(primitives
				(gr_poly
					(pts
						(arc
							(start -0.1778 -0.2794)
							(mid -0.249642 -0.249642)
							(end -0.2794 -0.1778)
						)
						(arc
							(start -0.2794 0.1778)
							(mid -0.249642 0.249642)
							(end -0.1778 0.2794)
						)
						(arc
							(start 0.1778 0.2794)
							(mid 0.249642 0.249642)
							(end 0.2794 0.1778)
						)
						(arc
							(start 0.2794 -0.1778)
							(mid 0.249642 -0.249642)
							(end 0.1778 -0.2794)
						)
					)
					(width 0)
					(fill yes)
				)
			)
		)
		(pad "2" smd custom
			(at 0 0.4445 180)
			(size 0.1397 0.1397)
			(layers "F.Cu" "F.Mask" "F.Paste")
			(net "P5VA_MODE_PG")
			(options
				(clearance outline)
				(anchor circle)
			)
			(primitives
				(gr_poly
					(pts
						(arc
							(start -0.1778 -0.2794)
							(mid -0.249642 -0.249642)
							(end -0.2794 -0.1778)
						)
						(arc
							(start -0.2794 0.1778)
							(mid -0.249642 0.249642)
							(end -0.1778 0.2794)
						)
						(arc
							(start 0.1778 0.2794)
							(mid 0.249642 0.249642)
							(end 0.2794 0.1778)
						)
						(arc
							(start 0.2794 -0.1778)
							(mid 0.249642 -0.249642)
							(end 0.1778 -0.2794)
						)
					)
					(width 0)
					(fill yes)
				)
			)
		)
	)
	(footprint ""
		(layer "F.Cu")
		(at 23.512272 -500.446548 180)
		(property "Reference" "PC27"
			(at 0 0 180)
			(layer "F.SilkS")
			(hide yes)
			(effects
				(font
					(size 1.27 1.27)
				)
			)
		)
		(property "Value" "SC22U25V5MX-GP"
			(at -0.0762 -6.1214 180)
			(unlocked yes)
			(layer "F.Fab")
			(hide yes)
			(effects
				(font
					(size 1.016 1.016)
					(thickness 0.1524)
				)
			)
		)
		(property "Device Type" "C805H58"
			(at -0.0762 -8.1534 180)
			(unlocked yes)
			(layer "F.Fab")
			(hide yes)
			(effects
				(font
					(size 1.016 1.016)
					(thickness 0.1524)
				)
			)
		)
		(duplicate_pad_numbers_are_jumpers no)
		(fp_line
			(start 0.635 0)
			(end -0.635 0)
			(stroke
				(width 0.508)
				(type default)
			)
			(layer "F.SilkS")
		)
		(fp_rect
			(start -0.9652 1.778)
			(end 0.9652 -1.778)
			(stroke
				(width 0)
				(type default)
			)
			(fill no)
			(layer "F.CrtYd")
		)
		(fp_poly
			(pts
				(xy -0.9652 -1.778) (xy 0.9652 -1.778) (xy 0.9652 1.778) (xy -0.9652 1.778)
			)
			(stroke
				(width 0)
				(type default)
			)
			(fill no)
			(layer "F.Fab")
		)
		(pad "1" smd rect
			(at 0 -0.9652 180)
			(size 1.397 1.143)
			(layers "F.Cu" "F.Mask" "F.Paste")
			(net "P5VC_12VIN")
		)
		(pad "2" smd rect
			(at 0 0.9652 180)
			(size 1.397 1.143)
			(layers "F.Cu" "F.Mask" "F.Paste")
			(net "GND")
		)
	)
	(footprint ""
		(layer "F.Cu")
		(at 37.083746 -436.5117 90)
		(property "Reference" "R253"
			(at 0 0 90)
			(layer "F.SilkS")
			(hide yes)
			(effects
				(font
					(size 1.27 1.27)
				)
			)
		)
		(property "Value" "0R2J-2-GP"
			(at 0.064008 -3.993896 90)
			(unlocked yes)
			(layer "F.Fab")
			(hide yes)
			(effects
				(font
					(size 1.016 1.016)
					(thickness 0.1524)
				)
			)
		)
		(property "Device Type" "R402H16"
			(at 0.064008 -5.517896 90)
			(unlocked yes)
			(layer "F.Fab")
			(hide yes)
			(effects
				(font
					(size 1.016 1.016)
					(thickness 0.1524)
				)
			)
		)
		(duplicate_pad_numbers_are_jumpers no)
		(fp_line
			(start 0.508 -0.9398)
			(end -0.508 -0.9398)
			(stroke
				(width 0.1524)
				(type default)
			)
			(layer "F.SilkS")
		)
		(fp_line
			(start -0.508 -0.9398)
			(end -0.508 0.9398)
			(stroke
				(width 0.1524)
				(type default)
			)
			(layer "F.SilkS")
		)
		(fp_rect
			(start -0.508 0.9398)
			(end 0.508 -0.9398)
			(stroke
				(width 0)
				(type default)
			)
			(fill no)
			(layer "F.CrtYd")
		)
		(fp_rect
			(start -0.508 0.9398)
			(end 0.508 -0.9398)
			(stroke
				(width 0)
				(type default)
			)
			(fill no)
			(layer "F.Fab")
		)
		(pad "1" smd custom
			(at 0 -0.4445 90)
			(size 0.1397 0.1397)
			(layers "F.Cu" "F.Mask" "F.Paste")
			(net "DRIVE_PWR10")
			(options
				(clearance outline)
				(anchor circle)
			)
			(primitives
				(gr_poly
					(pts
						(arc
							(start -0.1778 -0.2794)
							(mid -0.249642 -0.249642)
							(end -0.2794 -0.1778)
						)
						(arc
							(start -0.2794 0.1778)
							(mid -0.249642 0.249642)
							(end -0.1778 0.2794)
						)
						(arc
							(start 0.1778 0.2794)
							(mid 0.249642 0.249642)
							(end 0.2794 0.1778)
						)
						(arc
							(start 0.2794 -0.1778)
							(mid 0.249642 -0.249642)
							(end 0.1778 -0.2794)
						)
					)
					(width 0)
					(fill yes)
				)
			)
		)
		(pad "2" smd custom
			(at 0 0.4445 90)
			(size 0.1397 0.1397)
			(layers "F.Cu" "F.Mask" "F.Paste")
			(net "SW_PWR_HDD10")
			(options
				(clearance outline)
				(anchor circle)
			)
			(primitives
				(gr_poly
					(pts
						(arc
							(start -0.1778 -0.2794)
							(mid -0.249642 -0.249642)
							(end -0.2794 -0.1778)
						)
						(arc
							(start -0.2794 0.1778)
							(mid -0.249642 0.249642)
							(end -0.1778 0.2794)
						)
						(arc
							(start 0.1778 0.2794)
							(mid 0.249642 0.249642)
							(end 0.2794 0.1778)
						)
						(arc
							(start 0.2794 -0.1778)
							(mid 0.249642 -0.249642)
							(end 0.1778 -0.2794)
						)
					)
					(width 0)
					(fill yes)
				)
			)
		)
	)
	(footprint ""
		(layer "F.Cu")
		(at 200.037446 -458.377036 90)
		(property "Reference" "R352"
			(at 0 0 90)
			(layer "F.SilkS")
			(hide yes)
			(effects
				(font
					(size 1.27 1.27)
				)
			)
		)
		(property "Value" "0R2J-2-GP"
			(at 0.064008 -3.993896 90)
			(unlocked yes)
			(layer "F.Fab")
			(hide yes)
			(effects
				(font
					(size 1.016 1.016)
					(thickness 0.1524)
				)
			)
		)
		(property "Device Type" "R402H16"
			(at 0.064008 -5.517896 90)
			(unlocked yes)
			(layer "F.Fab")
			(hide yes)
			(effects
				(font
					(size 1.016 1.016)
					(thickness 0.1524)
				)
			)
		)
		(duplicate_pad_numbers_are_jumpers no)
		(fp_line
			(start 0.508 -0.9398)
			(end -0.508 -0.9398)
			(stroke
				(width 0.1524)
				(type default)
			)
			(layer "F.SilkS")
		)
		(fp_line
			(start -0.508 -0.9398)
			(end -0.508 0.9398)
			(stroke
				(width 0.1524)
				(type default)
			)
			(layer "F.SilkS")
		)
		(fp_rect
			(start -0.508 0.9398)
			(end 0.508 -0.9398)
			(stroke
				(width 0)
				(type default)
			)
			(fill no)
			(layer "F.CrtYd")
		)
		(fp_rect
			(start -0.508 0.9398)
			(end 0.508 -0.9398)
			(stroke
				(width 0)
				(type default)
			)
			(fill no)
			(layer "F.Fab")
		)
		(pad "1" smd custom
			(at 0 -0.4445 90)
			(size 0.1397 0.1397)
			(layers "F.Cu" "F.Mask" "F.Paste")
			(net "EEPROM_SCL")
			(options
				(clearance outline)
				(anchor circle)
			)
			(primitives
				(gr_poly
					(pts
						(arc
							(start -0.1778 -0.2794)
							(mid -0.249642 -0.249642)
							(end -0.2794 -0.1778)
						)
						(arc
							(start -0.2794 0.1778)
							(mid -0.249642 0.249642)
							(end -0.1778 0.2794)
						)
						(arc
							(start 0.1778 0.2794)
							(mid 0.249642 0.249642)
							(end 0.2794 0.1778)
						)
						(arc
							(start 0.2794 -0.1778)
							(mid 0.249642 -0.249642)
							(end 0.1778 -0.2794)
						)
					)
					(width 0)
					(fill yes)
				)
			)
		)
		(pad "2" smd custom
			(at 0 0.4445 90)
			(size 0.1397 0.1397)
			(layers "F.Cu" "F.Mask" "F.Paste")
			(net "I2C_B_SCL")
			(options
				(clearance outline)
				(anchor circle)
			)
			(primitives
				(gr_poly
					(pts
						(arc
							(start -0.1778 -0.2794)
							(mid -0.249642 -0.249642)
							(end -0.2794 -0.1778)
						)
						(arc
							(start -0.2794 0.1778)
							(mid -0.249642 0.249642)
							(end -0.1778 0.2794)
						)
						(arc
							(start 0.1778 0.2794)
							(mid 0.249642 0.249642)
							(end 0.2794 0.1778)
						)
						(arc
							(start 0.2794 -0.1778)
							(mid 0.249642 -0.249642)
							(end 0.1778 -0.2794)
						)
					)
					(width 0)
					(fill yes)
				)
			)
		)
	)
	(footprint ""
		(layer "F.Cu")
		(at 197.739 -281.686)
		(property "Reference" "C133"
			(at 0 0 0)
			(layer "F.SilkS")
			(hide yes)
			(effects
				(font
					(size 1.27 1.27)
				)
			)
		)
		(property "Value" "SCD1U10V2KX-5GP"
			(at 1.1811 -2.7051 0)
			(unlocked yes)
			(layer "F.Fab")
			(hide yes)
			(effects
				(font
					(size 1.016 1.016)
					(thickness 0.1524)
				)
			)
		)
		(property "Device Type" "C402H22"
			(at 1.1811 -4.2291 0)
			(unlocked yes)
			(layer "F.Fab")
			(hide yes)
			(effects
				(font
					(size 1.016 1.016)
					(thickness 0.1524)
				)
			)
		)
		(duplicate_pad_numbers_are_jumpers no)
		(fp_rect
			(start -0.4318 0.9525)
			(end 0.4318 -0.9525)
			(stroke
				(width 0)
				(type default)
			)
			(fill no)
			(layer "F.CrtYd")
		)
		(fp_rect
			(start -0.4318 0.9525)
			(end 0.4318 -0.9525)
			(stroke
				(width 0)
				(type default)
			)
			(fill no)
			(layer "F.Fab")
		)
		(pad "1" smd custom
			(at 0 -0.4445)
			(size 0.1524 0.1524)
			(layers "F.Cu" "F.Mask" "F.Paste")
			(net "P3V3")
			(options
				(clearance outline)
				(anchor circle)
			)
			(primitives
				(gr_poly
					(pts
						(arc
							(start 0.3048 -0.2032)
							(mid 0.275042 -0.275042)
							(end 0.2032 -0.3048)
						)
						(arc
							(start -0.2032 -0.3048)
							(mid -0.275042 -0.275042)
							(end -0.3048 -0.2032)
						)
						(arc
							(start -0.3048 0.2032)
							(mid -0.275042 0.275042)
							(end -0.2032 0.3048)
						)
						(arc
							(start 0.2032 0.3048)
							(mid 0.275042 0.275042)
							(end 0.3048 0.2032)
						)
					)
					(width 0)
					(fill yes)
				)
			)
		)
		(pad "2" smd custom
			(at 0 0.4445)
			(size 0.1524 0.1524)
			(layers "F.Cu" "F.Mask" "F.Paste")
			(net "GND")
			(options
				(clearance outline)
				(anchor circle)
			)
			(primitives
				(gr_poly
					(pts
						(arc
							(start 0.3048 -0.2032)
							(mid 0.275042 -0.275042)
							(end 0.2032 -0.3048)
						)
						(arc
							(start -0.2032 -0.3048)
							(mid -0.275042 -0.275042)
							(end -0.3048 -0.2032)
						)
						(arc
							(start -0.3048 0.2032)
							(mid -0.275042 0.275042)
							(end -0.2032 0.3048)
						)
						(arc
							(start 0.2032 0.3048)
							(mid 0.275042 0.275042)
							(end 0.3048 0.2032)
						)
					)
					(width 0)
					(fill yes)
				)
			)
		)
	)
	(footprint ""
		(layer "F.Cu")
		(at 202.564746 -185.9407 -90)
		(property "Reference" "R435"
			(at 0 0 270)
			(layer "F.SilkS")
			(hide yes)
			(effects
				(font
					(size 1.27 1.27)
				)
			)
		)
		(property "Value" "4K7R2J-2-GP"
			(at 0.064008 -3.993896 270)
			(unlocked yes)
			(layer "F.Fab")
			(hide yes)
			(effects
				(font
					(size 1.016 1.016)
					(thickness 0.1524)
				)
			)
		)
		(property "Device Type" "R402H16"
			(at 0.064008 -5.517896 270)
			(unlocked yes)
			(layer "F.Fab")
			(hide yes)
			(effects
				(font
					(size 1.016 1.016)
					(thickness 0.1524)
				)
			)
		)
		(duplicate_pad_numbers_are_jumpers no)
		(fp_line
			(start -0.508 -0.9398)
			(end -0.508 0.9398)
			(stroke
				(width 0.1524)
				(type default)
			)
			(layer "F.SilkS")
		)
		(fp_line
			(start 0.508 -0.9398)
			(end -0.508 -0.9398)
			(stroke
				(width 0.1524)
				(type default)
			)
			(layer "F.SilkS")
		)
		(fp_rect
			(start -0.508 0.9398)
			(end 0.508 -0.9398)
			(stroke
				(width 0)
				(type default)
			)
			(fill no)
			(layer "F.CrtYd")
		)
		(fp_rect
			(start -0.508 0.9398)
			(end 0.508 -0.9398)
			(stroke
				(width 0)
				(type default)
			)
			(fill no)
			(layer "F.Fab")
		)
		(pad "1" smd custom
			(at 0 -0.4445 270)
			(size 0.1397 0.1397)
			(layers "F.Cu" "F.Mask" "F.Paste")
			(net "P3V3")
			(options
				(clearance outline)
				(anchor circle)
			)
			(primitives
				(gr_poly
					(pts
						(arc
							(start -0.1778 -0.2794)
							(mid -0.249642 -0.249642)
							(end -0.2794 -0.1778)
						)
						(arc
							(start -0.2794 0.1778)
							(mid -0.249642 0.249642)
							(end -0.1778 0.2794)
						)
						(arc
							(start 0.1778 0.2794)
							(mid 0.249642 0.249642)
							(end 0.2794 0.1778)
						)
						(arc
							(start 0.2794 -0.1778)
							(mid 0.249642 -0.249642)
							(end 0.1778 -0.2794)
						)
					)
					(width 0)
					(fill yes)
				)
			)
		)
		(pad "2" smd custom
			(at 0 0.4445 270)
			(size 0.1397 0.1397)
			(layers "F.Cu" "F.Mask" "F.Paste")
			(net "SAS2X28_B_HDD3_FLT")
			(options
				(clearance outline)
				(anchor circle)
			)
			(primitives
				(gr_poly
					(pts
						(arc
							(start -0.1778 -0.2794)
							(mid -0.249642 -0.249642)
							(end -0.2794 -0.1778)
						)
						(arc
							(start -0.2794 0.1778)
							(mid -0.249642 0.249642)
							(end -0.1778 0.2794)
						)
						(arc
							(start 0.1778 0.2794)
							(mid 0.249642 0.249642)
							(end 0.2794 0.1778)
						)
						(arc
							(start 0.2794 -0.1778)
							(mid 0.249642 -0.249642)
							(end 0.1778 -0.2794)
						)
					)
					(width 0)
					(fill yes)
				)
			)
		)
	)
	(footprint ""
		(layer "F.Cu")
		(at 46.964346 -38.608 -90)
		(property "Reference" "R499"
			(at 0 0 270)
			(layer "F.SilkS")
			(hide yes)
			(effects
				(font
					(size 1.27 1.27)
				)
			)
		)
		(property "Value" "1KR2F-3-GP"
			(at 0.064008 -3.993896 270)
			(unlocked yes)
			(layer "F.Fab")
			(hide yes)
			(effects
				(font
					(size 1.016 1.016)
					(thickness 0.1524)
				)
			)
		)
		(property "Device Type" "R402H16"
			(at 0.064008 -5.517896 270)
			(unlocked yes)
			(layer "F.Fab")
			(hide yes)
			(effects
				(font
					(size 1.016 1.016)
					(thickness 0.1524)
				)
			)
		)
		(duplicate_pad_numbers_are_jumpers no)
		(fp_line
			(start -0.508 -0.9398)
			(end -0.508 0.9398)
			(stroke
				(width 0.1524)
				(type default)
			)
			(layer "F.SilkS")
		)
		(fp_line
			(start 0.508 -0.9398)
			(end -0.508 -0.9398)
			(stroke
				(width 0.1524)
				(type default)
			)
			(layer "F.SilkS")
		)
		(fp_rect
			(start -0.508 0.9398)
			(end 0.508 -0.9398)
			(stroke
				(width 0)
				(type default)
			)
			(fill no)
			(layer "F.CrtYd")
		)
		(fp_rect
			(start -0.508 0.9398)
			(end 0.508 -0.9398)
			(stroke
				(width 0)
				(type default)
			)
			(fill no)
			(layer "F.Fab")
		)
		(pad "1" smd custom
			(at 0 -0.4445 270)
			(size 0.1397 0.1397)
			(layers "F.Cu" "F.Mask" "F.Paste")
			(net "FLT_HDD9_B")
			(options
				(clearance outline)
				(anchor circle)
			)
			(primitives
				(gr_poly
					(pts
						(arc
							(start -0.1778 -0.2794)
							(mid -0.249642 -0.249642)
							(end -0.2794 -0.1778)
						)
						(arc
							(start -0.2794 0.1778)
							(mid -0.249642 0.249642)
							(end -0.1778 0.2794)
						)
						(arc
							(start 0.1778 0.2794)
							(mid 0.249642 0.249642)
							(end 0.2794 0.1778)
						)
						(arc
							(start 0.2794 -0.1778)
							(mid 0.249642 -0.249642)
							(end 0.1778 -0.2794)
						)
					)
					(width 0)
					(fill yes)
				)
			)
		)
		(pad "2" smd custom
			(at 0 0.4445 270)
			(size 0.1397 0.1397)
			(layers "F.Cu" "F.Mask" "F.Paste")
			(net "FLT_HDD9_DRIVE")
			(options
				(clearance outline)
				(anchor circle)
			)
			(primitives
				(gr_poly
					(pts
						(arc
							(start -0.1778 -0.2794)
							(mid -0.249642 -0.249642)
							(end -0.2794 -0.1778)
						)
						(arc
							(start -0.2794 0.1778)
							(mid -0.249642 0.249642)
							(end -0.1778 0.2794)
						)
						(arc
							(start 0.1778 0.2794)
							(mid 0.249642 0.249642)
							(end 0.2794 0.1778)
						)
						(arc
							(start 0.2794 -0.1778)
							(mid 0.249642 -0.249642)
							(end 0.1778 -0.2794)
						)
					)
					(width 0)
					(fill yes)
				)
			)
		)
	)
	(footprint ""
		(layer "F.Cu")
		(at 34.6964 -299.0596 180)
		(property "Reference" "C227"
			(at 0 0 180)
			(layer "F.SilkS")
			(hide yes)
			(effects
				(font
					(size 1.27 1.27)
				)
			)
		)
		(property "Value" "SC1U25V3KX-1-GP"
			(at 0 -2.8194 180)
			(unlocked yes)
			(layer "F.Fab")
			(hide yes)
			(effects
				(font
					(size 1.016 1.016)
					(thickness 0.1524)
				)
			)
		)
		(property "Device Type" "C603H36"
			(at 0 -4.3434 180)
			(unlocked yes)
			(layer "F.Fab")
			(hide yes)
			(effects
				(font
					(size 1.016 1.016)
					(thickness 0.1524)
				)
			)
		)
		(duplicate_pad_numbers_are_jumpers no)
		(fp_line
			(start 0.508 0)
			(end -0.508 0)
			(stroke
				(width 0.2032)
				(type default)
			)
			(layer "F.SilkS")
		)
		(fp_rect
			(start -0.5842 1.3335)
			(end 0.5842 -1.3335)
			(stroke
				(width 0)
				(type default)
			)
			(fill no)
			(layer "F.CrtYd")
		)
		(fp_rect
			(start -0.5842 1.3335)
			(end 0.5842 -1.3335)
			(stroke
				(width 0)
				(type default)
			)
			(fill no)
			(layer "F.Fab")
		)
		(pad "1" smd custom
			(at 0 -0.762 180)
			(size 0.2159 0.2159)
			(layers "F.Cu" "F.Mask" "F.Paste")
			(net "P12V_HDD7")
			(options
				(clearance outline)
				(anchor circle)
			)
			(primitives
				(gr_poly
					(pts
						(arc
							(start -0.3302 -0.4318)
							(mid -0.402042 -0.402042)
							(end -0.4318 -0.3302)
						)
						(arc
							(start -0.4318 0.3302)
							(mid -0.402042 0.402042)
							(end -0.3302 0.4318)
						)
						(arc
							(start 0.3302 0.4318)
							(mid 0.402042 0.402042)
							(end 0.4318 0.3302)
						)
						(arc
							(start 0.4318 -0.3302)
							(mid 0.402042 -0.402042)
							(end 0.3302 -0.4318)
						)
					)
					(width 0)
					(fill yes)
				)
			)
		)
		(pad "2" smd custom
			(at 0 0.762 180)
			(size 0.2159 0.2159)
			(layers "F.Cu" "F.Mask" "F.Paste")
			(net "GND")
			(options
				(clearance outline)
				(anchor circle)
			)
			(primitives
				(gr_poly
					(pts
						(arc
							(start -0.3302 -0.4318)
							(mid -0.402042 -0.402042)
							(end -0.4318 -0.3302)
						)
						(arc
							(start -0.4318 0.3302)
							(mid -0.402042 0.402042)
							(end -0.3302 0.4318)
						)
						(arc
							(start 0.3302 0.4318)
							(mid 0.402042 0.402042)
							(end 0.4318 0.3302)
						)
						(arc
							(start 0.4318 -0.3302)
							(mid 0.402042 -0.402042)
							(end 0.3302 -0.4318)
						)
					)
					(width 0)
					(fill yes)
				)
			)
		)
	)
	(footprint ""
		(layer "F.Cu")
		(at 78.612746 -193.6877 90)
		(property "Reference" "R222"
			(at 0 0 90)
			(layer "F.SilkS")
			(hide yes)
			(effects
				(font
					(size 1.27 1.27)
				)
			)
		)
		(property "Value" "200KR2F-L-GP"
			(at 0.064008 -3.993896 90)
			(unlocked yes)
			(layer "F.Fab")
			(hide yes)
			(effects
				(font
					(size 1.016 1.016)
					(thickness 0.1524)
				)
			)
		)
		(property "Device Type" "R402H16"
			(at 0.064008 -5.517896 90)
			(unlocked yes)
			(layer "F.Fab")
			(hide yes)
			(effects
				(font
					(size 1.016 1.016)
					(thickness 0.1524)
				)
			)
		)
		(duplicate_pad_numbers_are_jumpers no)
		(fp_line
			(start 0.508 -0.9398)
			(end -0.508 -0.9398)
			(stroke
				(width 0.1524)
				(type default)
			)
			(layer "F.SilkS")
		)
		(fp_line
			(start -0.508 -0.9398)
			(end -0.508 0.9398)
			(stroke
				(width 0.1524)
				(type default)
			)
			(layer "F.SilkS")
		)
		(fp_rect
			(start -0.508 0.9398)
			(end 0.508 -0.9398)
			(stroke
				(width 0)
				(type default)
			)
			(fill no)
			(layer "F.CrtYd")
		)
		(fp_rect
			(start -0.508 0.9398)
			(end 0.508 -0.9398)
			(stroke
				(width 0)
				(type default)
			)
			(fill no)
			(layer "F.Fab")
		)
		(pad "1" smd custom
			(at 0 -0.4445 90)
			(size 0.1397 0.1397)
			(layers "F.Cu" "F.Mask" "F.Paste")
			(net "P12V")
			(options
				(clearance outline)
				(anchor circle)
			)
			(primitives
				(gr_poly
					(pts
						(arc
							(start -0.1778 -0.2794)
							(mid -0.249642 -0.249642)
							(end -0.2794 -0.1778)
						)
						(arc
							(start -0.2794 0.1778)
							(mid -0.249642 0.249642)
							(end -0.1778 0.2794)
						)
						(arc
							(start 0.1778 0.2794)
							(mid 0.249642 0.249642)
							(end 0.2794 0.1778)
						)
						(arc
							(start 0.2794 -0.1778)
							(mid 0.249642 -0.249642)
							(end 0.1778 -0.2794)
						)
					)
					(width 0)
					(fill yes)
				)
			)
		)
		(pad "2" smd custom
			(at 0 0.4445 90)
			(size 0.1397 0.1397)
			(layers "F.Cu" "F.Mask" "F.Paste")
			(net "SW_HDD8_P")
			(options
				(clearance outline)
				(anchor circle)
			)
			(primitives
				(gr_poly
					(pts
						(arc
							(start -0.1778 -0.2794)
							(mid -0.249642 -0.249642)
							(end -0.2794 -0.1778)
						)
						(arc
							(start -0.2794 0.1778)
							(mid -0.249642 0.249642)
							(end -0.1778 0.2794)
						)
						(arc
							(start 0.1778 0.2794)
							(mid 0.249642 0.249642)
							(end 0.2794 0.1778)
						)
						(arc
							(start 0.2794 -0.1778)
							(mid 0.249642 -0.249642)
							(end 0.1778 -0.2794)
						)
					)
					(width 0)
					(fill yes)
				)
			)
		)
	)
	(footprint ""
		(layer "F.Cu")
		(at 7.499858 -78.629764)
		(property "Reference" "H6"
			(at 0 0 0)
			(layer "F.SilkS")
			(hide yes)
			(effects
				(font
					(size 1.27 1.27)
				)
			)
		)
		(property "Value" "HOLE315R140"
			(at 0 -7.5692 0)
			(unlocked yes)
			(layer "F.Fab")
			(hide yes)
			(effects
				(font
					(size 1.016 1.016)
					(thickness 0.1524)
				)
			)
		)
		(property "Device Type" "HOLE315R140"
			(at 0 -9.0932 0)
			(unlocked yes)
			(layer "F.Fab")
			(hide yes)
			(effects
				(font
					(size 1.016 1.016)
					(thickness 0.1524)
				)
			)
		)
		(duplicate_pad_numbers_are_jumpers no)
		(fp_poly
			(pts
				(arc
					(start 4.3053 0)
					(mid -4.3053 0)
					(end 4.3053 0)
				)
			)
			(stroke
				(width 0)
				(type default)
			)
			(fill no)
			(layer "F.CrtYd")
		)
		(fp_poly
			(pts
				(arc
					(start 4.3053 0)
					(mid -4.3053 0)
					(end 4.3053 0)
				)
			)
			(stroke
				(width 0)
				(type default)
			)
			(fill no)
			(layer "F.Fab")
		)
		(pad "1" thru_hole circle
			(at 0.00127 0.00127)
			(size 8.001 8.001)
			(drill 3.556)
			(layers "*.Cu" "*.Mask")
			(remove_unused_layers no)
			(net "GND")
			(clearance -1.7145)
			(thermal_gap 0.3048)
			(padstack
				(mode front_inner_back)
				(layer "Inner"
					(shape circle)
					(size 3.9624 3.9624)
					(clearance 0.3048)
				)
				(layer "B.Cu"
					(shape circle)
					(size 8.001 8.001)
					(clearance -1.7145)
				)
			)
		)
	)
	(footprint ""
		(layer "F.Cu")
		(at 215.773 -86.6902 180)
		(property "Reference" "C176"
			(at 0 0 180)
			(layer "F.SilkS")
			(hide yes)
			(effects
				(font
					(size 1.27 1.27)
				)
			)
		)
		(property "Value" "SC10U25V6KX-1GP"
			(at -0.0762 -5.1308 180)
			(unlocked yes)
			(layer "F.Fab")
			(hide yes)
			(effects
				(font
					(size 1.016 1.016)
					(thickness 0.1524)
				)
			)
		)
		(property "Device Type" "C1206H71"
			(at -0.127 -6.6548 180)
			(unlocked yes)
			(layer "F.Fab")
			(hide yes)
			(effects
				(font
					(size 1.016 1.016)
					(thickness 0.1524)
				)
			)
		)
		(duplicate_pad_numbers_are_jumpers no)
		(fp_line
			(start 1.016 2.2352)
			(end -1.016 2.2352)
			(stroke
				(width 0.1524)
				(type default)
			)
			(layer "F.SilkS")
		)
		(fp_line
			(start 1.016 0.8382)
			(end 1.016 2.2352)
			(stroke
				(width 0.1524)
				(type default)
			)
			(layer "F.SilkS")
		)
		(fp_line
			(start 1.016 -2.2352)
			(end 1.016 -0.8382)
			(stroke
				(width 0.1524)
				(type default)
			)
			(layer "F.SilkS")
		)
		(fp_line
			(start -1.016 2.2352)
			(end -1.016 0.8382)
			(stroke
				(width 0.1524)
				(type default)
			)
			(layer "F.SilkS")
		)
		(fp_line
			(start -1.016 -0.8382)
			(end -1.016 -2.2352)
			(stroke
				(width 0.1524)
				(type default)
			)
			(layer "F.SilkS")
		)
		(fp_line
			(start -1.016 -2.2352)
			(end 1.016 -2.2352)
			(stroke
				(width 0.1524)
				(type default)
			)
			(layer "F.SilkS")
		)
		(fp_rect
			(start -1.0922 2.3114)
			(end 1.0922 -2.3114)
			(stroke
				(width 0)
				(type default)
			)
			(fill no)
			(layer "F.CrtYd")
		)
		(fp_poly
			(pts
				(xy 1.0922 -2.3114) (xy 1.0922 2.3114) (xy -1.0922 2.3114) (xy -1.0922 -2.3114)
			)
			(stroke
				(width 0)
				(type default)
			)
			(fill no)
			(layer "F.Fab")
		)
		(pad "1" smd rect
			(at 0 -1.397 180)
			(size 1.651 1.27)
			(layers "F.Cu" "F.Mask" "F.Paste")
			(net "P12V_HDD4")
		)
		(pad "2" smd rect
			(at 0 1.397 180)
			(size 1.651 1.27)
			(layers "F.Cu" "F.Mask" "F.Paste")
			(net "GND")
		)
	)
	(footprint ""
		(layer "F.Cu")
		(at 33.019746 -64.1477 -90)
		(property "Reference" "C249"
			(at 0 0 270)
			(layer "F.SilkS")
			(hide yes)
			(effects
				(font
					(size 1.27 1.27)
				)
			)
		)
		(property "Value" "SCD01U50V2KX-1GP"
			(at 1.1811 -2.7051 270)
			(unlocked yes)
			(layer "F.Fab")
			(hide yes)
			(effects
				(font
					(size 1.016 1.016)
					(thickness 0.1524)
				)
			)
		)
		(property "Device Type" "C402H22"
			(at 1.1811 -4.2291 270)
			(unlocked yes)
			(layer "F.Fab")
			(hide yes)
			(effects
				(font
					(size 1.016 1.016)
					(thickness 0.1524)
				)
			)
		)
		(duplicate_pad_numbers_are_jumpers no)
		(fp_rect
			(start -0.4318 0.9525)
			(end 0.4318 -0.9525)
			(stroke
				(width 0)
				(type default)
			)
			(fill no)
			(layer "F.CrtYd")
		)
		(fp_rect
			(start -0.4318 0.9525)
			(end 0.4318 -0.9525)
			(stroke
				(width 0)
				(type default)
			)
			(fill no)
			(layer "F.Fab")
		)
		(pad "1" smd custom
			(at 0 -0.4445 270)
			(size 0.1524 0.1524)
			(layers "F.Cu" "F.Mask" "F.Paste")
			(net "SAS2X28_DRIVE_RX_P_B9")
			(options
				(clearance outline)
				(anchor circle)
			)
			(primitives
				(gr_poly
					(pts
						(arc
							(start 0.3048 -0.2032)
							(mid 0.275042 -0.275042)
							(end 0.2032 -0.3048)
						)
						(arc
							(start -0.2032 -0.3048)
							(mid -0.275042 -0.275042)
							(end -0.3048 -0.2032)
						)
						(arc
							(start -0.3048 0.2032)
							(mid -0.275042 0.275042)
							(end -0.2032 0.3048)
						)
						(arc
							(start 0.2032 0.3048)
							(mid 0.275042 0.275042)
							(end 0.3048 0.2032)
						)
					)
					(width 0)
					(fill yes)
				)
			)
		)
		(pad "2" smd custom
			(at 0 0.4445 270)
			(size 0.1524 0.1524)
			(layers "F.Cu" "F.Mask" "F.Paste")
			(net "SAS2X28_B_HDD9_RX_+")
			(options
				(clearance outline)
				(anchor circle)
			)
			(primitives
				(gr_poly
					(pts
						(arc
							(start 0.3048 -0.2032)
							(mid 0.275042 -0.275042)
							(end 0.2032 -0.3048)
						)
						(arc
							(start -0.2032 -0.3048)
							(mid -0.275042 -0.275042)
							(end -0.3048 -0.2032)
						)
						(arc
							(start -0.3048 0.2032)
							(mid -0.275042 0.275042)
							(end -0.2032 0.3048)
						)
						(arc
							(start 0.2032 0.3048)
							(mid 0.275042 0.275042)
							(end 0.3048 0.2032)
						)
					)
					(width 0)
					(fill yes)
				)
			)
		)
	)
	(footprint ""
		(layer "F.Cu")
		(at 22.987 -282.702 -90)
		(property "Reference" "D30"
			(at 0 0 270)
			(layer "F.SilkS")
			(hide yes)
			(effects
				(font
					(size 1.27 1.27)
				)
			)
		)
		(property "Value" "RB551V30-1-GP"
			(at 0 -6.7818 270)
			(unlocked yes)
			(layer "F.Fab")
			(hide yes)
			(effects
				(font
					(size 1.016 1.016)
					(thickness 0.1524)
				)
			)
		)
		(property "Device Type" "SOD323AKH44"
			(at 0 -8.6868 270)
			(unlocked yes)
			(layer "F.Fab")
			(hide yes)
			(effects
				(font
					(size 1.016 1.016)
					(thickness 0.1524)
				)
			)
		)
		(duplicate_pad_numbers_are_jumpers no)
		(fp_line
			(start -0.889 2.159)
			(end -0.889 -1.9304)
			(stroke
				(width 0.1524)
				(type default)
			)
			(layer "F.SilkS")
		)
		(fp_line
			(start 0.889 2.159)
			(end -0.889 2.159)
			(stroke
				(width 0.1524)
				(type default)
			)
			(layer "F.SilkS")
		)
		(fp_line
			(start 0.762 2.0574)
			(end -0.762 2.0574)
			(stroke
				(width 0.508)
				(type default)
			)
			(layer "F.SilkS")
		)
		(fp_line
			(start -0.889 -1.9304)
			(end 0.889 -1.9304)
			(stroke
				(width 0.1524)
				(type default)
			)
			(layer "F.SilkS")
		)
		(fp_line
			(start 0.889 -1.9304)
			(end 0.889 2.159)
			(stroke
				(width 0.1524)
				(type default)
			)
			(layer "F.SilkS")
		)
		(fp_rect
			(start -1.016 2.3114)
			(end 1.016 -2.0066)
			(stroke
				(width 0)
				(type default)
			)
			(fill no)
			(layer "F.CrtYd")
		)
		(fp_poly
			(pts
				(xy -1.016 -2.0066) (xy 1.016 -2.0066) (xy 1.016 2.3114) (xy -1.016 2.3114)
			)
			(stroke
				(width 0)
				(type default)
			)
			(fill no)
			(layer "F.Fab")
		)
		(pad "A" smd rect
			(at 0 -1.143 270)
			(size 0.5588 1.016)
			(layers "F.Cu" "F.Mask" "F.Paste")
			(net "SW_HDD7_R")
		)
		(pad "K" smd rect
			(at 0 1.143 270)
			(size 0.5588 1.016)
			(layers "F.Cu" "F.Mask" "F.Paste")
			(net "SW_HDD7_N")
		)
	)
	(footprint ""
		(layer "F.Cu")
		(at 53.511704 -18.422112 90)
		(property "Reference" "PU2"
			(at 0 0 90)
			(layer "F.SilkS")
			(hide yes)
			(effects
				(font
					(size 1.27 1.27)
				)
			)
		)
		(property "Value" "TPS53319DQPR-GP"
			(at 4.7498 -5.6896 90)
			(unlocked yes)
			(layer "F.Fab")
			(hide yes)
			(effects
				(font
					(size 1.016 1.016)
					(thickness 0.1524)
				)
			)
		)
		(property "Device Type" "QFN22G6050-G6133H60"
			(at 4.7498 -7.2136 90)
			(unlocked yes)
			(layer "F.Fab")
			(hide yes)
			(effects
				(font
					(size 1.016 1.016)
					(thickness 0.1524)
				)
			)
		)
		(duplicate_pad_numbers_are_jumpers no)
		(fp_line
			(start -2.286 -3.5179)
			(end -3.556 -3.5179)
			(stroke
				(width 0.1524)
				(type default)
			)
			(layer "F.SilkS")
		)
		(fp_line
			(start -3.556 -3.5179)
			(end -3.556 -2.2479)
			(stroke
				(width 0.1524)
				(type default)
			)
			(layer "F.SilkS")
		)
		(fp_line
			(start 0.500126 -3.262122)
			(end 0.500126 -3.770122)
			(stroke
				(width 0.1524)
				(type default)
			)
			(layer "F.SilkS")
		)
		(fp_line
			(start -1.999996 -3.262122)
			(end -1.999996 -4.024122)
			(stroke
				(width 0.1524)
				(type default)
			)
			(layer "F.SilkS")
		)
		(fp_line
			(start -3.556 2.2479)
			(end -3.556 3.5179)
			(stroke
				(width 0.1524)
				(type default)
			)
			(layer "F.SilkS")
		)
		(fp_line
			(start 1.500124 3.262122)
			(end 1.500124 4.024122)
			(stroke
				(width 0.1524)
				(type default)
			)
			(layer "F.SilkS")
		)
		(fp_line
			(start -0.999998 3.262122)
			(end -0.999998 3.770122)
			(stroke
				(width 0.1524)
				(type default)
			)
			(layer "F.SilkS")
		)
		(fp_line
			(start 3.556 3.5179)
			(end 3.556 2.2479)
			(stroke
				(width 0.1524)
				(type default)
			)
			(layer "F.SilkS")
		)
		(fp_line
			(start 2.286 3.5179)
			(end 3.556 3.5179)
			(stroke
				(width 0.1524)
				(type default)
			)
			(layer "F.SilkS")
		)
		(fp_line
			(start -3.556 3.5179)
			(end -2.286 3.5179)
			(stroke
				(width 0.1524)
				(type default)
			)
			(layer "F.SilkS")
		)
		(fp_poly
			(pts
				(xy 3.556 -3.5179) (xy 2.5273 -3.5179) (xy 3.556 -2.4892)
			)
			(stroke
				(width 0)
				(type default)
			)
			(fill yes)
			(layer "F.SilkS")
		)
		(fp_rect
			(start -2.9972 2.5019)
			(end 2.9972 -2.5019)
			(stroke
				(width 0)
				(type default)
			)
			(fill no)
			(layer "F.CrtYd")
		)
		(fp_poly
			(pts
				(xy 3.556 -2.5019) (xy -2.9972 -2.5019) (xy -2.9972 2.5019) (xy 2.9972 2.5019) (xy 2.9972 -2.4892)
				(xy 3.556 -2.4892) (xy 3.556 3.5179) (xy -3.556 3.5179) (xy -3.556 -3.5179) (xy 3.556 -3.5179)
			)
			(stroke
				(width 0)
				(type default)
			)
			(fill no)
			(layer "F.CrtYd")
		)
		(fp_rect
			(start -3.556 3.5179)
			(end 3.556 -3.5179)
			(stroke
				(width 0)
				(type default)
			)
			(fill no)
			(layer "F.Fab")
		)
		(pad "1" smd rect
			(at 2.500122 -2.449322 90)
			(size 0.3048 1.1176)
			(layers "F.Cu" "F.Mask" "F.Paste")
			(net "P5VB_VFB")
		)
		(pad "2" smd rect
			(at 1.999996 -2.449322 90)
			(size 0.3048 1.1176)
			(layers "F.Cu" "F.Mask" "F.Paste")
			(net "P5VB_EN")
		)
		(pad "3" smd rect
			(at 1.500124 -2.449322 90)
			(size 0.3048 1.1176)
			(layers "F.Cu" "F.Mask" "F.Paste")
			(net "P5VB_PGD")
		)
		(pad "4" smd rect
			(at 0.999998 -2.449322 90)
			(size 0.3048 1.1176)
			(layers "F.Cu" "F.Mask" "F.Paste")
			(net "P5VB_VBST")
		)
		(pad "5" smd rect
			(at 0.500126 -2.449322 90)
			(size 0.3048 1.1176)
			(layers "F.Cu" "F.Mask" "F.Paste")
			(net "P5VB_ROVP")
		)
		(pad "6" smd rect
			(at 0 -2.449322 90)
			(size 0.3048 1.1176)
			(layers "F.Cu" "F.Mask" "F.Paste")
			(net "P5VB_LL")
		)
		(pad "7" smd rect
			(at -0.500126 -2.449322 90)
			(size 0.3048 1.1176)
			(layers "F.Cu" "F.Mask" "F.Paste")
			(net "P5VB_LL")
		)
		(pad "8" smd rect
			(at -0.999998 -2.449322 90)
			(size 0.3048 1.1176)
			(layers "F.Cu" "F.Mask" "F.Paste")
			(net "P5VB_LL")
		)
		(pad "9" smd rect
			(at -1.500124 -2.449322 90)
			(size 0.3048 1.1176)
			(layers "F.Cu" "F.Mask" "F.Paste")
			(net "P5VB_LL")
		)
		(pad "10" smd rect
			(at -1.999996 -2.449322 90)
			(size 0.3048 1.1176)
			(layers "F.Cu" "F.Mask" "F.Paste")
			(net "P5VB_LL")
		)
		(pad "11" smd rect
			(at -2.500122 -2.449322 90)
			(size 0.3048 1.1176)
			(layers "F.Cu" "F.Mask" "F.Paste")
			(net "P5VB_LL")
		)
		(pad "12" smd rect
			(at -2.500122 2.449322 90)
			(size 0.3048 1.1176)
			(layers "F.Cu" "F.Mask" "F.Paste")
			(net "P5VB_12VIN")
		)
		(pad "13" smd rect
			(at -1.999996 2.449322 90)
			(size 0.3048 1.1176)
			(layers "F.Cu" "F.Mask" "F.Paste")
			(net "P5VB_12VIN")
		)
		(pad "14" smd rect
			(at -1.500124 2.449322 90)
			(size 0.3048 1.1176)
			(layers "F.Cu" "F.Mask" "F.Paste")
			(net "P5VB_12VIN")
		)
		(pad "15" smd rect
			(at -0.999998 2.449322 90)
			(size 0.3048 1.1176)
			(layers "F.Cu" "F.Mask" "F.Paste")
			(net "P5VB_12VIN")
		)
		(pad "16" smd rect
			(at -0.500126 2.449322 90)
			(size 0.3048 1.1176)
			(layers "F.Cu" "F.Mask" "F.Paste")
			(net "P5VB_12VIN")
		)
		(pad "17" smd rect
			(at 0 2.449322 90)
			(size 0.3048 1.1176)
			(layers "F.Cu" "F.Mask" "F.Paste")
			(net "P5VB_12VIN")
		)
		(pad "18" smd rect
			(at 0.500126 2.449322 90)
			(size 0.3048 1.1176)
			(layers "F.Cu" "F.Mask" "F.Paste")
			(net "P5VB_VREG")
		)
		(pad "19" smd rect
			(at 0.999998 2.449322 90)
			(size 0.3048 1.1176)
			(layers "F.Cu" "F.Mask" "F.Paste")
			(net "P5VB_VDD")
		)
		(pad "20" smd rect
			(at 1.500124 2.449322 90)
			(size 0.3048 1.1176)
			(layers "F.Cu" "F.Mask" "F.Paste")
			(net "P5VB_MODE")
		)
		(pad "21" smd rect
			(at 1.999996 2.449322 90)
			(size 0.3048 1.1176)
			(layers "F.Cu" "F.Mask" "F.Paste")
			(net "P5VB_TRIP")
		)
		(pad "22" smd rect
			(at 2.500122 2.449322 90)
			(size 0.3048 1.1176)
			(layers "F.Cu" "F.Mask" "F.Paste")
			(net "P5VB_RF")
		)
		(pad "23" smd custom
			(at 0 0 90)
			(size 0.83185 0.83185)
			(layers "F.Cu" "F.Mask" "F.Paste")
			(net "GND")
			(options
				(clearance outline)
				(anchor circle)
			)
			(primitives
				(gr_poly
					(pts
						(xy -2.7813 1.6637) (xy -2.7813 1.2954) (xy -3.048 1.2954) (xy -3.048 0.9525) (xy -2.7813 0.9525)
						(xy -2.7813 -0.9525) (xy -3.048 -0.9525) (xy -3.048 -1.2954) (xy -2.7813 -1.2954) (xy -2.7813 -1.6637)
						(xy 2.7813 -1.6637) (xy 2.7813 -1.2954) (xy 3.048 -1.2954) (xy 3.048 -0.9525) (xy 2.7813 -0.9525)
						(xy 2.7813 0.9525) (xy 3.048 0.9525) (xy 3.048 1.2954) (xy 2.7813 1.2954) (xy 2.7813 1.6637)
					)
					(width 0)
					(fill yes)
				)
			)
		)
	)
	(footprint ""
		(layer "F.Cu")
		(at 229.488746 -29.2227 -90)
		(property "Reference" "PR4"
			(at 0 0 270)
			(layer "F.SilkS")
			(hide yes)
			(effects
				(font
					(size 1.27 1.27)
				)
			)
		)
		(property "Value" "0R3J-0-U-GP"
			(at -0.0254 -2.5146 270)
			(unlocked yes)
			(layer "F.Fab")
			(hide yes)
			(effects
				(font
					(size 1.016 1.016)
					(thickness 0.1524)
				)
			)
		)
		(property "Device Type" "R603H22"
			(at -0.0254 -4.0386 270)
			(unlocked yes)
			(layer "F.Fab")
			(hide yes)
			(effects
				(font
					(size 1.016 1.016)
					(thickness 0.1524)
				)
			)
		)
		(duplicate_pad_numbers_are_jumpers no)
		(fp_line
			(start -0.4826 0)
			(end -0.2032 0)
			(stroke
				(width 0.2032)
				(type default)
			)
			(layer "F.SilkS")
		)
		(fp_line
			(start 0.2032 0)
			(end 0.4826 0)
			(stroke
				(width 0.2032)
				(type default)
			)
			(layer "F.SilkS")
		)
		(fp_rect
			(start -0.5842 1.3335)
			(end 0.5842 -1.3335)
			(stroke
				(width 0)
				(type default)
			)
			(fill no)
			(layer "F.CrtYd")
		)
		(fp_rect
			(start -0.5842 1.3335)
			(end 0.5842 -1.3335)
			(stroke
				(width 0)
				(type default)
			)
			(fill no)
			(layer "F.Fab")
		)
		(pad "1" smd custom
			(at 0 -0.762 270)
			(size 0.2159 0.2159)
			(layers "F.Cu" "F.Mask" "F.Paste")
			(net "P5VA_VBST")
			(options
				(clearance outline)
				(anchor circle)
			)
			(primitives
				(gr_poly
					(pts
						(arc
							(start -0.3302 -0.4318)
							(mid -0.402042 -0.402042)
							(end -0.4318 -0.3302)
						)
						(arc
							(start -0.4318 0.3302)
							(mid -0.402042 0.402042)
							(end -0.3302 0.4318)
						)
						(arc
							(start 0.3302 0.4318)
							(mid 0.402042 0.402042)
							(end 0.4318 0.3302)
						)
						(arc
							(start 0.4318 -0.3302)
							(mid 0.402042 -0.402042)
							(end 0.3302 -0.4318)
						)
					)
					(width 0)
					(fill yes)
				)
			)
		)
		(pad "2" smd custom
			(at 0 0.762 270)
			(size 0.2159 0.2159)
			(layers "F.Cu" "F.Mask" "F.Paste")
			(net "P5VA_VBST_NET")
			(options
				(clearance outline)
				(anchor circle)
			)
			(primitives
				(gr_poly
					(pts
						(arc
							(start -0.3302 -0.4318)
							(mid -0.402042 -0.402042)
							(end -0.4318 -0.3302)
						)
						(arc
							(start -0.4318 0.3302)
							(mid -0.402042 0.402042)
							(end -0.3302 0.4318)
						)
						(arc
							(start 0.3302 0.4318)
							(mid 0.402042 0.402042)
							(end 0.4318 0.3302)
						)
						(arc
							(start 0.4318 -0.3302)
							(mid 0.402042 -0.402042)
							(end 0.3302 -0.4318)
						)
					)
					(width 0)
					(fill yes)
				)
			)
		)
	)
	(footprint ""
		(layer "F.Cu")
		(at 197.357746 -285.3817 -90)
		(property "Reference" "R433"
			(at 0 0 270)
			(layer "F.SilkS")
			(hide yes)
			(effects
				(font
					(size 1.27 1.27)
				)
			)
		)
		(property "Value" "4K7R2J-2-GP"
			(at 0.064008 -3.993896 270)
			(unlocked yes)
			(layer "F.Fab")
			(hide yes)
			(effects
				(font
					(size 1.016 1.016)
					(thickness 0.1524)
				)
			)
		)
		(property "Device Type" "R402H16"
			(at 0.064008 -5.517896 270)
			(unlocked yes)
			(layer "F.Fab")
			(hide yes)
			(effects
				(font
					(size 1.016 1.016)
					(thickness 0.1524)
				)
			)
		)
		(duplicate_pad_numbers_are_jumpers no)
		(fp_line
			(start -0.508 -0.9398)
			(end -0.508 0.9398)
			(stroke
				(width 0.1524)
				(type default)
			)
			(layer "F.SilkS")
		)
		(fp_line
			(start 0.508 -0.9398)
			(end -0.508 -0.9398)
			(stroke
				(width 0.1524)
				(type default)
			)
			(layer "F.SilkS")
		)
		(fp_rect
			(start -0.508 0.9398)
			(end 0.508 -0.9398)
			(stroke
				(width 0)
				(type default)
			)
			(fill no)
			(layer "F.CrtYd")
		)
		(fp_rect
			(start -0.508 0.9398)
			(end 0.508 -0.9398)
			(stroke
				(width 0)
				(type default)
			)
			(fill no)
			(layer "F.Fab")
		)
		(pad "1" smd custom
			(at 0 -0.4445 270)
			(size 0.1397 0.1397)
			(layers "F.Cu" "F.Mask" "F.Paste")
			(net "P3V3")
			(options
				(clearance outline)
				(anchor circle)
			)
			(primitives
				(gr_poly
					(pts
						(arc
							(start -0.1778 -0.2794)
							(mid -0.249642 -0.249642)
							(end -0.2794 -0.1778)
						)
						(arc
							(start -0.2794 0.1778)
							(mid -0.249642 0.249642)
							(end -0.1778 0.2794)
						)
						(arc
							(start 0.1778 0.2794)
							(mid 0.249642 0.249642)
							(end 0.2794 0.1778)
						)
						(arc
							(start 0.2794 -0.1778)
							(mid 0.249642 -0.249642)
							(end 0.1778 -0.2794)
						)
					)
					(width 0)
					(fill yes)
				)
			)
		)
		(pad "2" smd custom
			(at 0 0.4445 270)
			(size 0.1397 0.1397)
			(layers "F.Cu" "F.Mask" "F.Paste")
			(net "SAS_EXP_B_PWR2")
			(options
				(clearance outline)
				(anchor circle)
			)
			(primitives
				(gr_poly
					(pts
						(arc
							(start -0.1778 -0.2794)
							(mid -0.249642 -0.249642)
							(end -0.2794 -0.1778)
						)
						(arc
							(start -0.2794 0.1778)
							(mid -0.249642 0.249642)
							(end -0.1778 0.2794)
						)
						(arc
							(start 0.1778 0.2794)
							(mid 0.249642 0.249642)
							(end 0.2794 0.1778)
						)
						(arc
							(start 0.2794 -0.1778)
							(mid 0.249642 -0.249642)
							(end 0.1778 -0.2794)
						)
					)
					(width 0)
					(fill yes)
				)
			)
		)
	)
	(footprint ""
		(layer "F.Cu")
		(at 24.764746 -276.4917)
		(property "Reference" "R206"
			(at 0 0 0)
			(layer "F.SilkS")
			(hide yes)
			(effects
				(font
					(size 1.27 1.27)
				)
			)
		)
		(property "Value" "1KR2F-3-GP"
			(at 0.064008 -3.993896 0)
			(unlocked yes)
			(layer "F.Fab")
			(hide yes)
			(effects
				(font
					(size 1.016 1.016)
					(thickness 0.1524)
				)
			)
		)
		(property "Device Type" "R402H16"
			(at 0.064008 -5.517896 0)
			(unlocked yes)
			(layer "F.Fab")
			(hide yes)
			(effects
				(font
					(size 1.016 1.016)
					(thickness 0.1524)
				)
			)
		)
		(duplicate_pad_numbers_are_jumpers no)
		(fp_line
			(start -0.508 -0.9398)
			(end -0.508 0.9398)
			(stroke
				(width 0.1524)
				(type default)
			)
			(layer "F.SilkS")
		)
		(fp_line
			(start 0.508 -0.9398)
			(end -0.508 -0.9398)
			(stroke
				(width 0.1524)
				(type default)
			)
			(layer "F.SilkS")
		)
		(fp_rect
			(start -0.508 0.9398)
			(end 0.508 -0.9398)
			(stroke
				(width 0)
				(type default)
			)
			(fill no)
			(layer "F.CrtYd")
		)
		(fp_rect
			(start -0.508 0.9398)
			(end 0.508 -0.9398)
			(stroke
				(width 0)
				(type default)
			)
			(fill no)
			(layer "F.Fab")
		)
		(pad "1" smd custom
			(at 0 -0.4445)
			(size 0.1397 0.1397)
			(layers "F.Cu" "F.Mask" "F.Paste")
			(net "P3V3")
			(options
				(clearance outline)
				(anchor circle)
			)
			(primitives
				(gr_poly
					(pts
						(arc
							(start -0.1778 -0.2794)
							(mid -0.249642 -0.249642)
							(end -0.2794 -0.1778)
						)
						(arc
							(start -0.2794 0.1778)
							(mid -0.249642 0.249642)
							(end -0.1778 0.2794)
						)
						(arc
							(start 0.1778 0.2794)
							(mid 0.249642 0.249642)
							(end 0.2794 0.1778)
						)
						(arc
							(start 0.2794 -0.1778)
							(mid 0.249642 -0.249642)
							(end 0.1778 -0.2794)
						)
					)
					(width 0)
					(fill yes)
				)
			)
		)
		(pad "2" smd custom
			(at 0 0.4445)
			(size 0.1397 0.1397)
			(layers "F.Cu" "F.Mask" "F.Paste")
			(net "SW_PWR_HDD7")
			(options
				(clearance outline)
				(anchor circle)
			)
			(primitives
				(gr_poly
					(pts
						(arc
							(start -0.1778 -0.2794)
							(mid -0.249642 -0.249642)
							(end -0.2794 -0.1778)
						)
						(arc
							(start -0.2794 0.1778)
							(mid -0.249642 0.249642)
							(end -0.1778 0.2794)
						)
						(arc
							(start 0.1778 0.2794)
							(mid 0.249642 0.249642)
							(end 0.2794 0.1778)
						)
						(arc
							(start 0.2794 -0.1778)
							(mid 0.249642 -0.249642)
							(end 0.1778 -0.2794)
						)
					)
					(width 0)
					(fill yes)
				)
			)
		)
	)
	(footprint ""
		(layer "F.Cu")
		(at 217.727784 -172.817028)
		(property "Reference" "C156"
			(at 0 0 0)
			(layer "F.SilkS")
			(hide yes)
			(effects
				(font
					(size 1.27 1.27)
				)
			)
		)
		(property "Value" "SCD01U50V2KX-1GP"
			(at 1.1811 -2.7051 0)
			(unlocked yes)
			(layer "F.Fab")
			(hide yes)
			(effects
				(font
					(size 1.016 1.016)
					(thickness 0.1524)
				)
			)
		)
		(property "Device Type" "C402H22"
			(at 1.1811 -4.2291 0)
			(unlocked yes)
			(layer "F.Fab")
			(hide yes)
			(effects
				(font
					(size 1.016 1.016)
					(thickness 0.1524)
				)
			)
		)
		(duplicate_pad_numbers_are_jumpers no)
		(fp_rect
			(start -0.4318 0.9525)
			(end 0.4318 -0.9525)
			(stroke
				(width 0)
				(type default)
			)
			(fill no)
			(layer "F.CrtYd")
		)
		(fp_rect
			(start -0.4318 0.9525)
			(end 0.4318 -0.9525)
			(stroke
				(width 0)
				(type default)
			)
			(fill no)
			(layer "F.Fab")
		)
		(pad "1" smd custom
			(at 0 -0.4445)
			(size 0.1524 0.1524)
			(layers "F.Cu" "F.Mask" "F.Paste")
			(net "HDD_PRSNT_NET3")
			(options
				(clearance outline)
				(anchor circle)
			)
			(primitives
				(gr_poly
					(pts
						(arc
							(start 0.3048 -0.2032)
							(mid 0.275042 -0.275042)
							(end 0.2032 -0.3048)
						)
						(arc
							(start -0.2032 -0.3048)
							(mid -0.275042 -0.275042)
							(end -0.3048 -0.2032)
						)
						(arc
							(start -0.3048 0.2032)
							(mid -0.275042 0.275042)
							(end -0.2032 0.3048)
						)
						(arc
							(start 0.2032 0.3048)
							(mid 0.275042 0.275042)
							(end 0.3048 0.2032)
						)
					)
					(width 0)
					(fill yes)
				)
			)
		)
		(pad "2" smd custom
			(at 0 0.4445)
			(size 0.1524 0.1524)
			(layers "F.Cu" "F.Mask" "F.Paste")
			(net "GND")
			(options
				(clearance outline)
				(anchor circle)
			)
			(primitives
				(gr_poly
					(pts
						(arc
							(start 0.3048 -0.2032)
							(mid 0.275042 -0.275042)
							(end 0.2032 -0.3048)
						)
						(arc
							(start -0.2032 -0.3048)
							(mid -0.275042 -0.275042)
							(end -0.3048 -0.2032)
						)
						(arc
							(start -0.3048 0.2032)
							(mid -0.275042 0.275042)
							(end -0.2032 0.3048)
						)
						(arc
							(start 0.2032 0.3048)
							(mid 0.275042 0.275042)
							(end 0.3048 0.2032)
						)
					)
					(width 0)
					(fill yes)
				)
			)
		)
	)
	(footprint ""
		(layer "F.Cu")
		(at 231.774746 -27.9527)
		(property "Reference" "PR5"
			(at 0 0 0)
			(layer "F.SilkS")
			(hide yes)
			(effects
				(font
					(size 1.27 1.27)
				)
			)
		)
		(property "Value" "10KR2F-2-GP"
			(at 0.064008 -3.993896 0)
			(unlocked yes)
			(layer "F.Fab")
			(hide yes)
			(effects
				(font
					(size 1.016 1.016)
					(thickness 0.1524)
				)
			)
		)
		(property "Device Type" "R402H16"
			(at 0.064008 -5.517896 0)
			(unlocked yes)
			(layer "F.Fab")
			(hide yes)
			(effects
				(font
					(size 1.016 1.016)
					(thickness 0.1524)
				)
			)
		)
		(duplicate_pad_numbers_are_jumpers no)
		(fp_line
			(start -0.508 -0.9398)
			(end -0.508 0.9398)
			(stroke
				(width 0.1524)
				(type default)
			)
			(layer "F.SilkS")
		)
		(fp_line
			(start 0.508 -0.9398)
			(end -0.508 -0.9398)
			(stroke
				(width 0.1524)
				(type default)
			)
			(layer "F.SilkS")
		)
		(fp_rect
			(start -0.508 0.9398)
			(end 0.508 -0.9398)
			(stroke
				(width 0)
				(type default)
			)
			(fill no)
			(layer "F.CrtYd")
		)
		(fp_rect
			(start -0.508 0.9398)
			(end 0.508 -0.9398)
			(stroke
				(width 0)
				(type default)
			)
			(fill no)
			(layer "F.Fab")
		)
		(pad "1" smd custom
			(at 0 -0.4445)
			(size 0.1397 0.1397)
			(layers "F.Cu" "F.Mask" "F.Paste")
			(net "P5VA_VREG")
			(options
				(clearance outline)
				(anchor circle)
			)
			(primitives
				(gr_poly
					(pts
						(arc
							(start -0.1778 -0.2794)
							(mid -0.249642 -0.249642)
							(end -0.2794 -0.1778)
						)
						(arc
							(start -0.2794 0.1778)
							(mid -0.249642 0.249642)
							(end -0.1778 0.2794)
						)
						(arc
							(start 0.1778 0.2794)
							(mid 0.249642 0.249642)
							(end 0.2794 0.1778)
						)
						(arc
							(start 0.2794 -0.1778)
							(mid 0.249642 -0.249642)
							(end 0.1778 -0.2794)
						)
					)
					(width 0)
					(fill yes)
				)
			)
		)
		(pad "2" smd custom
			(at 0 0.4445)
			(size 0.1397 0.1397)
			(layers "F.Cu" "F.Mask" "F.Paste")
			(net "P5VA_PGD")
			(options
				(clearance outline)
				(anchor circle)
			)
			(primitives
				(gr_poly
					(pts
						(arc
							(start -0.1778 -0.2794)
							(mid -0.249642 -0.249642)
							(end -0.2794 -0.1778)
						)
						(arc
							(start -0.2794 0.1778)
							(mid -0.249642 0.249642)
							(end -0.1778 0.2794)
						)
						(arc
							(start 0.1778 0.2794)
							(mid 0.249642 0.249642)
							(end 0.2794 0.1778)
						)
						(arc
							(start 0.2794 -0.1778)
							(mid 0.249642 -0.249642)
							(end 0.1778 -0.2794)
						)
					)
					(width 0)
					(fill yes)
				)
			)
		)
	)
	(footprint ""
		(layer "F.Cu")
		(at 73.659746 -400.3167 90)
		(property "Reference" "U20"
			(at 0 0 90)
			(layer "F.SilkS")
			(hide yes)
			(effects
				(font
					(size 1.27 1.27)
				)
			)
		)
		(property "Value" "P2003EVG-GP"
			(at 0 -11.1252 90)
			(unlocked yes)
			(layer "F.Fab")
			(hide yes)
			(effects
				(font
					(size 1.016 1.016)
					(thickness 0.1524)
				)
			)
		)
		(property "Device Type" "SOIC8H79"
			(at 0 -12.6492 90)
			(unlocked yes)
			(layer "F.Fab")
			(hide yes)
			(effects
				(font
					(size 1.016 1.016)
					(thickness 0.1524)
				)
			)
		)
		(duplicate_pad_numbers_are_jumpers no)
		(fp_line
			(start 2.1336 -1.4224)
			(end -2.7432 -1.4224)
			(stroke
				(width 0.1524)
				(type default)
			)
			(layer "F.SilkS")
		)
		(fp_line
			(start -2.7432 -1.4224)
			(end -2.7432 1.4224)
			(stroke
				(width 0.1524)
				(type default)
			)
			(layer "F.SilkS")
		)
		(fp_line
			(start -2.7432 -0.508)
			(end -2.2352 0)
			(stroke
				(width 0.1524)
				(type default)
			)
			(layer "F.SilkS")
		)
		(fp_line
			(start -2.2352 0)
			(end -2.7432 0.508)
			(stroke
				(width 0.1524)
				(type default)
			)
			(layer "F.SilkS")
		)
		(fp_line
			(start 2.1336 1.4224)
			(end 2.1336 -1.4224)
			(stroke
				(width 0.1524)
				(type default)
			)
			(layer "F.SilkS")
		)
		(fp_line
			(start -2.7432 1.4224)
			(end 2.1336 1.4224)
			(stroke
				(width 0.1524)
				(type default)
			)
			(layer "F.SilkS")
		)
		(fp_line
			(start -2.6162 3.429)
			(end -2.6162 1.4732)
			(stroke
				(width 0.4064)
				(type default)
			)
			(layer "F.SilkS")
		)
		(fp_poly
			(pts
				(xy 2.2098 -1.4224) (xy 2.2098 1.4224) (xy -2.2225 1.4224) (xy -2.2225 -1.4224)
			)
			(stroke
				(width 0)
				(type default)
			)
			(fill yes)
			(layer "F.SilkS")
		)
		(fp_rect
			(start -2.4511 2.9972)
			(end 2.4511 -2.9972)
			(stroke
				(width 0)
				(type default)
			)
			(fill no)
			(layer "F.CrtYd")
		)
		(fp_poly
			(pts
				(xy -2.8194 3.6322) (xy -2.8194 -3.6322) (xy 2.8194 -3.6322) (xy 2.8194 -2.2987) (xy 2.4511 -2.2987)
				(xy 2.4511 -2.9972) (xy -2.4511 -2.9972) (xy -2.4511 2.9972) (xy 2.4511 2.9972) (xy 2.4511 -2.286)
				(xy 2.8194 -2.286) (xy 2.8194 3.6322)
			)
			(stroke
				(width 0)
				(type default)
			)
			(fill no)
			(layer "F.CrtYd")
		)
		(fp_rect
			(start -2.8194 3.6322)
			(end 2.8194 -3.6322)
			(stroke
				(width 0)
				(type default)
			)
			(fill no)
			(layer "F.Fab")
		)
		(pad "1" smd rect
			(at -1.905 2.54 90)
			(size 0.635 1.651)
			(layers "F.Cu" "F.Mask" "F.Paste")
			(net "P12V")
		)
		(pad "2" smd rect
			(at -0.635 2.54 90)
			(size 0.635 1.651)
			(layers "F.Cu" "F.Mask" "F.Paste")
			(net "P12V")
		)
		(pad "3" smd rect
			(at 0.635 2.54 90)
			(size 0.635 1.651)
			(layers "F.Cu" "F.Mask" "F.Paste")
			(net "P12V")
		)
		(pad "4" smd rect
			(at 1.905 2.54 90)
			(size 0.635 1.651)
			(layers "F.Cu" "F.Mask" "F.Paste")
			(net "SW_HDD6_N")
		)
		(pad "5" smd rect
			(at 1.905 -2.54 90)
			(size 0.635 1.651)
			(layers "F.Cu" "F.Mask" "F.Paste")
			(net "P12V_HDD6")
		)
		(pad "6" smd rect
			(at 0.635 -2.54 90)
			(size 0.635 1.651)
			(layers "F.Cu" "F.Mask" "F.Paste")
			(net "P12V_HDD6")
		)
		(pad "7" smd rect
			(at -0.635 -2.54 90)
			(size 0.635 1.651)
			(layers "F.Cu" "F.Mask" "F.Paste")
			(net "P12V_HDD6")
		)
		(pad "8" smd rect
			(at -1.905 -2.54 90)
			(size 0.635 1.651)
			(layers "F.Cu" "F.Mask" "F.Paste")
			(net "P12V_HDD6")
		)
	)
	(footprint ""
		(layer "F.Cu")
		(at 28.447746 -274.9677 180)
		(property "Reference" "U22"
			(at 0 0 180)
			(layer "F.SilkS")
			(hide yes)
			(effects
				(font
					(size 1.27 1.27)
				)
			)
		)
		(property "Value" "74LVC1G08GW-1-GP"
			(at -2.3368 -8.6868 180)
			(unlocked yes)
			(layer "F.Fab")
			(hide yes)
			(effects
				(font
					(size 1.016 1.016)
					(thickness 0.1524)
				)
			)
		)
		(property "Device Type" "SC70-5H44"
			(at -2.3114 -10.414 180)
			(unlocked yes)
			(layer "F.Fab")
			(hide yes)
			(effects
				(font
					(size 1.016 1.016)
					(thickness 0.1524)
				)
			)
		)
		(duplicate_pad_numbers_are_jumpers no)
		(fp_line
			(start 1.3843 -1.8034)
			(end 1.3843 -1.1176)
			(stroke
				(width 0.3302)
				(type default)
			)
			(layer "F.SilkS")
		)
		(fp_line
			(start 1.27 1.7018)
			(end -1.27 1.7018)
			(stroke
				(width 0.1524)
				(type default)
			)
			(layer "F.SilkS")
		)
		(fp_line
			(start 1.27 -1.7018)
			(end 1.27 1.7018)
			(stroke
				(width 0.1524)
				(type default)
			)
			(layer "F.SilkS")
		)
		(fp_line
			(start 0.6604 -1.8034)
			(end 1.3843 -1.8034)
			(stroke
				(width 0.3302)
				(type default)
			)
			(layer "F.SilkS")
		)
		(fp_line
			(start -1.27 1.7018)
			(end -1.27 -1.7018)
			(stroke
				(width 0.1524)
				(type default)
			)
			(layer "F.SilkS")
		)
		(fp_line
			(start -1.27 -1.7018)
			(end 1.27 -1.7018)
			(stroke
				(width 0.1524)
				(type default)
			)
			(layer "F.SilkS")
		)
		(fp_rect
			(start -1.524 1.9558)
			(end 1.524 -1.9558)
			(stroke
				(width 0)
				(type default)
			)
			(fill no)
			(layer "F.CrtYd")
		)
		(fp_poly
			(pts
				(xy -1.524 -1.9558) (xy 1.524 -1.9558) (xy 1.524 1.9558) (xy -1.524 1.9558)
			)
			(stroke
				(width 0)
				(type default)
			)
			(fill no)
			(layer "F.Fab")
		)
		(pad "1" smd rect
			(at 0.65024 -0.8255 180)
			(size 0.4064 1.2192)
			(layers "F.Cu" "F.Mask" "F.Paste")
			(net "SAS2X28_B_HDD7_FLT")
		)
		(pad "2" smd rect
			(at 0 -0.8255 180)
			(size 0.4064 1.2192)
			(layers "F.Cu" "F.Mask" "F.Paste")
			(net "SAS2X28_A_HDD7_FLT")
		)
		(pad "3" smd rect
			(at -0.65024 -0.8255 180)
			(size 0.4064 1.2192)
			(layers "F.Cu" "F.Mask" "F.Paste")
			(net "GND")
		)
		(pad "4" smd rect
			(at -0.65024 0.8255 180)
			(size 0.4064 1.2192)
			(layers "F.Cu" "F.Mask" "F.Paste")
			(net "FLT_HDD7_DRIVE")
		)
		(pad "5" smd rect
			(at 0.65024 0.8255 180)
			(size 0.4064 1.2192)
			(layers "F.Cu" "F.Mask" "F.Paste")
			(net "P3V3")
		)
	)
	(footprint ""
		(layer "F.Cu")
		(at 223.875854 -430.2379 -90)
		(property "Reference" "PR56"
			(at 0 0 270)
			(layer "F.SilkS")
			(hide yes)
			(effects
				(font
					(size 1.27 1.27)
				)
			)
		)
		(property "Value" "22K1R3F-GP"
			(at -0.0254 -2.5146 270)
			(unlocked yes)
			(layer "F.Fab")
			(hide yes)
			(effects
				(font
					(size 1.016 1.016)
					(thickness 0.1524)
				)
			)
		)
		(property "Device Type" "R603H22"
			(at -0.0254 -4.0386 270)
			(unlocked yes)
			(layer "F.Fab")
			(hide yes)
			(effects
				(font
					(size 1.016 1.016)
					(thickness 0.1524)
				)
			)
		)
		(duplicate_pad_numbers_are_jumpers no)
		(fp_line
			(start -0.4826 0)
			(end -0.2032 0)
			(stroke
				(width 0.2032)
				(type default)
			)
			(layer "F.SilkS")
		)
		(fp_line
			(start 0.2032 0)
			(end 0.4826 0)
			(stroke
				(width 0.2032)
				(type default)
			)
			(layer "F.SilkS")
		)
		(fp_rect
			(start -0.5842 1.3335)
			(end 0.5842 -1.3335)
			(stroke
				(width 0)
				(type default)
			)
			(fill no)
			(layer "F.CrtYd")
		)
		(fp_rect
			(start -0.5842 1.3335)
			(end 0.5842 -1.3335)
			(stroke
				(width 0)
				(type default)
			)
			(fill no)
			(layer "F.Fab")
		)
		(pad "1" smd custom
			(at 0 -0.762 270)
			(size 0.2159 0.2159)
			(layers "F.Cu" "F.Mask" "F.Paste")
			(net "P3V3_FB")
			(options
				(clearance outline)
				(anchor circle)
			)
			(primitives
				(gr_poly
					(pts
						(arc
							(start -0.3302 -0.4318)
							(mid -0.402042 -0.402042)
							(end -0.4318 -0.3302)
						)
						(arc
							(start -0.4318 0.3302)
							(mid -0.402042 0.402042)
							(end -0.3302 0.4318)
						)
						(arc
							(start 0.3302 0.4318)
							(mid 0.402042 0.402042)
							(end 0.4318 0.3302)
						)
						(arc
							(start 0.4318 -0.3302)
							(mid 0.402042 -0.402042)
							(end 0.3302 -0.4318)
						)
					)
					(width 0)
					(fill yes)
				)
			)
		)
		(pad "2" smd custom
			(at 0 0.762 270)
			(size 0.2159 0.2159)
			(layers "F.Cu" "F.Mask" "F.Paste")
			(net "GND")
			(options
				(clearance outline)
				(anchor circle)
			)
			(primitives
				(gr_poly
					(pts
						(arc
							(start -0.3302 -0.4318)
							(mid -0.402042 -0.402042)
							(end -0.4318 -0.3302)
						)
						(arc
							(start -0.4318 0.3302)
							(mid -0.402042 0.402042)
							(end -0.3302 0.4318)
						)
						(arc
							(start 0.3302 0.4318)
							(mid 0.402042 0.402042)
							(end 0.4318 0.3302)
						)
						(arc
							(start 0.4318 -0.3302)
							(mid 0.402042 -0.402042)
							(end 0.3302 -0.4318)
						)
					)
					(width 0)
					(fill yes)
				)
			)
		)
	)
	(footprint ""
		(layer "F.Cu")
		(at 215.137746 -33.0327 180)
		(property "Reference" "PC11"
			(at 0 0 180)
			(layer "F.SilkS")
			(hide yes)
			(effects
				(font
					(size 1.27 1.27)
				)
			)
		)
		(property "Value" "SC10U16V6KX-2GP"
			(at -0.0762 -5.1308 180)
			(unlocked yes)
			(layer "F.Fab")
			(hide yes)
			(effects
				(font
					(size 1.016 1.016)
					(thickness 0.1524)
				)
			)
		)
		(property "Device Type" "C1206H71"
			(at -0.127 -6.6548 180)
			(unlocked yes)
			(layer "F.Fab")
			(hide yes)
			(effects
				(font
					(size 1.016 1.016)
					(thickness 0.1524)
				)
			)
		)
		(duplicate_pad_numbers_are_jumpers no)
		(fp_line
			(start 1.016 2.2352)
			(end -1.016 2.2352)
			(stroke
				(width 0.1524)
				(type default)
			)
			(layer "F.SilkS")
		)
		(fp_line
			(start 1.016 0.8382)
			(end 1.016 2.2352)
			(stroke
				(width 0.1524)
				(type default)
			)
			(layer "F.SilkS")
		)
		(fp_line
			(start 1.016 -2.2352)
			(end 1.016 -0.8382)
			(stroke
				(width 0.1524)
				(type default)
			)
			(layer "F.SilkS")
		)
		(fp_line
			(start -1.016 2.2352)
			(end -1.016 0.8382)
			(stroke
				(width 0.1524)
				(type default)
			)
			(layer "F.SilkS")
		)
		(fp_line
			(start -1.016 -0.8382)
			(end -1.016 -2.2352)
			(stroke
				(width 0.1524)
				(type default)
			)
			(layer "F.SilkS")
		)
		(fp_line
			(start -1.016 -2.2352)
			(end 1.016 -2.2352)
			(stroke
				(width 0.1524)
				(type default)
			)
			(layer "F.SilkS")
		)
		(fp_rect
			(start -1.0922 2.3114)
			(end 1.0922 -2.3114)
			(stroke
				(width 0)
				(type default)
			)
			(fill no)
			(layer "F.CrtYd")
		)
		(fp_poly
			(pts
				(xy 1.0922 -2.3114) (xy 1.0922 2.3114) (xy -1.0922 2.3114) (xy -1.0922 -2.3114)
			)
			(stroke
				(width 0)
				(type default)
			)
			(fill no)
			(layer "F.Fab")
		)
		(pad "1" smd rect
			(at 0 -1.397 180)
			(size 1.651 1.27)
			(layers "F.Cu" "F.Mask" "F.Paste")
			(net "P5VA")
		)
		(pad "2" smd rect
			(at 0 1.397 180)
			(size 1.651 1.27)
			(layers "F.Cu" "F.Mask" "F.Paste")
			(net "GND")
		)
	)
	(footprint ""
		(layer "F.Cu")
		(at 68.999608 -479.999802)
		(property "Reference" "H12"
			(at 0 0 0)
			(layer "F.SilkS")
			(hide yes)
			(effects
				(font
					(size 1.27 1.27)
				)
			)
		)
		(property "Value" "HOLE315R140"
			(at 0 -7.5692 0)
			(unlocked yes)
			(layer "F.Fab")
			(hide yes)
			(effects
				(font
					(size 1.016 1.016)
					(thickness 0.1524)
				)
			)
		)
		(property "Device Type" "HOLE315R140"
			(at 0 -9.0932 0)
			(unlocked yes)
			(layer "F.Fab")
			(hide yes)
			(effects
				(font
					(size 1.016 1.016)
					(thickness 0.1524)
				)
			)
		)
		(duplicate_pad_numbers_are_jumpers no)
		(fp_poly
			(pts
				(arc
					(start 4.3053 0)
					(mid -4.3053 0)
					(end 4.3053 0)
				)
			)
			(stroke
				(width 0)
				(type default)
			)
			(fill no)
			(layer "F.CrtYd")
		)
		(fp_poly
			(pts
				(arc
					(start 4.3053 0)
					(mid -4.3053 0)
					(end 4.3053 0)
				)
			)
			(stroke
				(width 0)
				(type default)
			)
			(fill no)
			(layer "F.Fab")
		)
		(pad "1" thru_hole circle
			(at 0.00127 0.00127)
			(size 8.001 8.001)
			(drill 3.556)
			(layers "*.Cu" "*.Mask")
			(remove_unused_layers no)
			(net "GND")
			(clearance -1.7145)
			(thermal_gap 0.3048)
			(padstack
				(mode front_inner_back)
				(layer "Inner"
					(shape circle)
					(size 3.9624 3.9624)
					(clearance 0.3048)
				)
				(layer "B.Cu"
					(shape circle)
					(size 8.001 8.001)
					(clearance -1.7145)
				)
			)
		)
	)
	(footprint ""
		(layer "F.Cu")
		(at 59.943746 -13.0937 90)
		(property "Reference" "PC22"
			(at 0 0 90)
			(layer "F.SilkS")
			(hide yes)
			(effects
				(font
					(size 1.27 1.27)
				)
			)
		)
		(property "Value" "SC22U25V5MX-GP"
			(at -0.0762 -6.1214 90)
			(unlocked yes)
			(layer "F.Fab")
			(hide yes)
			(effects
				(font
					(size 1.016 1.016)
					(thickness 0.1524)
				)
			)
		)
		(property "Device Type" "C805H58"
			(at -0.0762 -8.1534 90)
			(unlocked yes)
			(layer "F.Fab")
			(hide yes)
			(effects
				(font
					(size 1.016 1.016)
					(thickness 0.1524)
				)
			)
		)
		(duplicate_pad_numbers_are_jumpers no)
		(fp_line
			(start 0.635 0)
			(end -0.635 0)
			(stroke
				(width 0.508)
				(type default)
			)
			(layer "F.SilkS")
		)
		(fp_rect
			(start -0.9652 1.778)
			(end 0.9652 -1.778)
			(stroke
				(width 0)
				(type default)
			)
			(fill no)
			(layer "F.CrtYd")
		)
		(fp_poly
			(pts
				(xy -0.9652 -1.778) (xy 0.9652 -1.778) (xy 0.9652 1.778) (xy -0.9652 1.778)
			)
			(stroke
				(width 0)
				(type default)
			)
			(fill no)
			(layer "F.Fab")
		)
		(pad "1" smd rect
			(at 0 -0.9652 90)
			(size 1.397 1.143)
			(layers "F.Cu" "F.Mask" "F.Paste")
			(net "P5VB_12VIN")
		)
		(pad "2" smd rect
			(at 0 0.9652 90)
			(size 1.397 1.143)
			(layers "F.Cu" "F.Mask" "F.Paste")
			(net "GND")
		)
	)
	(footprint ""
		(layer "F.Cu")
		(at 230.267256 -452.529702 90)
		(property "Reference" "R103"
			(at 0 0 90)
			(layer "F.SilkS")
			(hide yes)
			(effects
				(font
					(size 1.27 1.27)
				)
			)
		)
		(property "Value" "0R2J-2-GP"
			(at 0.064008 -3.993896 90)
			(unlocked yes)
			(layer "F.Fab")
			(hide yes)
			(effects
				(font
					(size 1.016 1.016)
					(thickness 0.1524)
				)
			)
		)
		(property "Device Type" "R402H16"
			(at 0.064008 -5.517896 90)
			(unlocked yes)
			(layer "F.Fab")
			(hide yes)
			(effects
				(font
					(size 1.016 1.016)
					(thickness 0.1524)
				)
			)
		)
		(duplicate_pad_numbers_are_jumpers no)
		(fp_line
			(start 0.508 -0.9398)
			(end -0.508 -0.9398)
			(stroke
				(width 0.1524)
				(type default)
			)
			(layer "F.SilkS")
		)
		(fp_line
			(start -0.508 -0.9398)
			(end -0.508 0.9398)
			(stroke
				(width 0.1524)
				(type default)
			)
			(layer "F.SilkS")
		)
		(fp_rect
			(start -0.508 0.9398)
			(end 0.508 -0.9398)
			(stroke
				(width 0)
				(type default)
			)
			(fill no)
			(layer "F.CrtYd")
		)
		(fp_rect
			(start -0.508 0.9398)
			(end 0.508 -0.9398)
			(stroke
				(width 0)
				(type default)
			)
			(fill no)
			(layer "F.Fab")
		)
		(pad "1" smd custom
			(at 0 -0.4445 90)
			(size 0.1397 0.1397)
			(layers "F.Cu" "F.Mask" "F.Paste")
			(net "DRV_ACT_NET0")
			(options
				(clearance outline)
				(anchor circle)
			)
			(primitives
				(gr_poly
					(pts
						(arc
							(start -0.1778 -0.2794)
							(mid -0.249642 -0.249642)
							(end -0.2794 -0.1778)
						)
						(arc
							(start -0.2794 0.1778)
							(mid -0.249642 0.249642)
							(end -0.1778 0.2794)
						)
						(arc
							(start 0.1778 0.2794)
							(mid 0.249642 0.249642)
							(end 0.2794 0.1778)
						)
						(arc
							(start 0.2794 -0.1778)
							(mid 0.249642 -0.249642)
							(end 0.1778 -0.2794)
						)
					)
					(width 0)
					(fill yes)
				)
			)
		)
		(pad "2" smd custom
			(at 0 0.4445 90)
			(size 0.1397 0.1397)
			(layers "F.Cu" "F.Mask" "F.Paste")
			(net "DRIVE_ACT_0")
			(options
				(clearance outline)
				(anchor circle)
			)
			(primitives
				(gr_poly
					(pts
						(arc
							(start -0.1778 -0.2794)
							(mid -0.249642 -0.249642)
							(end -0.2794 -0.1778)
						)
						(arc
							(start -0.2794 0.1778)
							(mid -0.249642 0.249642)
							(end -0.1778 0.2794)
						)
						(arc
							(start 0.1778 0.2794)
							(mid 0.249642 0.249642)
							(end 0.2794 0.1778)
						)
						(arc
							(start 0.2794 -0.1778)
							(mid 0.249642 -0.249642)
							(end 0.1778 -0.2794)
						)
					)
					(width 0)
					(fill yes)
				)
			)
		)
	)
	(footprint ""
		(layer "F.Cu")
		(at 200.724262 -389.224012)
		(property "Reference" "U4"
			(at 0 0 0)
			(layer "F.SilkS")
			(hide yes)
			(effects
				(font
					(size 1.27 1.27)
				)
			)
		)
		(property "Value" "74LVC1G08GW-1-GP"
			(at -2.3368 -8.6868 0)
			(unlocked yes)
			(layer "F.Fab")
			(hide yes)
			(effects
				(font
					(size 1.016 1.016)
					(thickness 0.1524)
				)
			)
		)
		(property "Device Type" "SC70-5H44"
			(at -2.3114 -10.414 0)
			(unlocked yes)
			(layer "F.Fab")
			(hide yes)
			(effects
				(font
					(size 1.016 1.016)
					(thickness 0.1524)
				)
			)
		)
		(duplicate_pad_numbers_are_jumpers no)
		(fp_line
			(start -1.27 -1.7018)
			(end 1.27 -1.7018)
			(stroke
				(width 0.1524)
				(type default)
			)
			(layer "F.SilkS")
		)
		(fp_line
			(start -1.27 1.7018)
			(end -1.27 -1.7018)
			(stroke
				(width 0.1524)
				(type default)
			)
			(layer "F.SilkS")
		)
		(fp_line
			(start 0.6604 -1.8034)
			(end 1.3843 -1.8034)
			(stroke
				(width 0.3302)
				(type default)
			)
			(layer "F.SilkS")
		)
		(fp_line
			(start 1.27 -1.7018)
			(end 1.27 1.7018)
			(stroke
				(width 0.1524)
				(type default)
			)
			(layer "F.SilkS")
		)
		(fp_line
			(start 1.27 1.7018)
			(end -1.27 1.7018)
			(stroke
				(width 0.1524)
				(type default)
			)
			(layer "F.SilkS")
		)
		(fp_line
			(start 1.3843 -1.8034)
			(end 1.3843 -1.1176)
			(stroke
				(width 0.3302)
				(type default)
			)
			(layer "F.SilkS")
		)
		(fp_rect
			(start -1.524 1.9558)
			(end 1.524 -1.9558)
			(stroke
				(width 0)
				(type default)
			)
			(fill no)
			(layer "F.CrtYd")
		)
		(fp_poly
			(pts
				(xy -1.524 -1.9558) (xy 1.524 -1.9558) (xy 1.524 1.9558) (xy -1.524 1.9558)
			)
			(stroke
				(width 0)
				(type default)
			)
			(fill no)
			(layer "F.Fab")
		)
		(pad "1" smd rect
			(at 0.65024 -0.8255)
			(size 0.4064 1.2192)
			(layers "F.Cu" "F.Mask" "F.Paste")
			(net "SAS2X28_B_HDD1_FLT")
		)
		(pad "2" smd rect
			(at 0 -0.8255)
			(size 0.4064 1.2192)
			(layers "F.Cu" "F.Mask" "F.Paste")
			(net "SAS2X28_A_HDD1_FLT")
		)
		(pad "3" smd rect
			(at -0.65024 -0.8255)
			(size 0.4064 1.2192)
			(layers "F.Cu" "F.Mask" "F.Paste")
			(net "GND")
		)
		(pad "4" smd rect
			(at -0.65024 0.8255)
			(size 0.4064 1.2192)
			(layers "F.Cu" "F.Mask" "F.Paste")
			(net "FLT_HDD1_DRIVE")
		)
		(pad "5" smd rect
			(at 0.65024 0.8255)
			(size 0.4064 1.2192)
			(layers "F.Cu" "F.Mask" "F.Paste")
			(net "P3V3")
		)
	)
	(footprint ""
		(layer "F.Cu")
		(at 45.085 -323.85)
		(property "Reference" "C375"
			(at 0 0 0)
			(layer "F.SilkS")
			(hide yes)
			(effects
				(font
					(size 1.27 1.27)
				)
			)
		)
		(property "Value" "SCD033U25V2KX-GP"
			(at 1.1811 -2.7051 0)
			(unlocked yes)
			(layer "F.Fab")
			(hide yes)
			(effects
				(font
					(size 1.016 1.016)
					(thickness 0.1524)
				)
			)
		)
		(property "Device Type" "C402H22"
			(at 1.1811 -4.2291 0)
			(unlocked yes)
			(layer "F.Fab")
			(hide yes)
			(effects
				(font
					(size 1.016 1.016)
					(thickness 0.1524)
				)
			)
		)
		(duplicate_pad_numbers_are_jumpers no)
		(fp_rect
			(start -0.4318 0.9525)
			(end 0.4318 -0.9525)
			(stroke
				(width 0)
				(type default)
			)
			(fill no)
			(layer "F.CrtYd")
		)
		(fp_rect
			(start -0.4318 0.9525)
			(end 0.4318 -0.9525)
			(stroke
				(width 0)
				(type default)
			)
			(fill no)
			(layer "F.Fab")
		)
		(pad "1" smd custom
			(at 0 -0.4445)
			(size 0.1524 0.1524)
			(layers "F.Cu" "F.Mask" "F.Paste")
			(net "SW_HDD11_P")
			(options
				(clearance outline)
				(anchor circle)
			)
			(primitives
				(gr_poly
					(pts
						(arc
							(start 0.3048 -0.2032)
							(mid 0.275042 -0.275042)
							(end 0.2032 -0.3048)
						)
						(arc
							(start -0.2032 -0.3048)
							(mid -0.275042 -0.275042)
							(end -0.3048 -0.2032)
						)
						(arc
							(start -0.3048 0.2032)
							(mid -0.275042 0.275042)
							(end -0.2032 0.3048)
						)
						(arc
							(start 0.2032 0.3048)
							(mid 0.275042 0.275042)
							(end 0.3048 0.2032)
						)
					)
					(width 0)
					(fill yes)
				)
			)
		)
		(pad "2" smd custom
			(at 0 0.4445)
			(size 0.1524 0.1524)
			(layers "F.Cu" "F.Mask" "F.Paste")
			(net "GND")
			(options
				(clearance outline)
				(anchor circle)
			)
			(primitives
				(gr_poly
					(pts
						(arc
							(start 0.3048 -0.2032)
							(mid 0.275042 -0.275042)
							(end 0.2032 -0.3048)
						)
						(arc
							(start -0.2032 -0.3048)
							(mid -0.275042 -0.275042)
							(end -0.3048 -0.2032)
						)
						(arc
							(start -0.3048 0.2032)
							(mid -0.275042 0.275042)
							(end -0.2032 0.3048)
						)
						(arc
							(start 0.2032 0.3048)
							(mid 0.275042 0.275042)
							(end 0.3048 0.2032)
						)
					)
					(width 0)
					(fill yes)
				)
			)
		)
	)
	(footprint ""
		(layer "F.Cu")
		(at 240.537746 -29.8577 180)
		(property "Reference" "PG1"
			(at 0 0 180)
			(layer "F.SilkS")
			(hide yes)
			(effects
				(font
					(size 1.27 1.27)
				)
			)
		)
		(property "Value" "COPPER-CLOSE-GP-U"
			(at 0.0762 -2.8702 180)
			(unlocked yes)
			(layer "F.Fab")
			(hide yes)
			(effects
				(font
					(size 1.016 1.016)
					(thickness 0.1524)
				)
			)
		)
		(property "Device Type" "CON2C-U"
			(at 0.0762 -4.3942 180)
			(unlocked yes)
			(layer "F.Fab")
			(hide yes)
			(effects
				(font
					(size 1.016 1.016)
					(thickness 0.1524)
				)
			)
		)
		(duplicate_pad_numbers_are_jumpers no)
		(fp_rect
			(start -0.9398 0.9652)
			(end 0.9398 -0.9652)
			(stroke
				(width 0)
				(type default)
			)
			(fill no)
			(layer "F.CrtYd")
		)
		(fp_rect
			(start -0.9398 0.9652)
			(end 0.9398 -0.9652)
			(stroke
				(width 0)
				(type default)
			)
			(fill no)
			(layer "F.Fab")
		)
		(pad "1" smd custom
			(at 0 -0.5334 180)
			(size 0.17145 0.17145)
			(layers "F.Cu" "F.Mask" "F.Paste")
			(net "P5VA_AGND")
			(options
				(clearance outline)
				(anchor circle)
			)
			(primitives
				(gr_poly
					(pts
						(xy -0.127 0.3429) (xy -0.127 0.1651) (xy -0.635 -0.3429) (xy 0.635 -0.3429) (xy 0.127 0.1651)
						(xy 0.127 0.3429)
					)
					(width 0)
					(fill yes)
				)
			)
		)
		(pad "2" smd custom
			(at 0 0.5334 180)
			(size 0.17145 0.17145)
			(layers "F.Cu" "F.Mask" "F.Paste")
			(net "GND")
			(options
				(clearance outline)
				(anchor circle)
			)
			(primitives
				(gr_poly
					(pts
						(xy -0.635 0.3429) (xy -0.127 -0.1651) (xy -0.127 -0.3429) (xy 0.127 -0.3429) (xy 0.127 -0.1651)
						(xy 0.635 0.3429)
					)
					(width 0)
					(fill yes)
				)
			)
		)
	)
	(footprint ""
		(layer "F.Cu")
		(at 2.500122 -305.204622 -90)
		(property "Reference" "CN8"
			(at 0 0 270)
			(layer "F.SilkS")
			(hide yes)
			(effects
				(font
					(size 1.27 1.27)
				)
			)
		)
		(property "Value" "PCISLT36-27-GP"
			(at 5.281422 -7.491476 270)
			(unlocked yes)
			(layer "F.Fab")
			(hide yes)
			(effects
				(font
					(size 1.016 1.016)
					(thickness 0.1524)
				)
			)
		)
		(property "Device Type" "G630H3612248EU"
			(at 5.281422 -9.015476 270)
			(unlocked yes)
			(layer "F.Fab")
			(hide yes)
			(effects
				(font
					(size 1.016 1.016)
					(thickness 0.1524)
				)
			)
		)
		(duplicate_pad_numbers_are_jumpers no)
		(fp_line
			(start -14.899894 2.499868)
			(end -1.450086 2.499868)
			(stroke
				(width 0.1524)
				(type default)
			)
			(layer "F.SilkS")
		)
		(fp_line
			(start -1.450086 2.499868)
			(end -0.94996 1.999742)
			(stroke
				(width 0.1524)
				(type default)
			)
			(layer "F.SilkS")
		)
		(fp_line
			(start 1.450086 2.499868)
			(end 18.899886 2.499868)
			(stroke
				(width 0.1524)
				(type default)
			)
			(layer "F.SilkS")
		)
		(fp_line
			(start 18.899886 2.499868)
			(end 19.400012 1.999742)
			(stroke
				(width 0.1524)
				(type default)
			)
			(layer "F.SilkS")
		)
		(fp_line
			(start -15.40002 1.999742)
			(end -14.899894 2.499868)
			(stroke
				(width 0.1524)
				(type default)
			)
			(layer "F.SilkS")
		)
		(fp_line
			(start -0.94996 1.999742)
			(end -0.94996 -2.55016)
			(stroke
				(width 0.1524)
				(type default)
			)
			(layer "F.SilkS")
		)
		(fp_line
			(start 0.94996 1.999742)
			(end 1.450086 2.499868)
			(stroke
				(width 0.1524)
				(type default)
			)
			(layer "F.SilkS")
		)
		(fp_line
			(start 19.400012 1.999742)
			(end 19.400012 -4.064)
			(stroke
				(width 0.1524)
				(type default)
			)
			(layer "F.SilkS")
		)
		(fp_line
			(start 0.94996 -2.539746)
			(end 0.94996 1.999742)
			(stroke
				(width 0.1524)
				(type default)
			)
			(layer "F.SilkS")
		)
		(fp_line
			(start 0.94996 -2.55016)
			(end 0.94996 -2.539746)
			(stroke
				(width 0.1524)
				(type default)
			)
			(layer "F.SilkS")
		)
		(fp_line
			(start -15.40002 -4.064)
			(end -15.40002 1.999742)
			(stroke
				(width 0.1524)
				(type default)
			)
			(layer "F.SilkS")
		)
		(fp_line
			(start 19.400012 -4.064)
			(end -15.40002 -4.064)
			(stroke
				(width 0.1524)
				(type default)
			)
			(layer "F.SilkS")
		)
		(fp_line
			(start 11.6713 -4.1529)
			(end 11.2903 -4.1529)
			(stroke
				(width 0.3302)
				(type default)
			)
			(layer "F.SilkS")
		)
		(fp_arc
			(start -0.94996 -2.55016)
			(mid 0 -3.50012)
			(end 0.94996 -2.55016)
			(stroke
				(width 0.1524)
				(type default)
			)
			(layer "F.SilkS")
		)
		(fp_poly
			(pts
				(xy 11.474704 -4.1402) (xy 10.966704 -4.6482) (xy 11.982704 -4.6482)
			)
			(stroke
				(width 0)
				(type default)
			)
			(fill yes)
			(layer "F.SilkS")
		)
		(fp_poly
			(pts
				(xy -10.4902 14.986) (xy -10.4902 4.8006) (xy -15.3924 4.8006) (xy -15.3924 -3.81) (xy 19.4056 -3.81)
				(xy 19.4056 4.8006) (xy 14.5034 4.8006) (xy 14.5034 14.986)
			)
			(stroke
				(width 0)
				(type default)
			)
			(fill no)
			(layer "B.CrtYd")
		)
		(fp_poly
			(pts
				(xy -10.9982 15.494) (xy -10.9982 5.3086) (xy -15.9004 5.3086) (xy -15.9004 -4.318) (xy 19.9136 -4.318)
				(xy 19.9136 5.3086) (xy 15.0114 5.3086) (xy 15.0114 15.494) (xy 0.00254 15.494) (xy 0.00254 14.986)
				(xy 14.5034 14.986) (xy 14.5034 4.8006) (xy 19.4056 4.8006) (xy 19.4056 -3.81) (xy -15.3924 -3.81)
				(xy -15.3924 4.8006) (xy -10.4902 4.8006) (xy -10.4902 14.986) (xy -0.00254 14.986) (xy -0.00254 15.494)
			)
			(stroke
				(width 0)
				(type default)
			)
			(fill no)
			(layer "B.CrtYd")
		)
		(fp_poly
			(pts
				(xy -10.4902 14.986) (xy -10.4902 4.8006) (xy -15.3924 4.8006) (xy -15.3924 -3.81) (xy 19.4056 -3.81)
				(xy 19.4056 4.8006) (xy 14.5034 4.8006) (xy 14.5034 14.986)
			)
			(stroke
				(width 0)
				(type default)
			)
			(fill no)
			(layer "F.CrtYd")
		)
		(fp_poly
			(pts
				(xy -10.9982 15.494) (xy -10.9982 5.3086) (xy -15.9004 5.3086) (xy -15.9004 -4.318) (xy 19.9136 -4.318)
				(xy 19.9136 5.3086) (xy 15.0114 5.3086) (xy 15.0114 15.494) (xy 0.00254 15.494) (xy 0.00254 14.986)
				(xy 14.5034 14.986) (xy 14.5034 4.8006) (xy 19.4056 4.8006) (xy 19.4056 -3.81) (xy -15.3924 -3.81)
				(xy -15.3924 4.8006) (xy -10.4902 4.8006) (xy -10.4902 14.986) (xy -0.00254 14.986) (xy -0.00254 15.494)
			)
			(stroke
				(width 0)
				(type default)
			)
			(fill no)
			(layer "F.CrtYd")
		)
		(fp_poly
			(pts
				(xy -10.9982 15.494) (xy -10.9982 5.3086) (xy -15.9004 5.3086) (xy -15.9004 -4.318) (xy 19.9136 -4.318)
				(xy 19.9136 5.3086) (xy 15.0114 5.3086) (xy 15.0114 15.494)
			)
			(stroke
				(width 0)
				(type default)
			)
			(fill no)
			(layer "B.Fab")
		)
		(fp_poly
			(pts
				(xy -10.9982 15.494) (xy -10.9982 5.3086) (xy -15.9004 5.3086) (xy -15.9004 -4.318) (xy 19.9136 -4.318)
				(xy 19.9136 5.3086) (xy 15.0114 5.3086) (xy 15.0114 15.494)
			)
			(stroke
				(width 0)
				(type default)
			)
			(fill no)
			(layer "F.Fab")
		)
		(fp_text user "Slit"
			(at 1.9304 5.088636 270)
			(unlocked yes)
			(layer "F.SilkS")
			(effects
				(font
					(size 1.016 1.016)
					(thickness 0.1524)
				)
				(justify left)
			)
		)
		(pad "" np_thru_hole circle
			(at -12.300204 0 270)
			(size 0.254 0.254)
			(drill 2.3114)
			(layers "*.Cu" "*.Mask")
			(clearance 1.3843)
			(thermal_gap 1.3843)
		)
		(pad "" np_thru_hole circle
			(at 16.299942 0 270)
			(size 0.254 0.254)
			(drill 2.3114)
			(layers "*.Cu" "*.Mask")
			(clearance 1.3843)
			(thermal_gap 1.3843)
		)
		(pad "A1" smd rect
			(at 11.500104 -0.309118 270)
			(size 0.7112 3.6068)
			(drill
				(offset 0 -0.381)
			)
			(layers "F.Cu" "F.Mask" "F.Paste")
			(net "PRSNT_A")
		)
		(pad "A2" smd rect
			(at 10.500106 -0.309118 270)
			(size 0.7112 3.6068)
			(drill
				(offset 0 -0.381)
			)
			(layers "F.Cu" "F.Mask" "F.Paste")
			(net "P12V")
		)
		(pad "A3" smd rect
			(at 9.500108 -0.309118 270)
			(size 0.7112 3.6068)
			(drill
				(offset 0 -0.381)
			)
			(layers "F.Cu" "F.Mask" "F.Paste")
			(net "P12V")
		)
		(pad "A4" smd rect
			(at 8.50011 -0.309118 270)
			(size 0.7112 3.6068)
			(drill
				(offset 0 -0.381)
			)
			(layers "F.Cu" "F.Mask" "F.Paste")
			(net "P12V")
		)
		(pad "A5" smd rect
			(at 7.500112 -0.309118 270)
			(size 0.7112 3.6068)
			(drill
				(offset 0 -0.381)
			)
			(layers "F.Cu" "F.Mask" "F.Paste")
			(net "P12V")
		)
		(pad "A6" smd rect
			(at 6.500114 -0.309118 270)
			(size 0.7112 3.6068)
			(drill
				(offset 0 -0.381)
			)
			(layers "F.Cu" "F.Mask" "F.Paste")
			(net "P12V")
		)
		(pad "A7" smd rect
			(at 5.500116 -0.309118 270)
			(size 0.7112 3.6068)
			(drill
				(offset 0 -0.381)
			)
			(layers "F.Cu" "F.Mask" "F.Paste")
			(net "P12V")
		)
		(pad "A8" smd rect
			(at 4.500118 -0.309118 270)
			(size 0.7112 3.6068)
			(drill
				(offset 0 -0.381)
			)
			(layers "F.Cu" "F.Mask" "F.Paste")
			(net "P12V")
		)
		(pad "A9" smd rect
			(at 3.50012 -0.309118 270)
			(size 0.7112 3.6068)
			(drill
				(offset 0 -0.381)
			)
			(layers "F.Cu" "F.Mask" "F.Paste")
			(net "Net_104")
		)
		(pad "A10" smd rect
			(at 2.500122 -0.309118 270)
			(size 0.7112 3.6068)
			(drill
				(offset 0 -0.381)
			)
			(layers "F.Cu" "F.Mask" "F.Paste")
			(net "Net_103")
		)
		(pad "A11" smd rect
			(at 1.500124 -0.309118 270)
			(size 0.7112 3.6068)
			(drill
				(offset 0 -0.381)
			)
			(layers "F.Cu" "F.Mask" "F.Paste")
			(net "Net_102")
		)
		(pad "A12" smd rect
			(at -1.500124 -0.309118 270)
			(size 0.7112 3.6068)
			(drill
				(offset 0 -0.381)
			)
			(layers "F.Cu" "F.Mask" "F.Paste")
			(net "Net_111")
		)
		(pad "A13" smd rect
			(at -2.500122 -0.309118 270)
			(size 0.7112 3.6068)
			(drill
				(offset 0 -0.381)
			)
			(layers "F.Cu" "F.Mask" "F.Paste")
			(net "GND")
		)
		(pad "A14" smd rect
			(at -3.50012 -0.309118 270)
			(size 0.7112 3.6068)
			(drill
				(offset 0 -0.381)
			)
			(layers "F.Cu" "F.Mask" "F.Paste")
			(net "Net_110")
		)
		(pad "A15" smd rect
			(at -4.500118 -0.309118 270)
			(size 0.7112 3.6068)
			(drill
				(offset 0 -0.381)
			)
			(layers "F.Cu" "F.Mask" "F.Paste")
			(net "Net_109")
		)
		(pad "A16" smd rect
			(at -5.500116 -0.309118 270)
			(size 0.7112 3.6068)
			(drill
				(offset 0 -0.381)
			)
			(layers "F.Cu" "F.Mask" "F.Paste")
			(net "GND")
		)
		(pad "A17" smd rect
			(at -6.500114 -0.309118 270)
			(size 0.7112 3.6068)
			(drill
				(offset 0 -0.381)
			)
			(layers "F.Cu" "F.Mask" "F.Paste")
			(net "Net_114")
		)
		(pad "A18" smd rect
			(at -7.500112 -0.309118 270)
			(size 0.7112 3.6068)
			(drill
				(offset 0 -0.381)
			)
			(layers "F.Cu" "F.Mask" "F.Paste")
			(net "GND")
		)
		(pad "B1" smd rect
			(at 11.500104 -0.690118 270)
			(size 0.7112 3.6068)
			(layers "F.Cu" "F.Mask" "F.Paste")
			(net "GND")
		)
		(pad "B2" smd rect
			(at 10.500106 -0.690118 270)
			(size 0.7112 3.6068)
			(layers "F.Cu" "F.Mask" "F.Paste")
			(net "GND")
		)
		(pad "B3" smd rect
			(at 9.500108 -0.690118 270)
			(size 0.7112 3.6068)
			(layers "F.Cu" "F.Mask" "F.Paste")
			(net "GND")
		)
		(pad "B4" smd rect
			(at 8.50011 -0.690118 270)
			(size 0.7112 3.6068)
			(layers "F.Cu" "F.Mask" "F.Paste")
			(net "GND")
		)
		(pad "B5" smd rect
			(at 7.500112 -0.690118 270)
			(size 0.7112 3.6068)
			(layers "F.Cu" "F.Mask" "F.Paste")
			(net "GND")
		)
		(pad "B6" smd rect
			(at 6.500114 -0.690118 270)
			(size 0.7112 3.6068)
			(layers "F.Cu" "F.Mask" "F.Paste")
			(net "GND")
		)
		(pad "B7" smd rect
			(at 5.500116 -0.690118 270)
			(size 0.7112 3.6068)
			(layers "F.Cu" "F.Mask" "F.Paste")
			(net "GND")
		)
		(pad "B8" smd rect
			(at 4.500118 -0.690118 270)
			(size 0.7112 3.6068)
			(layers "F.Cu" "F.Mask" "F.Paste")
			(net "Net_108")
		)
		(pad "B9" smd rect
			(at 3.50012 -0.690118 270)
			(size 0.7112 3.6068)
			(layers "F.Cu" "F.Mask" "F.Paste")
			(net "Net_107")
		)
		(pad "B10" smd rect
			(at 2.500122 -0.690118 270)
			(size 0.7112 3.6068)
			(layers "F.Cu" "F.Mask" "F.Paste")
			(net "Net_106")
		)
		(pad "B11" smd rect
			(at 1.500124 -0.690118 270)
			(size 0.7112 3.6068)
			(layers "F.Cu" "F.Mask" "F.Paste")
			(net "Net_105")
		)
		(pad "B12" smd rect
			(at -1.500124 -0.690118 270)
			(size 0.7112 3.6068)
			(layers "F.Cu" "F.Mask" "F.Paste")
			(net "GND")
		)
		(pad "B13" smd rect
			(at -2.500122 -0.690118 270)
			(size 0.7112 3.6068)
			(layers "F.Cu" "F.Mask" "F.Paste")
			(net "Net_113")
		)
		(pad "B14" smd rect
			(at -3.50012 -0.690118 270)
			(size 0.7112 3.6068)
			(layers "F.Cu" "F.Mask" "F.Paste")
			(net "Net_112")
		)
		(pad "B15" smd rect
			(at -4.500118 -0.690118 270)
			(size 0.7112 3.6068)
			(layers "F.Cu" "F.Mask" "F.Paste")
			(net "GND")
		)
		(pad "B16" smd rect
			(at -5.500116 -0.690118 270)
			(size 0.7112 3.6068)
			(layers "F.Cu" "F.Mask" "F.Paste")
			(net "Net_116")
		)
		(pad "B17" smd rect
			(at -6.500114 -0.690118 270)
			(size 0.7112 3.6068)
			(layers "F.Cu" "F.Mask" "F.Paste")
			(net "Net_115")
		)
		(pad "B18" smd rect
			(at -7.500112 -0.690118 270)
			(size 0.7112 3.6068)
			(layers "F.Cu" "F.Mask" "F.Paste")
			(net "GND")
		)
		(zone
			(layers "F.Cu" "B.Cu" "In1.Cu" "In2.Cu" "In3.Cu" "In4.Cu" "In5.Cu" "In6.Cu")
			(hatch none 0.5)
			(connect_pads
				(clearance 0)
			)
			(min_thickness 0.25)
			(keepout
				(tracks not_allowed)
				(vias allowed)
				(pads allowed)
				(copperpour not_allowed)
				(footprints allowed)
			)
			(placement
				(enabled no)
				(sheetname "")
			)
			(fill
				(thermal_gap 0.5)
				(thermal_bridge_width 0.5)
				(island_removal_mode 0)
			)
			(polygon
				(pts
					(arc
						(start 3.960622 -317.504826)
						(mid 1.039622 -317.504826)
						(end 3.960622 -317.504826)
					)
				)
			)
		)
		(zone
			(layers "F.Cu" "B.Cu" "In1.Cu" "In2.Cu" "In3.Cu" "In4.Cu" "In5.Cu" "In6.Cu")
			(hatch none 0.5)
			(connect_pads
				(clearance 0)
			)
			(min_thickness 0.25)
			(keepout
				(tracks not_allowed)
				(vias allowed)
				(pads allowed)
				(copperpour not_allowed)
				(footprints allowed)
			)
			(placement
				(enabled no)
				(sheetname "")
			)
			(fill
				(thermal_gap 0.5)
				(thermal_bridge_width 0.5)
				(island_removal_mode 0)
			)
			(polygon
				(pts
					(arc
						(start 3.960622 -288.90468)
						(mid 1.039622 -288.90468)
						(end 3.960622 -288.90468)
					)
				)
			)
		)
	)
	(footprint ""
		(layer "F.Cu")
		(at 235.838746 -27.9527)
		(property "Reference" "PC13"
			(at 0 0 0)
			(layer "F.SilkS")
			(hide yes)
			(effects
				(font
					(size 1.27 1.27)
				)
			)
		)
		(property "Value" "SC680P50V2KX-2GP"
			(at 1.1811 -2.7051 0)
			(unlocked yes)
			(layer "F.Fab")
			(hide yes)
			(effects
				(font
					(size 1.016 1.016)
					(thickness 0.1524)
				)
			)
		)
		(property "Device Type" "C402H22"
			(at 1.1811 -4.2291 0)
			(unlocked yes)
			(layer "F.Fab")
			(hide yes)
			(effects
				(font
					(size 1.016 1.016)
					(thickness 0.1524)
				)
			)
		)
		(duplicate_pad_numbers_are_jumpers no)
		(fp_rect
			(start -0.4318 0.9525)
			(end 0.4318 -0.9525)
			(stroke
				(width 0)
				(type default)
			)
			(fill no)
			(layer "F.CrtYd")
		)
		(fp_rect
			(start -0.4318 0.9525)
			(end 0.4318 -0.9525)
			(stroke
				(width 0)
				(type default)
			)
			(fill no)
			(layer "F.Fab")
		)
		(pad "1" smd custom
			(at 0 -0.4445)
			(size 0.1524 0.1524)
			(layers "F.Cu" "F.Mask" "F.Paste")
			(net "P5VA_LL_NET")
			(options
				(clearance outline)
				(anchor circle)
			)
			(primitives
				(gr_poly
					(pts
						(arc
							(start 0.3048 -0.2032)
							(mid 0.275042 -0.275042)
							(end 0.2032 -0.3048)
						)
						(arc
							(start -0.2032 -0.3048)
							(mid -0.275042 -0.275042)
							(end -0.3048 -0.2032)
						)
						(arc
							(start -0.3048 0.2032)
							(mid -0.275042 0.275042)
							(end -0.2032 0.3048)
						)
						(arc
							(start 0.2032 0.3048)
							(mid 0.275042 0.275042)
							(end 0.3048 0.2032)
						)
					)
					(width 0)
					(fill yes)
				)
			)
		)
		(pad "2" smd custom
			(at 0 0.4445)
			(size 0.1524 0.1524)
			(layers "F.Cu" "F.Mask" "F.Paste")
			(net "P5VA_VFB")
			(options
				(clearance outline)
				(anchor circle)
			)
			(primitives
				(gr_poly
					(pts
						(arc
							(start 0.3048 -0.2032)
							(mid 0.275042 -0.275042)
							(end 0.2032 -0.3048)
						)
						(arc
							(start -0.2032 -0.3048)
							(mid -0.275042 -0.275042)
							(end -0.3048 -0.2032)
						)
						(arc
							(start -0.3048 0.2032)
							(mid -0.275042 0.275042)
							(end -0.2032 0.3048)
						)
						(arc
							(start 0.2032 0.3048)
							(mid 0.275042 0.275042)
							(end 0.3048 0.2032)
						)
					)
					(width 0)
					(fill yes)
				)
			)
		)
	)
	(footprint ""
		(layer "F.Cu")
		(at 223.4946 -442.1378 -90)
		(property "Reference" "PR63"
			(at 0 0 270)
			(layer "F.SilkS")
			(hide yes)
			(effects
				(font
					(size 1.27 1.27)
				)
			)
		)
		(property "Value" "0R0603-PAD-2-GP-U"
			(at 2.1209 -0.1397 270)
			(unlocked yes)
			(layer "F.Fab")
			(hide yes)
			(effects
				(font
					(size 1.016 1.016)
					(thickness 0.1524)
				)
			)
		)
		(property "Device Type" "0R0603-PAD-1-U"
			(at 2.1209 -1.6637 270)
			(unlocked yes)
			(layer "F.Fab")
			(hide yes)
			(effects
				(font
					(size 1.016 1.016)
					(thickness 0.1524)
				)
			)
		)
		(duplicate_pad_numbers_are_jumpers no)
		(fp_rect
			(start -0.5842 1.3335)
			(end 0.5842 -1.3335)
			(stroke
				(width 0)
				(type default)
			)
			(fill no)
			(layer "F.CrtYd")
		)
		(fp_rect
			(start -0.5842 1.3335)
			(end 0.5842 -1.3335)
			(stroke
				(width 0)
				(type default)
			)
			(fill no)
			(layer "F.Fab")
		)
		(pad "1" smd custom
			(at 0 -0.762 270)
			(size 0.2159 0.2159)
			(layers "F.Cu" "F.Mask" "F.Paste")
			(net "P12V")
			(options
				(clearance outline)
				(anchor circle)
			)
			(primitives
				(gr_poly
					(pts
						(arc
							(start -0.3302 -0.5842)
							(mid -0.402042 -0.554442)
							(end -0.4318 -0.4826)
						)
						(arc
							(start -0.4318 0.4826)
							(mid -0.402042 0.554442)
							(end -0.3302 0.5842)
						)
						(arc
							(start 0.3302 0.5842)
							(mid 0.402042 0.554442)
							(end 0.4318 0.4826)
						)
						(arc
							(start 0.4318 -0.4826)
							(mid 0.402042 -0.554442)
							(end 0.3302 -0.5842)
						)
					)
					(width 0)
					(fill yes)
				)
			)
		)
		(pad "2" smd custom
			(at 0 0.762 270)
			(size 0.2159 0.2159)
			(layers "F.Cu" "F.Mask" "F.Paste")
			(net "P3V3_IN")
			(options
				(clearance outline)
				(anchor circle)
			)
			(primitives
				(gr_poly
					(pts
						(arc
							(start -0.4318 0.4826)
							(mid -0.402042 0.554442)
							(end -0.3302 0.5842)
						)
						(arc
							(start 0.3302 0.5842)
							(mid 0.402042 0.554442)
							(end 0.4318 0.4826)
						)
						(arc
							(start 0.4318 -0.4826)
							(mid 0.402042 -0.554442)
							(end 0.3302 -0.5842)
						)
						(arc
							(start -0.3302 -0.5842)
							(mid -0.402042 -0.554442)
							(end -0.4318 -0.4826)
						)
					)
					(width 0)
					(fill yes)
				)
			)
		)
	)
	(footprint ""
		(layer "F.Cu")
		(at 34.543746 -433.0827 180)
		(property "Reference" "R462"
			(at 0 0 180)
			(layer "F.SilkS")
			(hide yes)
			(effects
				(font
					(size 1.27 1.27)
				)
			)
		)
		(property "Value" "4K7R2J-2-GP"
			(at 0.064008 -3.993896 180)
			(unlocked yes)
			(layer "F.Fab")
			(hide yes)
			(effects
				(font
					(size 1.016 1.016)
					(thickness 0.1524)
				)
			)
		)
		(property "Device Type" "R402H16"
			(at 0.064008 -5.517896 180)
			(unlocked yes)
			(layer "F.Fab")
			(hide yes)
			(effects
				(font
					(size 1.016 1.016)
					(thickness 0.1524)
				)
			)
		)
		(duplicate_pad_numbers_are_jumpers no)
		(fp_line
			(start 0.508 -0.9398)
			(end -0.508 -0.9398)
			(stroke
				(width 0.1524)
				(type default)
			)
			(layer "F.SilkS")
		)
		(fp_line
			(start -0.508 -0.9398)
			(end -0.508 0.9398)
			(stroke
				(width 0.1524)
				(type default)
			)
			(layer "F.SilkS")
		)
		(fp_rect
			(start -0.508 0.9398)
			(end 0.508 -0.9398)
			(stroke
				(width 0)
				(type default)
			)
			(fill no)
			(layer "F.CrtYd")
		)
		(fp_rect
			(start -0.508 0.9398)
			(end 0.508 -0.9398)
			(stroke
				(width 0)
				(type default)
			)
			(fill no)
			(layer "F.Fab")
		)
		(pad "1" smd custom
			(at 0 -0.4445 180)
			(size 0.1397 0.1397)
			(layers "F.Cu" "F.Mask" "F.Paste")
			(net "P3V3")
			(options
				(clearance outline)
				(anchor circle)
			)
			(primitives
				(gr_poly
					(pts
						(arc
							(start -0.1778 -0.2794)
							(mid -0.249642 -0.249642)
							(end -0.2794 -0.1778)
						)
						(arc
							(start -0.2794 0.1778)
							(mid -0.249642 0.249642)
							(end -0.1778 0.2794)
						)
						(arc
							(start 0.1778 0.2794)
							(mid 0.249642 0.249642)
							(end 0.2794 0.1778)
						)
						(arc
							(start 0.2794 -0.1778)
							(mid 0.249642 -0.249642)
							(end 0.1778 -0.2794)
						)
					)
					(width 0)
					(fill yes)
				)
			)
		)
		(pad "2" smd custom
			(at 0 0.4445 180)
			(size 0.1397 0.1397)
			(layers "F.Cu" "F.Mask" "F.Paste")
			(net "SAS_EXP_A_PWR10")
			(options
				(clearance outline)
				(anchor circle)
			)
			(primitives
				(gr_poly
					(pts
						(arc
							(start -0.1778 -0.2794)
							(mid -0.249642 -0.249642)
							(end -0.2794 -0.1778)
						)
						(arc
							(start -0.2794 0.1778)
							(mid -0.249642 0.249642)
							(end -0.1778 0.2794)
						)
						(arc
							(start 0.1778 0.2794)
							(mid 0.249642 0.249642)
							(end 0.2794 0.1778)
						)
						(arc
							(start 0.2794 -0.1778)
							(mid 0.249642 -0.249642)
							(end 0.1778 -0.2794)
						)
					)
					(width 0)
					(fill yes)
				)
			)
		)
	)
	(footprint ""
		(layer "F.Cu")
		(at 195.58 -188.087 180)
		(property "Reference" "R411"
			(at 0 0 180)
			(layer "F.SilkS")
			(hide yes)
			(effects
				(font
					(size 1.27 1.27)
				)
			)
		)
		(property "Value" "0R2J-2-GP"
			(at 0.064008 -3.993896 180)
			(unlocked yes)
			(layer "F.Fab")
			(hide yes)
			(effects
				(font
					(size 1.016 1.016)
					(thickness 0.1524)
				)
			)
		)
		(property "Device Type" "R402H16"
			(at 0.064008 -5.517896 180)
			(unlocked yes)
			(layer "F.Fab")
			(hide yes)
			(effects
				(font
					(size 1.016 1.016)
					(thickness 0.1524)
				)
			)
		)
		(duplicate_pad_numbers_are_jumpers no)
		(fp_line
			(start 0.508 -0.9398)
			(end -0.508 -0.9398)
			(stroke
				(width 0.1524)
				(type default)
			)
			(layer "F.SilkS")
		)
		(fp_line
			(start -0.508 -0.9398)
			(end -0.508 0.9398)
			(stroke
				(width 0.1524)
				(type default)
			)
			(layer "F.SilkS")
		)
		(fp_rect
			(start -0.508 0.9398)
			(end 0.508 -0.9398)
			(stroke
				(width 0)
				(type default)
			)
			(fill no)
			(layer "F.CrtYd")
		)
		(fp_rect
			(start -0.508 0.9398)
			(end 0.508 -0.9398)
			(stroke
				(width 0)
				(type default)
			)
			(fill no)
			(layer "F.Fab")
		)
		(pad "1" smd custom
			(at 0 -0.4445 180)
			(size 0.1397 0.1397)
			(layers "F.Cu" "F.Mask" "F.Paste")
			(net "SW_HDD3_G")
			(options
				(clearance outline)
				(anchor circle)
			)
			(primitives
				(gr_poly
					(pts
						(arc
							(start -0.1778 -0.2794)
							(mid -0.249642 -0.249642)
							(end -0.2794 -0.1778)
						)
						(arc
							(start -0.2794 0.1778)
							(mid -0.249642 0.249642)
							(end -0.1778 0.2794)
						)
						(arc
							(start 0.1778 0.2794)
							(mid 0.249642 0.249642)
							(end 0.2794 0.1778)
						)
						(arc
							(start 0.2794 -0.1778)
							(mid 0.249642 -0.249642)
							(end 0.1778 -0.2794)
						)
					)
					(width 0)
					(fill yes)
				)
			)
		)
		(pad "2" smd custom
			(at 0 0.4445 180)
			(size 0.1397 0.1397)
			(layers "F.Cu" "F.Mask" "F.Paste")
			(net "SW_HDD3_R")
			(options
				(clearance outline)
				(anchor circle)
			)
			(primitives
				(gr_poly
					(pts
						(arc
							(start -0.1778 -0.2794)
							(mid -0.249642 -0.249642)
							(end -0.2794 -0.1778)
						)
						(arc
							(start -0.2794 0.1778)
							(mid -0.249642 0.249642)
							(end -0.1778 0.2794)
						)
						(arc
							(start 0.1778 0.2794)
							(mid 0.249642 0.249642)
							(end 0.2794 0.1778)
						)
						(arc
							(start 0.2794 -0.1778)
							(mid 0.249642 -0.249642)
							(end 0.1778 -0.2794)
						)
					)
					(width 0)
					(fill yes)
				)
			)
		)
	)
	(footprint ""
		(layer "F.Cu")
		(at 5.969 -32.004 -90)
		(property "Reference" "PC69"
			(at 0 0 270)
			(layer "F.SilkS")
			(hide yes)
			(effects
				(font
					(size 1.27 1.27)
				)
			)
		)
		(property "Value" "SC22U25V5MX-GP"
			(at -0.0762 -6.1214 270)
			(unlocked yes)
			(layer "F.Fab")
			(hide yes)
			(effects
				(font
					(size 1.016 1.016)
					(thickness 0.1524)
				)
			)
		)
		(property "Device Type" "C805H58"
			(at -0.0762 -8.1534 270)
			(unlocked yes)
			(layer "F.Fab")
			(hide yes)
			(effects
				(font
					(size 1.016 1.016)
					(thickness 0.1524)
				)
			)
		)
		(duplicate_pad_numbers_are_jumpers no)
		(fp_line
			(start 0.635 0)
			(end -0.635 0)
			(stroke
				(width 0.508)
				(type default)
			)
			(layer "F.SilkS")
		)
		(fp_rect
			(start -0.9652 1.778)
			(end 0.9652 -1.778)
			(stroke
				(width 0)
				(type default)
			)
			(fill no)
			(layer "F.CrtYd")
		)
		(fp_poly
			(pts
				(xy -0.9652 -1.778) (xy 0.9652 -1.778) (xy 0.9652 1.778) (xy -0.9652 1.778)
			)
			(stroke
				(width 0)
				(type default)
			)
			(fill no)
			(layer "F.Fab")
		)
		(pad "1" smd rect
			(at 0 -0.9652 270)
			(size 1.397 1.143)
			(layers "F.Cu" "F.Mask" "F.Paste")
			(net "P12V")
		)
		(pad "2" smd rect
			(at 0 0.9652 270)
			(size 1.397 1.143)
			(layers "F.Cu" "F.Mask" "F.Paste")
			(net "GND")
		)
	)
	(footprint ""
		(layer "F.Cu")
		(at 227.2792 -433.578)
		(property "Reference" "PC42"
			(at 0 0 0)
			(layer "F.SilkS")
			(hide yes)
			(effects
				(font
					(size 1.27 1.27)
				)
			)
		)
		(property "Value" "SC22P50V3JN-GP"
			(at 0 -2.8194 0)
			(unlocked yes)
			(layer "F.Fab")
			(hide yes)
			(effects
				(font
					(size 1.016 1.016)
					(thickness 0.1524)
				)
			)
		)
		(property "Device Type" "C603H36"
			(at 0 -4.3434 0)
			(unlocked yes)
			(layer "F.Fab")
			(hide yes)
			(effects
				(font
					(size 1.016 1.016)
					(thickness 0.1524)
				)
			)
		)
		(duplicate_pad_numbers_are_jumpers no)
		(fp_line
			(start 0.508 0)
			(end -0.508 0)
			(stroke
				(width 0.2032)
				(type default)
			)
			(layer "F.SilkS")
		)
		(fp_rect
			(start -0.5842 1.3335)
			(end 0.5842 -1.3335)
			(stroke
				(width 0)
				(type default)
			)
			(fill no)
			(layer "F.CrtYd")
		)
		(fp_rect
			(start -0.5842 1.3335)
			(end 0.5842 -1.3335)
			(stroke
				(width 0)
				(type default)
			)
			(fill no)
			(layer "F.Fab")
		)
		(pad "1" smd custom
			(at 0 -0.762)
			(size 0.2159 0.2159)
			(layers "F.Cu" "F.Mask" "F.Paste")
			(net "P3V3_LX_COOPER")
			(options
				(clearance outline)
				(anchor circle)
			)
			(primitives
				(gr_poly
					(pts
						(arc
							(start -0.3302 -0.4318)
							(mid -0.402042 -0.402042)
							(end -0.4318 -0.3302)
						)
						(arc
							(start -0.4318 0.3302)
							(mid -0.402042 0.402042)
							(end -0.3302 0.4318)
						)
						(arc
							(start 0.3302 0.4318)
							(mid 0.402042 0.402042)
							(end 0.4318 0.3302)
						)
						(arc
							(start 0.4318 -0.3302)
							(mid 0.402042 -0.402042)
							(end 0.3302 -0.4318)
						)
					)
					(width 0)
					(fill yes)
				)
			)
		)
		(pad "2" smd custom
			(at 0 0.762)
			(size 0.2159 0.2159)
			(layers "F.Cu" "F.Mask" "F.Paste")
			(net "P3V3_FB")
			(options
				(clearance outline)
				(anchor circle)
			)
			(primitives
				(gr_poly
					(pts
						(arc
							(start -0.3302 -0.4318)
							(mid -0.402042 -0.402042)
							(end -0.4318 -0.3302)
						)
						(arc
							(start -0.4318 0.3302)
							(mid -0.402042 0.402042)
							(end -0.3302 0.4318)
						)
						(arc
							(start 0.3302 0.4318)
							(mid 0.402042 0.402042)
							(end 0.4318 0.3302)
						)
						(arc
							(start 0.4318 -0.3302)
							(mid 0.402042 -0.402042)
							(end 0.3302 -0.4318)
						)
					)
					(width 0)
					(fill yes)
				)
			)
		)
	)
	(footprint ""
		(layer "F.Cu")
		(at 33.908746 -343.2937 90)
		(property "Reference" "Q45"
			(at 0 0 90)
			(layer "F.SilkS")
			(hide yes)
			(effects
				(font
					(size 1.27 1.27)
				)
			)
		)
		(property "Value" "PMBS3904-1-GP"
			(at 0 -9.0932 90)
			(unlocked yes)
			(layer "F.Fab")
			(hide yes)
			(effects
				(font
					(size 1.016 1.016)
					(thickness 0.1524)
				)
			)
		)
		(property "Device Type" "SOT-23-10H44"
			(at 0 -10.6172 90)
			(unlocked yes)
			(layer "F.Fab")
			(hide yes)
			(effects
				(font
					(size 1.016 1.016)
					(thickness 0.1524)
				)
			)
		)
		(duplicate_pad_numbers_are_jumpers no)
		(fp_line
			(start 1.651 -1.778)
			(end -1.651 -1.778)
			(stroke
				(width 0.1524)
				(type default)
			)
			(layer "F.SilkS")
		)
		(fp_line
			(start -1.651 -1.778)
			(end -1.651 1.778)
			(stroke
				(width 0.1524)
				(type default)
			)
			(layer "F.SilkS")
		)
		(fp_line
			(start 1.651 1.778)
			(end 1.651 -1.778)
			(stroke
				(width 0.1524)
				(type default)
			)
			(layer "F.SilkS")
		)
		(fp_line
			(start -1.651 1.778)
			(end 1.651 1.778)
			(stroke
				(width 0.1524)
				(type default)
			)
			(layer "F.SilkS")
		)
		(fp_line
			(start -0.9906 1.86309)
			(end -0.701294 2.15265)
			(stroke
				(width 0.0127)
				(type default)
			)
			(layer "F.SilkS")
		)
		(fp_line
			(start -0.994156 1.8669)
			(end -0.987044 1.8669)
			(stroke
				(width 0.0127)
				(type default)
			)
			(layer "F.SilkS")
		)
		(fp_line
			(start -1.003808 1.876552)
			(end -0.977646 1.876552)
			(stroke
				(width 0.0127)
				(type default)
			)
			(layer "F.SilkS")
		)
		(fp_line
			(start -0.635 1.8796)
			(end -1.7526 1.8796)
			(stroke
				(width 0.3302)
				(type default)
			)
			(layer "F.SilkS")
		)
		(fp_line
			(start -1.7526 1.8796)
			(end -1.7526 0.9906)
			(stroke
				(width 0.3302)
				(type default)
			)
			(layer "F.SilkS")
		)
		(fp_line
			(start -1.013206 1.88595)
			(end -0.967994 1.88595)
			(stroke
				(width 0.0127)
				(type default)
			)
			(layer "F.SilkS")
		)
		(fp_line
			(start -1.022858 1.895602)
			(end -0.958596 1.895602)
			(stroke
				(width 0.0127)
				(type default)
			)
			(layer "F.SilkS")
		)
		(fp_line
			(start -1.032256 1.905)
			(end -0.948944 1.905)
			(stroke
				(width 0.0127)
				(type default)
			)
			(layer "F.SilkS")
		)
		(fp_line
			(start -1.041908 1.914652)
			(end -0.939546 1.914652)
			(stroke
				(width 0.0127)
				(type default)
			)
			(layer "F.SilkS")
		)
		(fp_line
			(start -1.051306 1.92405)
			(end -0.929894 1.92405)
			(stroke
				(width 0.0127)
				(type default)
			)
			(layer "F.SilkS")
		)
		(fp_line
			(start -1.060958 1.933702)
			(end -0.920496 1.933702)
			(stroke
				(width 0.0127)
				(type default)
			)
			(layer "F.SilkS")
		)
		(fp_line
			(start -1.070356 1.9431)
			(end -0.910844 1.9431)
			(stroke
				(width 0.0127)
				(type default)
			)
			(layer "F.SilkS")
		)
		(fp_line
			(start -1.080008 1.952752)
			(end -0.901446 1.952752)
			(stroke
				(width 0.0127)
				(type default)
			)
			(layer "F.SilkS")
		)
		(fp_line
			(start -1.089406 1.96215)
			(end -0.891794 1.96215)
			(stroke
				(width 0.0127)
				(type default)
			)
			(layer "F.SilkS")
		)
		(fp_line
			(start -1.099058 1.971802)
			(end -0.882396 1.971802)
			(stroke
				(width 0.0127)
				(type default)
			)
			(layer "F.SilkS")
		)
		(fp_line
			(start -1.108456 1.9812)
			(end -0.872744 1.9812)
			(stroke
				(width 0.0127)
				(type default)
			)
			(layer "F.SilkS")
		)
		(fp_line
			(start -1.118108 1.990852)
			(end -0.863346 1.990852)
			(stroke
				(width 0.0127)
				(type default)
			)
			(layer "F.SilkS")
		)
		(fp_line
			(start -1.127506 2.00025)
			(end -0.853694 2.00025)
			(stroke
				(width 0.0127)
				(type default)
			)
			(layer "F.SilkS")
		)
		(fp_line
			(start -1.137158 2.009902)
			(end -0.844296 2.009902)
			(stroke
				(width 0.0127)
				(type default)
			)
			(layer "F.SilkS")
		)
		(fp_line
			(start -1.146556 2.0193)
			(end -0.834644 2.0193)
			(stroke
				(width 0.0127)
				(type default)
			)
			(layer "F.SilkS")
		)
		(fp_line
			(start -1.156208 2.028952)
			(end -0.825246 2.028952)
			(stroke
				(width 0.0127)
				(type default)
			)
			(layer "F.SilkS")
		)
		(fp_line
			(start -1.165606 2.03835)
			(end -0.815594 2.03835)
			(stroke
				(width 0.0127)
				(type default)
			)
			(layer "F.SilkS")
		)
		(fp_line
			(start -1.175258 2.048002)
			(end -0.806196 2.048002)
			(stroke
				(width 0.0127)
				(type default)
			)
			(layer "F.SilkS")
		)
		(fp_line
			(start -1.184656 2.0574)
			(end -0.796544 2.0574)
			(stroke
				(width 0.0127)
				(type default)
			)
			(layer "F.SilkS")
		)
		(fp_line
			(start -1.194308 2.067052)
			(end -0.787146 2.067052)
			(stroke
				(width 0.0127)
				(type default)
			)
			(layer "F.SilkS")
		)
		(fp_line
			(start -1.203706 2.07645)
			(end -0.777494 2.07645)
			(stroke
				(width 0.0127)
				(type default)
			)
			(layer "F.SilkS")
		)
		(fp_line
			(start -1.213358 2.086102)
			(end -0.768096 2.086102)
			(stroke
				(width 0.0127)
				(type default)
			)
			(layer "F.SilkS")
		)
		(fp_line
			(start -1.222756 2.0955)
			(end -0.758444 2.0955)
			(stroke
				(width 0.0127)
				(type default)
			)
			(layer "F.SilkS")
		)
		(fp_line
			(start -1.232408 2.105152)
			(end -0.749046 2.105152)
			(stroke
				(width 0.0127)
				(type default)
			)
			(layer "F.SilkS")
		)
		(fp_line
			(start -1.241806 2.11455)
			(end -0.739394 2.11455)
			(stroke
				(width 0.0127)
				(type default)
			)
			(layer "F.SilkS")
		)
		(fp_line
			(start -1.251458 2.124202)
			(end -0.729996 2.124202)
			(stroke
				(width 0.0127)
				(type default)
			)
			(layer "F.SilkS")
		)
		(fp_line
			(start -1.260856 2.1336)
			(end -0.720344 2.1336)
			(stroke
				(width 0.0127)
				(type default)
			)
			(layer "F.SilkS")
		)
		(fp_line
			(start -0.719074 2.145538)
			(end -1.265936 2.14122)
			(stroke
				(width 0.0127)
				(type default)
			)
			(layer "F.SilkS")
		)
		(fp_line
			(start -1.279398 2.152142)
			(end -0.9906 1.86309)
			(stroke
				(width 0.0127)
				(type default)
			)
			(layer "F.SilkS")
		)
		(fp_line
			(start -0.71628 2.15265)
			(end -1.26492 2.15265)
			(stroke
				(width 0.0127)
				(type default)
			)
			(layer "F.SilkS")
		)
		(fp_line
			(start -1.279144 2.15265)
			(end -0.701294 2.15265)
			(stroke
				(width 0.0127)
				(type default)
			)
			(layer "F.SilkS")
		)
		(fp_poly
			(pts
				(xy -1.285748 2.159) (xy -1.285748 1.8796) (xy -1.778 1.8796) (xy -1.778 -1.8796) (xy 1.778 -1.8796)
				(xy 1.778 1.8796) (xy -0.694944 1.8796) (xy -0.694944 2.159)
			)
			(stroke
				(width 0)
				(type default)
			)
			(fill no)
			(layer "F.CrtYd")
		)
		(fp_poly
			(pts
				(xy -1.285748 2.159) (xy -1.285748 1.8796) (xy -1.778 1.8796) (xy -1.778 -1.8796) (xy 1.778 -1.8796)
				(xy 1.778 1.8796) (xy -0.694944 1.8796) (xy -0.694944 2.159)
			)
			(stroke
				(width 0)
				(type default)
			)
			(fill no)
			(layer "F.Fab")
		)
		(pad "1" smd rect
			(at -0.98425 0.9525 90)
			(size 0.762 1.143)
			(layers "F.Cu" "F.Mask" "F.Paste")
			(net "FLT_HDD11_B")
		)
		(pad "2" smd rect
			(at 0.98425 0.9525 90)
			(size 0.762 1.143)
			(layers "F.Cu" "F.Mask" "F.Paste")
			(net "GND")
		)
		(pad "3" smd rect
			(at 0 -0.9525 90)
			(size 0.762 1.143)
			(layers "F.Cu" "F.Mask" "F.Paste")
			(net "DRIVE_ACT_11")
		)
	)
	(footprint ""
		(layer "F.Cu")
		(at 45.465746 -18.5547)
		(property "Reference" "PC15"
			(at 0 0 0)
			(layer "F.SilkS")
			(hide yes)
			(effects
				(font
					(size 1.27 1.27)
				)
			)
		)
		(property "Value" "SCD1U25V2KX-GP"
			(at 1.1811 -2.7051 0)
			(unlocked yes)
			(layer "F.Fab")
			(hide yes)
			(effects
				(font
					(size 1.016 1.016)
					(thickness 0.1524)
				)
			)
		)
		(property "Device Type" "C402H22"
			(at 1.1811 -4.2291 0)
			(unlocked yes)
			(layer "F.Fab")
			(hide yes)
			(effects
				(font
					(size 1.016 1.016)
					(thickness 0.1524)
				)
			)
		)
		(duplicate_pad_numbers_are_jumpers no)
		(fp_rect
			(start -0.4318 0.9525)
			(end 0.4318 -0.9525)
			(stroke
				(width 0)
				(type default)
			)
			(fill no)
			(layer "F.CrtYd")
		)
		(fp_rect
			(start -0.4318 0.9525)
			(end 0.4318 -0.9525)
			(stroke
				(width 0)
				(type default)
			)
			(fill no)
			(layer "F.Fab")
		)
		(pad "1" smd custom
			(at 0 -0.4445)
			(size 0.1524 0.1524)
			(layers "F.Cu" "F.Mask" "F.Paste")
			(net "P5VB_VBST_NET")
			(options
				(clearance outline)
				(anchor circle)
			)
			(primitives
				(gr_poly
					(pts
						(arc
							(start 0.3048 -0.2032)
							(mid 0.275042 -0.275042)
							(end 0.2032 -0.3048)
						)
						(arc
							(start -0.2032 -0.3048)
							(mid -0.275042 -0.275042)
							(end -0.3048 -0.2032)
						)
						(arc
							(start -0.3048 0.2032)
							(mid -0.275042 0.275042)
							(end -0.2032 0.3048)
						)
						(arc
							(start 0.2032 0.3048)
							(mid 0.275042 0.275042)
							(end 0.3048 0.2032)
						)
					)
					(width 0)
					(fill yes)
				)
			)
		)
		(pad "2" smd custom
			(at 0 0.4445)
			(size 0.1524 0.1524)
			(layers "F.Cu" "F.Mask" "F.Paste")
			(net "P5VB_LL")
			(options
				(clearance outline)
				(anchor circle)
			)
			(primitives
				(gr_poly
					(pts
						(arc
							(start 0.3048 -0.2032)
							(mid 0.275042 -0.275042)
							(end 0.2032 -0.3048)
						)
						(arc
							(start -0.2032 -0.3048)
							(mid -0.275042 -0.275042)
							(end -0.3048 -0.2032)
						)
						(arc
							(start -0.3048 0.2032)
							(mid -0.275042 0.275042)
							(end -0.2032 0.3048)
						)
						(arc
							(start 0.2032 0.3048)
							(mid 0.275042 0.275042)
							(end 0.3048 0.2032)
						)
					)
					(width 0)
					(fill yes)
				)
			)
		)
	)
	(footprint ""
		(layer "F.Cu")
		(at 26.288746 -441.8457 90)
		(property "Reference" "C265"
			(at 0 0 90)
			(layer "F.SilkS")
			(hide yes)
			(effects
				(font
					(size 1.27 1.27)
				)
			)
		)
		(property "Value" "SCD01U50V2KX-1GP"
			(at 1.1811 -2.7051 90)
			(unlocked yes)
			(layer "F.Fab")
			(hide yes)
			(effects
				(font
					(size 1.016 1.016)
					(thickness 0.1524)
				)
			)
		)
		(property "Device Type" "C402H22"
			(at 1.1811 -4.2291 90)
			(unlocked yes)
			(layer "F.Fab")
			(hide yes)
			(effects
				(font
					(size 1.016 1.016)
					(thickness 0.1524)
				)
			)
		)
		(duplicate_pad_numbers_are_jumpers no)
		(fp_rect
			(start -0.4318 0.9525)
			(end 0.4318 -0.9525)
			(stroke
				(width 0)
				(type default)
			)
			(fill no)
			(layer "F.CrtYd")
		)
		(fp_rect
			(start -0.4318 0.9525)
			(end 0.4318 -0.9525)
			(stroke
				(width 0)
				(type default)
			)
			(fill no)
			(layer "F.Fab")
		)
		(pad "1" smd custom
			(at 0 -0.4445 90)
			(size 0.1524 0.1524)
			(layers "F.Cu" "F.Mask" "F.Paste")
			(net "SAS2X28_DRIVE_RX_P_B10")
			(options
				(clearance outline)
				(anchor circle)
			)
			(primitives
				(gr_poly
					(pts
						(arc
							(start 0.3048 -0.2032)
							(mid 0.275042 -0.275042)
							(end 0.2032 -0.3048)
						)
						(arc
							(start -0.2032 -0.3048)
							(mid -0.275042 -0.275042)
							(end -0.3048 -0.2032)
						)
						(arc
							(start -0.3048 0.2032)
							(mid -0.275042 0.275042)
							(end -0.2032 0.3048)
						)
						(arc
							(start 0.2032 0.3048)
							(mid 0.275042 0.275042)
							(end 0.3048 0.2032)
						)
					)
					(width 0)
					(fill yes)
				)
			)
		)
		(pad "2" smd custom
			(at 0 0.4445 90)
			(size 0.1524 0.1524)
			(layers "F.Cu" "F.Mask" "F.Paste")
			(net "SAS2X28_B_HDD10_RX_+")
			(options
				(clearance outline)
				(anchor circle)
			)
			(primitives
				(gr_poly
					(pts
						(arc
							(start 0.3048 -0.2032)
							(mid 0.275042 -0.275042)
							(end 0.2032 -0.3048)
						)
						(arc
							(start -0.2032 -0.3048)
							(mid -0.275042 -0.275042)
							(end -0.3048 -0.2032)
						)
						(arc
							(start -0.3048 0.2032)
							(mid -0.275042 0.275042)
							(end -0.2032 0.3048)
						)
						(arc
							(start 0.2032 0.3048)
							(mid 0.275042 0.275042)
							(end 0.3048 0.2032)
						)
					)
					(width 0)
					(fill yes)
				)
			)
		)
	)
	(footprint ""
		(layer "F.Cu")
		(at 194.818 -293.878)
		(property "Reference" "C381"
			(at 0 0 0)
			(layer "F.SilkS")
			(hide yes)
			(effects
				(font
					(size 1.27 1.27)
				)
			)
		)
		(property "Value" "SCD033U25V2KX-GP"
			(at 1.1811 -2.7051 0)
			(unlocked yes)
			(layer "F.Fab")
			(hide yes)
			(effects
				(font
					(size 1.016 1.016)
					(thickness 0.1524)
				)
			)
		)
		(property "Device Type" "C402H22"
			(at 1.1811 -4.2291 0)
			(unlocked yes)
			(layer "F.Fab")
			(hide yes)
			(effects
				(font
					(size 1.016 1.016)
					(thickness 0.1524)
				)
			)
		)
		(duplicate_pad_numbers_are_jumpers no)
		(fp_rect
			(start -0.4318 0.9525)
			(end 0.4318 -0.9525)
			(stroke
				(width 0)
				(type default)
			)
			(fill no)
			(layer "F.CrtYd")
		)
		(fp_rect
			(start -0.4318 0.9525)
			(end 0.4318 -0.9525)
			(stroke
				(width 0)
				(type default)
			)
			(fill no)
			(layer "F.Fab")
		)
		(pad "1" smd custom
			(at 0 -0.4445)
			(size 0.1524 0.1524)
			(layers "F.Cu" "F.Mask" "F.Paste")
			(net "P12V")
			(options
				(clearance outline)
				(anchor circle)
			)
			(primitives
				(gr_poly
					(pts
						(arc
							(start 0.3048 -0.2032)
							(mid 0.275042 -0.275042)
							(end 0.2032 -0.3048)
						)
						(arc
							(start -0.2032 -0.3048)
							(mid -0.275042 -0.275042)
							(end -0.3048 -0.2032)
						)
						(arc
							(start -0.3048 0.2032)
							(mid -0.275042 0.275042)
							(end -0.2032 0.3048)
						)
						(arc
							(start 0.2032 0.3048)
							(mid 0.275042 0.275042)
							(end 0.3048 0.2032)
						)
					)
					(width 0)
					(fill yes)
				)
			)
		)
		(pad "2" smd custom
			(at 0 0.4445)
			(size 0.1524 0.1524)
			(layers "F.Cu" "F.Mask" "F.Paste")
			(net "SW_HDD2_N")
			(options
				(clearance outline)
				(anchor circle)
			)
			(primitives
				(gr_poly
					(pts
						(arc
							(start 0.3048 -0.2032)
							(mid 0.275042 -0.275042)
							(end 0.2032 -0.3048)
						)
						(arc
							(start -0.2032 -0.3048)
							(mid -0.275042 -0.275042)
							(end -0.3048 -0.2032)
						)
						(arc
							(start -0.3048 0.2032)
							(mid -0.275042 0.275042)
							(end -0.2032 0.3048)
						)
						(arc
							(start 0.2032 0.3048)
							(mid 0.275042 0.275042)
							(end 0.3048 0.2032)
						)
					)
					(width 0)
					(fill yes)
				)
			)
		)
	)
	(footprint ""
		(layer "F.Cu")
		(at 35.432746 -124.869702)
		(property "Reference" "C316"
			(at 0 0 0)
			(layer "F.SilkS")
			(hide yes)
			(effects
				(font
					(size 1.27 1.27)
				)
			)
		)
		(property "Value" "SC1U16V3KX-5GP"
			(at 0 -2.8194 0)
			(unlocked yes)
			(layer "F.Fab")
			(hide yes)
			(effects
				(font
					(size 1.016 1.016)
					(thickness 0.1524)
				)
			)
		)
		(property "Device Type" "C603H36"
			(at 0 -4.3434 0)
			(unlocked yes)
			(layer "F.Fab")
			(hide yes)
			(effects
				(font
					(size 1.016 1.016)
					(thickness 0.1524)
				)
			)
		)
		(duplicate_pad_numbers_are_jumpers no)
		(fp_line
			(start 0.508 0)
			(end -0.508 0)
			(stroke
				(width 0.2032)
				(type default)
			)
			(layer "F.SilkS")
		)
		(fp_rect
			(start -0.5842 1.3335)
			(end 0.5842 -1.3335)
			(stroke
				(width 0)
				(type default)
			)
			(fill no)
			(layer "F.CrtYd")
		)
		(fp_rect
			(start -0.5842 1.3335)
			(end 0.5842 -1.3335)
			(stroke
				(width 0)
				(type default)
			)
			(fill no)
			(layer "F.Fab")
		)
		(pad "1" smd custom
			(at 0 -0.762)
			(size 0.2159 0.2159)
			(layers "F.Cu" "F.Mask" "F.Paste")
			(net "P5V_HDD13")
			(options
				(clearance outline)
				(anchor circle)
			)
			(primitives
				(gr_poly
					(pts
						(arc
							(start -0.3302 -0.4318)
							(mid -0.402042 -0.402042)
							(end -0.4318 -0.3302)
						)
						(arc
							(start -0.4318 0.3302)
							(mid -0.402042 0.402042)
							(end -0.3302 0.4318)
						)
						(arc
							(start 0.3302 0.4318)
							(mid 0.402042 0.402042)
							(end 0.4318 0.3302)
						)
						(arc
							(start 0.4318 -0.3302)
							(mid 0.402042 -0.402042)
							(end 0.3302 -0.4318)
						)
					)
					(width 0)
					(fill yes)
				)
			)
		)
		(pad "2" smd custom
			(at 0 0.762)
			(size 0.2159 0.2159)
			(layers "F.Cu" "F.Mask" "F.Paste")
			(net "GND")
			(options
				(clearance outline)
				(anchor circle)
			)
			(primitives
				(gr_poly
					(pts
						(arc
							(start -0.3302 -0.4318)
							(mid -0.402042 -0.402042)
							(end -0.4318 -0.3302)
						)
						(arc
							(start -0.4318 0.3302)
							(mid -0.402042 0.402042)
							(end -0.3302 0.4318)
						)
						(arc
							(start 0.3302 0.4318)
							(mid 0.402042 0.402042)
							(end 0.4318 0.3302)
						)
						(arc
							(start 0.4318 -0.3302)
							(mid 0.402042 -0.402042)
							(end 0.3302 -0.4318)
						)
					)
					(width 0)
					(fill yes)
				)
			)
		)
	)
	(footprint ""
		(layer "F.Cu")
		(at 213.054184 -188.488828 180)
		(property "Reference" "C160"
			(at 0 0 180)
			(layer "F.SilkS")
			(hide yes)
			(effects
				(font
					(size 1.27 1.27)
				)
			)
		)
		(property "Value" "SC10U25V6KX-1GP"
			(at -0.0762 -5.1308 180)
			(unlocked yes)
			(layer "F.Fab")
			(hide yes)
			(effects
				(font
					(size 1.016 1.016)
					(thickness 0.1524)
				)
			)
		)
		(property "Device Type" "C1206H71"
			(at -0.127 -6.6548 180)
			(unlocked yes)
			(layer "F.Fab")
			(hide yes)
			(effects
				(font
					(size 1.016 1.016)
					(thickness 0.1524)
				)
			)
		)
		(duplicate_pad_numbers_are_jumpers no)
		(fp_line
			(start 1.016 2.2352)
			(end -1.016 2.2352)
			(stroke
				(width 0.1524)
				(type default)
			)
			(layer "F.SilkS")
		)
		(fp_line
			(start 1.016 0.8382)
			(end 1.016 2.2352)
			(stroke
				(width 0.1524)
				(type default)
			)
			(layer "F.SilkS")
		)
		(fp_line
			(start 1.016 -2.2352)
			(end 1.016 -0.8382)
			(stroke
				(width 0.1524)
				(type default)
			)
			(layer "F.SilkS")
		)
		(fp_line
			(start -1.016 2.2352)
			(end -1.016 0.8382)
			(stroke
				(width 0.1524)
				(type default)
			)
			(layer "F.SilkS")
		)
		(fp_line
			(start -1.016 -0.8382)
			(end -1.016 -2.2352)
			(stroke
				(width 0.1524)
				(type default)
			)
			(layer "F.SilkS")
		)
		(fp_line
			(start -1.016 -2.2352)
			(end 1.016 -2.2352)
			(stroke
				(width 0.1524)
				(type default)
			)
			(layer "F.SilkS")
		)
		(fp_rect
			(start -1.0922 2.3114)
			(end 1.0922 -2.3114)
			(stroke
				(width 0)
				(type default)
			)
			(fill no)
			(layer "F.CrtYd")
		)
		(fp_poly
			(pts
				(xy 1.0922 -2.3114) (xy 1.0922 2.3114) (xy -1.0922 2.3114) (xy -1.0922 -2.3114)
			)
			(stroke
				(width 0)
				(type default)
			)
			(fill no)
			(layer "F.Fab")
		)
		(pad "1" smd rect
			(at 0 -1.397 180)
			(size 1.651 1.27)
			(layers "F.Cu" "F.Mask" "F.Paste")
			(net "P12V_HDD3")
		)
		(pad "2" smd rect
			(at 0 1.397 180)
			(size 1.651 1.27)
			(layers "F.Cu" "F.Mask" "F.Paste")
			(net "GND")
		)
	)
	(footprint ""
		(layer "F.Cu")
		(at 211.792058 -388.441184)
		(property "Reference" "C126"
			(at 0 0 0)
			(layer "F.SilkS")
			(hide yes)
			(effects
				(font
					(size 1.27 1.27)
				)
			)
		)
		(property "Value" "SC10U25V6KX-1GP"
			(at -0.0762 -5.1308 0)
			(unlocked yes)
			(layer "F.Fab")
			(hide yes)
			(effects
				(font
					(size 1.016 1.016)
					(thickness 0.1524)
				)
			)
		)
		(property "Device Type" "C1206H71"
			(at -0.127 -6.6548 0)
			(unlocked yes)
			(layer "F.Fab")
			(hide yes)
			(effects
				(font
					(size 1.016 1.016)
					(thickness 0.1524)
				)
			)
		)
		(duplicate_pad_numbers_are_jumpers no)
		(fp_line
			(start -1.016 -2.2352)
			(end 1.016 -2.2352)
			(stroke
				(width 0.1524)
				(type default)
			)
			(layer "F.SilkS")
		)
		(fp_line
			(start -1.016 -0.8382)
			(end -1.016 -2.2352)
			(stroke
				(width 0.1524)
				(type default)
			)
			(layer "F.SilkS")
		)
		(fp_line
			(start -1.016 2.2352)
			(end -1.016 0.8382)
			(stroke
				(width 0.1524)
				(type default)
			)
			(layer "F.SilkS")
		)
		(fp_line
			(start 1.016 -2.2352)
			(end 1.016 -0.8382)
			(stroke
				(width 0.1524)
				(type default)
			)
			(layer "F.SilkS")
		)
		(fp_line
			(start 1.016 0.8382)
			(end 1.016 2.2352)
			(stroke
				(width 0.1524)
				(type default)
			)
			(layer "F.SilkS")
		)
		(fp_line
			(start 1.016 2.2352)
			(end -1.016 2.2352)
			(stroke
				(width 0.1524)
				(type default)
			)
			(layer "F.SilkS")
		)
		(fp_rect
			(start -1.0922 2.3114)
			(end 1.0922 -2.3114)
			(stroke
				(width 0)
				(type default)
			)
			(fill no)
			(layer "F.CrtYd")
		)
		(fp_poly
			(pts
				(xy 1.0922 -2.3114) (xy 1.0922 2.3114) (xy -1.0922 2.3114) (xy -1.0922 -2.3114)
			)
			(stroke
				(width 0)
				(type default)
			)
			(fill no)
			(layer "F.Fab")
		)
		(pad "1" smd rect
			(at 0 -1.397)
			(size 1.651 1.27)
			(layers "F.Cu" "F.Mask" "F.Paste")
			(net "P12V_HDD1")
		)
		(pad "2" smd rect
			(at 0 1.397)
			(size 1.651 1.27)
			(layers "F.Cu" "F.Mask" "F.Paste")
			(net "GND")
		)
	)
	(footprint ""
		(layer "F.Cu")
		(at 44.3992 -427.2534)
		(property "Reference" "Q66"
			(at 0 0 0)
			(layer "F.SilkS")
			(hide yes)
			(effects
				(font
					(size 1.27 1.27)
				)
			)
		)
		(property "Value" "2N7002DW-7F-GP"
			(at -2.3622 -8.2042 0)
			(unlocked yes)
			(layer "F.Fab")
			(hide yes)
			(effects
				(font
					(size 1.016 1.016)
					(thickness 0.1524)
				)
			)
		)
		(property "Device Type" "SOT-363H44"
			(at -2.3622 -10.1092 0)
			(unlocked yes)
			(layer "F.Fab")
			(hide yes)
			(effects
				(font
					(size 1.016 1.016)
					(thickness 0.1524)
				)
			)
		)
		(duplicate_pad_numbers_are_jumpers no)
		(fp_line
			(start -1.4478 -1.7018)
			(end -1.4478 1.7018)
			(stroke
				(width 0.1524)
				(type default)
			)
			(layer "F.SilkS")
		)
		(fp_line
			(start -1.4478 1.7018)
			(end 1.4478 1.7018)
			(stroke
				(width 0.1524)
				(type default)
			)
			(layer "F.SilkS")
		)
		(fp_line
			(start -1.27 1.524)
			(end -1.27 0.6604)
			(stroke
				(width 0.4826)
				(type default)
			)
			(layer "F.SilkS")
		)
		(fp_line
			(start 1.4478 -1.7018)
			(end -1.4478 -1.7018)
			(stroke
				(width 0.1524)
				(type default)
			)
			(layer "F.SilkS")
		)
		(fp_line
			(start 1.4478 1.7018)
			(end 1.4478 -1.7018)
			(stroke
				(width 0.1524)
				(type default)
			)
			(layer "F.SilkS")
		)
		(fp_poly
			(pts
				(xy -1.524 -1.778) (xy 1.524 -1.778) (xy 1.524 1.778) (xy -1.524 1.778)
			)
			(stroke
				(width 0)
				(type default)
			)
			(fill no)
			(layer "F.CrtYd")
		)
		(fp_poly
			(pts
				(xy -1.524 -1.778) (xy 1.524 -1.778) (xy 1.524 1.778) (xy -1.524 1.778)
			)
			(stroke
				(width 0)
				(type default)
			)
			(fill no)
			(layer "F.Fab")
		)
		(pad "1" smd rect
			(at -0.65024 0.9398)
			(size 0.4064 1.016)
			(layers "F.Cu" "F.Mask" "F.Paste")
			(net "P3V3_HDD10_LED")
		)
		(pad "2" smd rect
			(at 0 0.9398)
			(size 0.4064 1.016)
			(layers "F.Cu" "F.Mask" "F.Paste")
			(net "HDD10_LED_G")
		)
		(pad "3" smd rect
			(at 0.65024 0.9398)
			(size 0.4064 1.016)
			(layers "F.Cu" "F.Mask" "F.Paste")
			(net "P5VC")
		)
		(pad "4" smd rect
			(at 0.65024 -0.9398)
			(size 0.4064 1.016)
			(layers "F.Cu" "F.Mask" "F.Paste")
			(net "P5VC_HDD10_LED")
		)
		(pad "5" smd rect
			(at 0 -0.9398)
			(size 0.4064 1.016)
			(layers "F.Cu" "F.Mask" "F.Paste")
			(net "HDD10_LED_G")
		)
		(pad "6" smd rect
			(at -0.65024 -0.9398)
			(size 0.4064 1.016)
			(layers "F.Cu" "F.Mask" "F.Paste")
			(net "P3V3")
		)
	)
	(footprint ""
		(layer "F.Cu")
		(at 216.999058 -378.281184)
		(property "Reference" "R125"
			(at 0 0 0)
			(layer "F.SilkS")
			(hide yes)
			(effects
				(font
					(size 1.27 1.27)
				)
			)
		)
		(property "Value" "220R3F-1-GP"
			(at -0.0254 -2.5146 0)
			(unlocked yes)
			(layer "F.Fab")
			(hide yes)
			(effects
				(font
					(size 1.016 1.016)
					(thickness 0.1524)
				)
			)
		)
		(property "Device Type" "R603H22"
			(at -0.0254 -4.0386 0)
			(unlocked yes)
			(layer "F.Fab")
			(hide yes)
			(effects
				(font
					(size 1.016 1.016)
					(thickness 0.1524)
				)
			)
		)
		(duplicate_pad_numbers_are_jumpers no)
		(fp_line
			(start -0.4826 0)
			(end -0.2032 0)
			(stroke
				(width 0.2032)
				(type default)
			)
			(layer "F.SilkS")
		)
		(fp_line
			(start 0.2032 0)
			(end 0.4826 0)
			(stroke
				(width 0.2032)
				(type default)
			)
			(layer "F.SilkS")
		)
		(fp_rect
			(start -0.5842 1.3335)
			(end 0.5842 -1.3335)
			(stroke
				(width 0)
				(type default)
			)
			(fill no)
			(layer "F.CrtYd")
		)
		(fp_rect
			(start -0.5842 1.3335)
			(end 0.5842 -1.3335)
			(stroke
				(width 0)
				(type default)
			)
			(fill no)
			(layer "F.Fab")
		)
		(pad "1" smd custom
			(at 0 -0.762)
			(size 0.2159 0.2159)
			(layers "F.Cu" "F.Mask" "F.Paste")
			(net "HDD_PRSNT_NET1")
			(options
				(clearance outline)
				(anchor circle)
			)
			(primitives
				(gr_poly
					(pts
						(arc
							(start -0.3302 -0.4318)
							(mid -0.402042 -0.402042)
							(end -0.4318 -0.3302)
						)
						(arc
							(start -0.4318 0.3302)
							(mid -0.402042 0.402042)
							(end -0.3302 0.4318)
						)
						(arc
							(start 0.3302 0.4318)
							(mid 0.402042 0.402042)
							(end 0.4318 0.3302)
						)
						(arc
							(start 0.4318 -0.3302)
							(mid 0.402042 -0.402042)
							(end 0.3302 -0.4318)
						)
					)
					(width 0)
					(fill yes)
				)
			)
		)
		(pad "2" smd custom
			(at 0 0.762)
			(size 0.2159 0.2159)
			(layers "F.Cu" "F.Mask" "F.Paste")
			(net "HDD_PRSNT1")
			(options
				(clearance outline)
				(anchor circle)
			)
			(primitives
				(gr_poly
					(pts
						(arc
							(start -0.3302 -0.4318)
							(mid -0.402042 -0.402042)
							(end -0.4318 -0.3302)
						)
						(arc
							(start -0.4318 0.3302)
							(mid -0.402042 0.402042)
							(end -0.3302 0.4318)
						)
						(arc
							(start 0.3302 0.4318)
							(mid 0.402042 0.402042)
							(end 0.4318 0.3302)
						)
						(arc
							(start 0.4318 -0.3302)
							(mid 0.402042 -0.402042)
							(end 0.3302 -0.4318)
						)
					)
					(width 0)
					(fill yes)
				)
			)
		)
	)
	(footprint ""
		(layer "F.Cu")
		(at 195.707 -396.24)
		(property "Reference" "C380"
			(at 0 0 0)
			(layer "F.SilkS")
			(hide yes)
			(effects
				(font
					(size 1.27 1.27)
				)
			)
		)
		(property "Value" "SCD033U25V2KX-GP"
			(at 1.1811 -2.7051 0)
			(unlocked yes)
			(layer "F.Fab")
			(hide yes)
			(effects
				(font
					(size 1.016 1.016)
					(thickness 0.1524)
				)
			)
		)
		(property "Device Type" "C402H22"
			(at 1.1811 -4.2291 0)
			(unlocked yes)
			(layer "F.Fab")
			(hide yes)
			(effects
				(font
					(size 1.016 1.016)
					(thickness 0.1524)
				)
			)
		)
		(duplicate_pad_numbers_are_jumpers no)
		(fp_rect
			(start -0.4318 0.9525)
			(end 0.4318 -0.9525)
			(stroke
				(width 0)
				(type default)
			)
			(fill no)
			(layer "F.CrtYd")
		)
		(fp_rect
			(start -0.4318 0.9525)
			(end 0.4318 -0.9525)
			(stroke
				(width 0)
				(type default)
			)
			(fill no)
			(layer "F.Fab")
		)
		(pad "1" smd custom
			(at 0 -0.4445)
			(size 0.1524 0.1524)
			(layers "F.Cu" "F.Mask" "F.Paste")
			(net "P12V")
			(options
				(clearance outline)
				(anchor circle)
			)
			(primitives
				(gr_poly
					(pts
						(arc
							(start 0.3048 -0.2032)
							(mid 0.275042 -0.275042)
							(end 0.2032 -0.3048)
						)
						(arc
							(start -0.2032 -0.3048)
							(mid -0.275042 -0.275042)
							(end -0.3048 -0.2032)
						)
						(arc
							(start -0.3048 0.2032)
							(mid -0.275042 0.275042)
							(end -0.2032 0.3048)
						)
						(arc
							(start 0.2032 0.3048)
							(mid 0.275042 0.275042)
							(end 0.3048 0.2032)
						)
					)
					(width 0)
					(fill yes)
				)
			)
		)
		(pad "2" smd custom
			(at 0 0.4445)
			(size 0.1524 0.1524)
			(layers "F.Cu" "F.Mask" "F.Paste")
			(net "SW_HDD1_N")
			(options
				(clearance outline)
				(anchor circle)
			)
			(primitives
				(gr_poly
					(pts
						(arc
							(start 0.3048 -0.2032)
							(mid 0.275042 -0.275042)
							(end 0.2032 -0.3048)
						)
						(arc
							(start -0.2032 -0.3048)
							(mid -0.275042 -0.275042)
							(end -0.3048 -0.2032)
						)
						(arc
							(start -0.3048 0.2032)
							(mid -0.275042 0.275042)
							(end -0.2032 0.3048)
						)
						(arc
							(start 0.2032 0.3048)
							(mid 0.275042 0.275042)
							(end 0.3048 0.2032)
						)
					)
					(width 0)
					(fill yes)
				)
			)
		)
	)
	(footprint ""
		(layer "F.Cu")
		(at 66.801746 -386.2197 -90)
		(property "Reference" "Q13"
			(at 0 0 270)
			(layer "F.SilkS")
			(hide yes)
			(effects
				(font
					(size 1.27 1.27)
				)
			)
		)
		(property "Value" "AO4406AL-GP"
			(at -3.707384 -1.5367 270)
			(unlocked yes)
			(layer "F.Fab")
			(hide yes)
			(effects
				(font
					(size 1.016 1.016)
					(thickness 0.1524)
				)
			)
		)
		(property "Device Type" "SOIC8H69"
			(at -3.707384 -3.0607 270)
			(unlocked yes)
			(layer "F.Fab")
			(hide yes)
			(effects
				(font
					(size 1.016 1.016)
					(thickness 0.1524)
				)
			)
		)
		(duplicate_pad_numbers_are_jumpers no)
		(fp_line
			(start -2.6289 3.4417)
			(end -2.6289 1.4732)
			(stroke
				(width 0.381)
				(type default)
			)
			(layer "F.SilkS")
		)
		(fp_line
			(start -2.7432 1.4224)
			(end -2.6416 1.4224)
			(stroke
				(width 0.1524)
				(type default)
			)
			(layer "F.SilkS")
		)
		(fp_line
			(start -2.7432 1.4224)
			(end 2.1336 1.4224)
			(stroke
				(width 0.1524)
				(type default)
			)
			(layer "F.SilkS")
		)
		(fp_line
			(start 2.1336 1.4224)
			(end 2.1336 -1.4224)
			(stroke
				(width 0.1524)
				(type default)
			)
			(layer "F.SilkS")
		)
		(fp_line
			(start -2.1844 -0.0508)
			(end -2.7178 0.508)
			(stroke
				(width 0.1524)
				(type default)
			)
			(layer "F.SilkS")
		)
		(fp_line
			(start -2.7178 -0.508)
			(end -2.1844 -0.0508)
			(stroke
				(width 0.1524)
				(type default)
			)
			(layer "F.SilkS")
		)
		(fp_line
			(start -2.7432 -1.4224)
			(end -2.7432 1.4224)
			(stroke
				(width 0.1524)
				(type default)
			)
			(layer "F.SilkS")
		)
		(fp_line
			(start 2.1336 -1.4224)
			(end -2.7432 -1.4224)
			(stroke
				(width 0.1524)
				(type default)
			)
			(layer "F.SilkS")
		)
		(fp_poly
			(pts
				(xy -2.2098 -1.4224) (xy -2.2098 1.4224) (xy 2.2098 1.4224) (xy 2.2098 -1.4224)
			)
			(stroke
				(width 0)
				(type default)
			)
			(fill yes)
			(layer "F.SilkS")
		)
		(fp_rect
			(start -2.450084 2.999994)
			(end 2.450084 -2.999994)
			(stroke
				(width 0)
				(type default)
			)
			(fill no)
			(layer "F.CrtYd")
		)
		(fp_poly
			(pts
				(xy -2.8194 3.6322) (xy -2.8194 -3.6322) (xy 2.8194 -3.6322) (xy 2.8194 1.18364) (xy 2.450084 1.18364)
				(xy 2.450084 -2.999994) (xy -2.450084 -2.999994) (xy -2.450084 2.999994) (xy 2.450084 2.999994)
				(xy 2.450084 1.18618) (xy 2.8194 1.18618) (xy 2.8194 3.6322)
			)
			(stroke
				(width 0)
				(type default)
			)
			(fill no)
			(layer "F.CrtYd")
		)
		(fp_rect
			(start -2.8194 3.6322)
			(end 2.8194 -3.6322)
			(stroke
				(width 0)
				(type default)
			)
			(fill no)
			(layer "F.Fab")
		)
		(pad "1" smd rect
			(at -1.905 2.54 270)
			(size 0.635 1.651)
			(layers "F.Cu" "F.Mask" "F.Paste")
			(net "P5V_HDD6")
		)
		(pad "2" smd rect
			(at -0.635 2.54 270)
			(size 0.635 1.651)
			(layers "F.Cu" "F.Mask" "F.Paste")
			(net "P5V_HDD6")
		)
		(pad "3" smd rect
			(at 0.635 2.54 270)
			(size 0.635 1.651)
			(layers "F.Cu" "F.Mask" "F.Paste")
			(net "P5V_HDD6")
		)
		(pad "4" smd rect
			(at 1.905 2.54 270)
			(size 0.635 1.651)
			(layers "F.Cu" "F.Mask" "F.Paste")
			(net "SW_HDD6_P")
		)
		(pad "5" smd rect
			(at 1.905 -2.54 270)
			(size 0.635 1.651)
			(layers "F.Cu" "F.Mask" "F.Paste")
			(net "P5VB")
		)
		(pad "6" smd rect
			(at 0.635 -2.54 270)
			(size 0.635 1.651)
			(layers "F.Cu" "F.Mask" "F.Paste")
			(net "P5VB")
		)
		(pad "7" smd rect
			(at -0.635 -2.54 270)
			(size 0.635 1.651)
			(layers "F.Cu" "F.Mask" "F.Paste")
			(net "P5VB")
		)
		(pad "8" smd rect
			(at -1.905 -2.54 270)
			(size 0.635 1.651)
			(layers "F.Cu" "F.Mask" "F.Paste")
			(net "P5VB")
		)
	)
	(footprint ""
		(layer "F.Cu")
		(at 163.588446 -455.837036 180)
		(property "Reference" "R483"
			(at 0 0 180)
			(layer "F.SilkS")
			(hide yes)
			(effects
				(font
					(size 1.27 1.27)
				)
			)
		)
		(property "Value" "10KR2F-2-GP"
			(at 0.064008 -3.993896 180)
			(unlocked yes)
			(layer "F.Fab")
			(hide yes)
			(effects
				(font
					(size 1.016 1.016)
					(thickness 0.1524)
				)
			)
		)
		(property "Device Type" "R402H16"
			(at 0.064008 -5.517896 180)
			(unlocked yes)
			(layer "F.Fab")
			(hide yes)
			(effects
				(font
					(size 1.016 1.016)
					(thickness 0.1524)
				)
			)
		)
		(duplicate_pad_numbers_are_jumpers no)
		(fp_line
			(start 0.508 -0.9398)
			(end -0.508 -0.9398)
			(stroke
				(width 0.1524)
				(type default)
			)
			(layer "F.SilkS")
		)
		(fp_line
			(start -0.508 -0.9398)
			(end -0.508 0.9398)
			(stroke
				(width 0.1524)
				(type default)
			)
			(layer "F.SilkS")
		)
		(fp_rect
			(start -0.508 0.9398)
			(end 0.508 -0.9398)
			(stroke
				(width 0)
				(type default)
			)
			(fill no)
			(layer "F.CrtYd")
		)
		(fp_rect
			(start -0.508 0.9398)
			(end 0.508 -0.9398)
			(stroke
				(width 0)
				(type default)
			)
			(fill no)
			(layer "F.Fab")
		)
		(pad "1" smd custom
			(at 0 -0.4445 180)
			(size 0.1397 0.1397)
			(layers "F.Cu" "F.Mask" "F.Paste")
			(net "P5VB")
			(options
				(clearance outline)
				(anchor circle)
			)
			(primitives
				(gr_poly
					(pts
						(arc
							(start -0.1778 -0.2794)
							(mid -0.249642 -0.249642)
							(end -0.2794 -0.1778)
						)
						(arc
							(start -0.2794 0.1778)
							(mid -0.249642 0.249642)
							(end -0.1778 0.2794)
						)
						(arc
							(start 0.1778 0.2794)
							(mid 0.249642 0.249642)
							(end 0.2794 0.1778)
						)
						(arc
							(start 0.2794 -0.1778)
							(mid 0.249642 -0.249642)
							(end 0.1778 -0.2794)
						)
					)
					(width 0)
					(fill yes)
				)
			)
		)
		(pad "2" smd custom
			(at 0 0.4445 180)
			(size 0.1397 0.1397)
			(layers "F.Cu" "F.Mask" "F.Paste")
			(net "P5VB_DIV")
			(options
				(clearance outline)
				(anchor circle)
			)
			(primitives
				(gr_poly
					(pts
						(arc
							(start -0.1778 -0.2794)
							(mid -0.249642 -0.249642)
							(end -0.2794 -0.1778)
						)
						(arc
							(start -0.2794 0.1778)
							(mid -0.249642 0.249642)
							(end -0.1778 0.2794)
						)
						(arc
							(start 0.1778 0.2794)
							(mid 0.249642 0.249642)
							(end 0.2794 0.1778)
						)
						(arc
							(start 0.2794 -0.1778)
							(mid 0.249642 -0.249642)
							(end 0.1778 -0.2794)
						)
					)
					(width 0)
					(fill yes)
				)
			)
		)
	)
	(footprint ""
		(layer "F.Cu")
		(at 37.591746 -109.248702 180)
		(property "Reference" "U42"
			(at 0 0 180)
			(layer "F.SilkS")
			(hide yes)
			(effects
				(font
					(size 1.27 1.27)
				)
			)
		)
		(property "Value" "74LVC1G08GW-1-GP"
			(at -2.3368 -8.6868 180)
			(unlocked yes)
			(layer "F.Fab")
			(hide yes)
			(effects
				(font
					(size 1.016 1.016)
					(thickness 0.1524)
				)
			)
		)
		(property "Device Type" "SC70-5H44"
			(at -2.3114 -10.414 180)
			(unlocked yes)
			(layer "F.Fab")
			(hide yes)
			(effects
				(font
					(size 1.016 1.016)
					(thickness 0.1524)
				)
			)
		)
		(duplicate_pad_numbers_are_jumpers no)
		(fp_line
			(start 1.3843 -1.8034)
			(end 1.3843 -1.1176)
			(stroke
				(width 0.3302)
				(type default)
			)
			(layer "F.SilkS")
		)
		(fp_line
			(start 1.27 1.7018)
			(end -1.27 1.7018)
			(stroke
				(width 0.1524)
				(type default)
			)
			(layer "F.SilkS")
		)
		(fp_line
			(start 1.27 -1.7018)
			(end 1.27 1.7018)
			(stroke
				(width 0.1524)
				(type default)
			)
			(layer "F.SilkS")
		)
		(fp_line
			(start 0.6604 -1.8034)
			(end 1.3843 -1.8034)
			(stroke
				(width 0.3302)
				(type default)
			)
			(layer "F.SilkS")
		)
		(fp_line
			(start -1.27 1.7018)
			(end -1.27 -1.7018)
			(stroke
				(width 0.1524)
				(type default)
			)
			(layer "F.SilkS")
		)
		(fp_line
			(start -1.27 -1.7018)
			(end 1.27 -1.7018)
			(stroke
				(width 0.1524)
				(type default)
			)
			(layer "F.SilkS")
		)
		(fp_rect
			(start -1.524 1.9558)
			(end 1.524 -1.9558)
			(stroke
				(width 0)
				(type default)
			)
			(fill no)
			(layer "F.CrtYd")
		)
		(fp_poly
			(pts
				(xy -1.524 -1.9558) (xy 1.524 -1.9558) (xy 1.524 1.9558) (xy -1.524 1.9558)
			)
			(stroke
				(width 0)
				(type default)
			)
			(fill no)
			(layer "F.Fab")
		)
		(pad "1" smd rect
			(at 0.65024 -0.8255 180)
			(size 0.4064 1.2192)
			(layers "F.Cu" "F.Mask" "F.Paste")
			(net "SAS_EXP_B_PWR13")
		)
		(pad "2" smd rect
			(at 0 -0.8255 180)
			(size 0.4064 1.2192)
			(layers "F.Cu" "F.Mask" "F.Paste")
			(net "SAS_EXP_A_PWR13")
		)
		(pad "3" smd rect
			(at -0.65024 -0.8255 180)
			(size 0.4064 1.2192)
			(layers "F.Cu" "F.Mask" "F.Paste")
			(net "GND")
		)
		(pad "4" smd rect
			(at -0.65024 0.8255 180)
			(size 0.4064 1.2192)
			(layers "F.Cu" "F.Mask" "F.Paste")
			(net "DRIVE_PWR13")
		)
		(pad "5" smd rect
			(at 0.65024 0.8255 180)
			(size 0.4064 1.2192)
			(layers "F.Cu" "F.Mask" "F.Paste")
			(net "P3V3")
		)
	)
	(footprint ""
		(layer "F.Cu")
		(at 75.438 -394.1064 180)
		(property "Reference" "C203"
			(at 0 0 180)
			(layer "F.SilkS")
			(hide yes)
			(effects
				(font
					(size 1.27 1.27)
				)
			)
		)
		(property "Value" "SCD1U10V2KX-5GP"
			(at 1.1811 -2.7051 180)
			(unlocked yes)
			(layer "F.Fab")
			(hide yes)
			(effects
				(font
					(size 1.016 1.016)
					(thickness 0.1524)
				)
			)
		)
		(property "Device Type" "C402H22"
			(at 1.1811 -4.2291 180)
			(unlocked yes)
			(layer "F.Fab")
			(hide yes)
			(effects
				(font
					(size 1.016 1.016)
					(thickness 0.1524)
				)
			)
		)
		(duplicate_pad_numbers_are_jumpers no)
		(fp_rect
			(start -0.4318 0.9525)
			(end 0.4318 -0.9525)
			(stroke
				(width 0)
				(type default)
			)
			(fill no)
			(layer "F.CrtYd")
		)
		(fp_rect
			(start -0.4318 0.9525)
			(end 0.4318 -0.9525)
			(stroke
				(width 0)
				(type default)
			)
			(fill no)
			(layer "F.Fab")
		)
		(pad "1" smd custom
			(at 0 -0.4445 180)
			(size 0.1524 0.1524)
			(layers "F.Cu" "F.Mask" "F.Paste")
			(net "P3V3")
			(options
				(clearance outline)
				(anchor circle)
			)
			(primitives
				(gr_poly
					(pts
						(arc
							(start 0.3048 -0.2032)
							(mid 0.275042 -0.275042)
							(end 0.2032 -0.3048)
						)
						(arc
							(start -0.2032 -0.3048)
							(mid -0.275042 -0.275042)
							(end -0.3048 -0.2032)
						)
						(arc
							(start -0.3048 0.2032)
							(mid -0.275042 0.275042)
							(end -0.2032 0.3048)
						)
						(arc
							(start 0.2032 0.3048)
							(mid 0.275042 0.275042)
							(end 0.3048 0.2032)
						)
					)
					(width 0)
					(fill yes)
				)
			)
		)
		(pad "2" smd custom
			(at 0 0.4445 180)
			(size 0.1524 0.1524)
			(layers "F.Cu" "F.Mask" "F.Paste")
			(net "GND")
			(options
				(clearance outline)
				(anchor circle)
			)
			(primitives
				(gr_poly
					(pts
						(arc
							(start 0.3048 -0.2032)
							(mid 0.275042 -0.275042)
							(end 0.2032 -0.3048)
						)
						(arc
							(start -0.2032 -0.3048)
							(mid -0.275042 -0.275042)
							(end -0.3048 -0.2032)
						)
						(arc
							(start -0.3048 0.2032)
							(mid -0.275042 0.275042)
							(end -0.2032 0.3048)
						)
						(arc
							(start 0.2032 0.3048)
							(mid 0.275042 0.275042)
							(end 0.3048 0.2032)
						)
					)
					(width 0)
					(fill yes)
				)
			)
		)
	)
	(footprint ""
		(layer "F.Cu")
		(at 190.960756 -493.322102 -90)
		(property "Reference" "R113"
			(at 0 0 270)
			(layer "F.SilkS")
			(hide yes)
			(effects
				(font
					(size 1.27 1.27)
				)
			)
		)
		(property "Value" "0R2J-2-GP"
			(at 0.064008 -3.993896 270)
			(unlocked yes)
			(layer "F.Fab")
			(hide yes)
			(effects
				(font
					(size 1.016 1.016)
					(thickness 0.1524)
				)
			)
		)
		(property "Device Type" "R402H16"
			(at 0.064008 -5.517896 270)
			(unlocked yes)
			(layer "F.Fab")
			(hide yes)
			(effects
				(font
					(size 1.016 1.016)
					(thickness 0.1524)
				)
			)
		)
		(duplicate_pad_numbers_are_jumpers no)
		(fp_line
			(start -0.508 -0.9398)
			(end -0.508 0.9398)
			(stroke
				(width 0.1524)
				(type default)
			)
			(layer "F.SilkS")
		)
		(fp_line
			(start 0.508 -0.9398)
			(end -0.508 -0.9398)
			(stroke
				(width 0.1524)
				(type default)
			)
			(layer "F.SilkS")
		)
		(fp_rect
			(start -0.508 0.9398)
			(end 0.508 -0.9398)
			(stroke
				(width 0)
				(type default)
			)
			(fill no)
			(layer "F.CrtYd")
		)
		(fp_rect
			(start -0.508 0.9398)
			(end 0.508 -0.9398)
			(stroke
				(width 0)
				(type default)
			)
			(fill no)
			(layer "F.Fab")
		)
		(pad "1" smd custom
			(at 0 -0.4445 270)
			(size 0.1397 0.1397)
			(layers "F.Cu" "F.Mask" "F.Paste")
			(net "DRIVE_PWR0")
			(options
				(clearance outline)
				(anchor circle)
			)
			(primitives
				(gr_poly
					(pts
						(arc
							(start -0.1778 -0.2794)
							(mid -0.249642 -0.249642)
							(end -0.2794 -0.1778)
						)
						(arc
							(start -0.2794 0.1778)
							(mid -0.249642 0.249642)
							(end -0.1778 0.2794)
						)
						(arc
							(start 0.1778 0.2794)
							(mid 0.249642 0.249642)
							(end 0.2794 0.1778)
						)
						(arc
							(start 0.2794 -0.1778)
							(mid 0.249642 -0.249642)
							(end 0.1778 -0.2794)
						)
					)
					(width 0)
					(fill yes)
				)
			)
		)
		(pad "2" smd custom
			(at 0 0.4445 270)
			(size 0.1397 0.1397)
			(layers "F.Cu" "F.Mask" "F.Paste")
			(net "SW_PWR_HDD0")
			(options
				(clearance outline)
				(anchor circle)
			)
			(primitives
				(gr_poly
					(pts
						(arc
							(start -0.1778 -0.2794)
							(mid -0.249642 -0.249642)
							(end -0.2794 -0.1778)
						)
						(arc
							(start -0.2794 0.1778)
							(mid -0.249642 0.249642)
							(end -0.1778 0.2794)
						)
						(arc
							(start 0.1778 0.2794)
							(mid 0.249642 0.249642)
							(end 0.2794 0.1778)
						)
						(arc
							(start 0.2794 -0.1778)
							(mid 0.249642 -0.249642)
							(end 0.1778 -0.2794)
						)
					)
					(width 0)
					(fill yes)
				)
			)
		)
	)
	(footprint ""
		(layer "F.Cu")
		(at 56.3372 -477.6216 -90)
		(property "Reference" "Q56"
			(at 0 0 270)
			(layer "F.SilkS")
			(hide yes)
			(effects
				(font
					(size 1.27 1.27)
				)
			)
		)
		(property "Value" "2N7002DW-7F-GP"
			(at -2.3622 -8.2042 270)
			(unlocked yes)
			(layer "F.Fab")
			(hide yes)
			(effects
				(font
					(size 1.016 1.016)
					(thickness 0.1524)
				)
			)
		)
		(property "Device Type" "SOT-363H44"
			(at -2.3622 -10.1092 270)
			(unlocked yes)
			(layer "F.Fab")
			(hide yes)
			(effects
				(font
					(size 1.016 1.016)
					(thickness 0.1524)
				)
			)
		)
		(duplicate_pad_numbers_are_jumpers no)
		(fp_line
			(start -1.4478 1.7018)
			(end 1.4478 1.7018)
			(stroke
				(width 0.1524)
				(type default)
			)
			(layer "F.SilkS")
		)
		(fp_line
			(start 1.4478 1.7018)
			(end 1.4478 -1.7018)
			(stroke
				(width 0.1524)
				(type default)
			)
			(layer "F.SilkS")
		)
		(fp_line
			(start -1.27 1.524)
			(end -1.27 0.6604)
			(stroke
				(width 0.4826)
				(type default)
			)
			(layer "F.SilkS")
		)
		(fp_line
			(start -1.4478 -1.7018)
			(end -1.4478 1.7018)
			(stroke
				(width 0.1524)
				(type default)
			)
			(layer "F.SilkS")
		)
		(fp_line
			(start 1.4478 -1.7018)
			(end -1.4478 -1.7018)
			(stroke
				(width 0.1524)
				(type default)
			)
			(layer "F.SilkS")
		)
		(fp_poly
			(pts
				(xy -1.524 -1.778) (xy 1.524 -1.778) (xy 1.524 1.778) (xy -1.524 1.778)
			)
			(stroke
				(width 0)
				(type default)
			)
			(fill no)
			(layer "F.CrtYd")
		)
		(fp_poly
			(pts
				(xy -1.524 -1.778) (xy 1.524 -1.778) (xy 1.524 1.778) (xy -1.524 1.778)
			)
			(stroke
				(width 0)
				(type default)
			)
			(fill no)
			(layer "F.Fab")
		)
		(pad "1" smd rect
			(at -0.65024 0.9398 270)
			(size 0.4064 1.016)
			(layers "F.Cu" "F.Mask" "F.Paste")
			(net "P3V3_HDD5_LED")
		)
		(pad "2" smd rect
			(at 0 0.9398 270)
			(size 0.4064 1.016)
			(layers "F.Cu" "F.Mask" "F.Paste")
			(net "HDD5_LED_G")
		)
		(pad "3" smd rect
			(at 0.65024 0.9398 270)
			(size 0.4064 1.016)
			(layers "F.Cu" "F.Mask" "F.Paste")
			(net "P5VB")
		)
		(pad "4" smd rect
			(at 0.65024 -0.9398 270)
			(size 0.4064 1.016)
			(layers "F.Cu" "F.Mask" "F.Paste")
			(net "P5VB_HDD5_LED")
		)
		(pad "5" smd rect
			(at 0 -0.9398 270)
			(size 0.4064 1.016)
			(layers "F.Cu" "F.Mask" "F.Paste")
			(net "HDD5_LED_G")
		)
		(pad "6" smd rect
			(at -0.65024 -0.9398 270)
			(size 0.4064 1.016)
			(layers "F.Cu" "F.Mask" "F.Paste")
			(net "P3V3")
		)
	)
	(footprint ""
		(layer "F.Cu")
		(at 177.558446 -457.615036 -90)
		(property "Reference" "R361"
			(at 0 0 270)
			(layer "F.SilkS")
			(hide yes)
			(effects
				(font
					(size 1.27 1.27)
				)
			)
		)
		(property "Value" "0R2J-2-GP"
			(at 0.064008 -3.993896 270)
			(unlocked yes)
			(layer "F.Fab")
			(hide yes)
			(effects
				(font
					(size 1.016 1.016)
					(thickness 0.1524)
				)
			)
		)
		(property "Device Type" "R402H16"
			(at 0.064008 -5.517896 270)
			(unlocked yes)
			(layer "F.Fab")
			(hide yes)
			(effects
				(font
					(size 1.016 1.016)
					(thickness 0.1524)
				)
			)
		)
		(duplicate_pad_numbers_are_jumpers no)
		(fp_line
			(start -0.508 -0.9398)
			(end -0.508 0.9398)
			(stroke
				(width 0.1524)
				(type default)
			)
			(layer "F.SilkS")
		)
		(fp_line
			(start 0.508 -0.9398)
			(end -0.508 -0.9398)
			(stroke
				(width 0.1524)
				(type default)
			)
			(layer "F.SilkS")
		)
		(fp_rect
			(start -0.508 0.9398)
			(end 0.508 -0.9398)
			(stroke
				(width 0)
				(type default)
			)
			(fill no)
			(layer "F.CrtYd")
		)
		(fp_rect
			(start -0.508 0.9398)
			(end 0.508 -0.9398)
			(stroke
				(width 0)
				(type default)
			)
			(fill no)
			(layer "F.Fab")
		)
		(pad "1" smd custom
			(at 0 -0.4445 270)
			(size 0.1397 0.1397)
			(layers "F.Cu" "F.Mask" "F.Paste")
			(net "P5VC_DIV")
			(options
				(clearance outline)
				(anchor circle)
			)
			(primitives
				(gr_poly
					(pts
						(arc
							(start -0.1778 -0.2794)
							(mid -0.249642 -0.249642)
							(end -0.2794 -0.1778)
						)
						(arc
							(start -0.2794 0.1778)
							(mid -0.249642 0.249642)
							(end -0.1778 0.2794)
						)
						(arc
							(start 0.1778 0.2794)
							(mid 0.249642 0.249642)
							(end 0.2794 0.1778)
						)
						(arc
							(start 0.2794 -0.1778)
							(mid 0.249642 -0.249642)
							(end 0.1778 -0.2794)
						)
					)
					(width 0)
					(fill yes)
				)
			)
		)
		(pad "2" smd custom
			(at 0 0.4445 270)
			(size 0.1397 0.1397)
			(layers "F.Cu" "F.Mask" "F.Paste")
			(net "P5VC_SENSE")
			(options
				(clearance outline)
				(anchor circle)
			)
			(primitives
				(gr_poly
					(pts
						(arc
							(start -0.1778 -0.2794)
							(mid -0.249642 -0.249642)
							(end -0.2794 -0.1778)
						)
						(arc
							(start -0.2794 0.1778)
							(mid -0.249642 0.249642)
							(end -0.1778 0.2794)
						)
						(arc
							(start 0.1778 0.2794)
							(mid 0.249642 0.249642)
							(end 0.2794 0.1778)
						)
						(arc
							(start 0.2794 -0.1778)
							(mid 0.249642 -0.249642)
							(end 0.1778 -0.2794)
						)
					)
					(width 0)
					(fill yes)
				)
			)
		)
	)
	(footprint ""
		(layer "F.Cu")
		(at 219.175584 -188.869828 180)
		(property "Reference" "C163"
			(at 0 0 180)
			(layer "F.SilkS")
			(hide yes)
			(effects
				(font
					(size 1.27 1.27)
				)
			)
		)
		(property "Value" "SC1U25V3KX-1-GP"
			(at 0 -2.8194 180)
			(unlocked yes)
			(layer "F.Fab")
			(hide yes)
			(effects
				(font
					(size 1.016 1.016)
					(thickness 0.1524)
				)
			)
		)
		(property "Device Type" "C603H36"
			(at 0 -4.3434 180)
			(unlocked yes)
			(layer "F.Fab")
			(hide yes)
			(effects
				(font
					(size 1.016 1.016)
					(thickness 0.1524)
				)
			)
		)
		(duplicate_pad_numbers_are_jumpers no)
		(fp_line
			(start 0.508 0)
			(end -0.508 0)
			(stroke
				(width 0.2032)
				(type default)
			)
			(layer "F.SilkS")
		)
		(fp_rect
			(start -0.5842 1.3335)
			(end 0.5842 -1.3335)
			(stroke
				(width 0)
				(type default)
			)
			(fill no)
			(layer "F.CrtYd")
		)
		(fp_rect
			(start -0.5842 1.3335)
			(end 0.5842 -1.3335)
			(stroke
				(width 0)
				(type default)
			)
			(fill no)
			(layer "F.Fab")
		)
		(pad "1" smd custom
			(at 0 -0.762 180)
			(size 0.2159 0.2159)
			(layers "F.Cu" "F.Mask" "F.Paste")
			(net "P12V_HDD3")
			(options
				(clearance outline)
				(anchor circle)
			)
			(primitives
				(gr_poly
					(pts
						(arc
							(start -0.3302 -0.4318)
							(mid -0.402042 -0.402042)
							(end -0.4318 -0.3302)
						)
						(arc
							(start -0.4318 0.3302)
							(mid -0.402042 0.402042)
							(end -0.3302 0.4318)
						)
						(arc
							(start 0.3302 0.4318)
							(mid 0.402042 0.402042)
							(end 0.4318 0.3302)
						)
						(arc
							(start 0.4318 -0.3302)
							(mid 0.402042 -0.402042)
							(end 0.3302 -0.4318)
						)
					)
					(width 0)
					(fill yes)
				)
			)
		)
		(pad "2" smd custom
			(at 0 0.762 180)
			(size 0.2159 0.2159)
			(layers "F.Cu" "F.Mask" "F.Paste")
			(net "GND")
			(options
				(clearance outline)
				(anchor circle)
			)
			(primitives
				(gr_poly
					(pts
						(arc
							(start -0.3302 -0.4318)
							(mid -0.402042 -0.402042)
							(end -0.4318 -0.3302)
						)
						(arc
							(start -0.4318 0.3302)
							(mid -0.402042 0.402042)
							(end -0.3302 0.4318)
						)
						(arc
							(start 0.3302 0.4318)
							(mid 0.402042 0.402042)
							(end 0.4318 0.3302)
						)
						(arc
							(start 0.4318 -0.3302)
							(mid 0.402042 -0.402042)
							(end 0.3302 -0.4318)
						)
					)
					(width 0)
					(fill yes)
				)
			)
		)
	)
	(footprint ""
		(layer "F.Cu")
		(at 56.260492 -72.164956)
		(property "Reference" "R237"
			(at 0 0 0)
			(layer "F.SilkS")
			(hide yes)
			(effects
				(font
					(size 1.27 1.27)
				)
			)
		)
		(property "Value" "220R3F-1-GP"
			(at -0.0254 -2.5146 0)
			(unlocked yes)
			(layer "F.Fab")
			(hide yes)
			(effects
				(font
					(size 1.016 1.016)
					(thickness 0.1524)
				)
			)
		)
		(property "Device Type" "R603H22"
			(at -0.0254 -4.0386 0)
			(unlocked yes)
			(layer "F.Fab")
			(hide yes)
			(effects
				(font
					(size 1.016 1.016)
					(thickness 0.1524)
				)
			)
		)
		(duplicate_pad_numbers_are_jumpers no)
		(fp_line
			(start -0.4826 0)
			(end -0.2032 0)
			(stroke
				(width 0.2032)
				(type default)
			)
			(layer "F.SilkS")
		)
		(fp_line
			(start 0.2032 0)
			(end 0.4826 0)
			(stroke
				(width 0.2032)
				(type default)
			)
			(layer "F.SilkS")
		)
		(fp_rect
			(start -0.5842 1.3335)
			(end 0.5842 -1.3335)
			(stroke
				(width 0)
				(type default)
			)
			(fill no)
			(layer "F.CrtYd")
		)
		(fp_rect
			(start -0.5842 1.3335)
			(end 0.5842 -1.3335)
			(stroke
				(width 0)
				(type default)
			)
			(fill no)
			(layer "F.Fab")
		)
		(pad "1" smd custom
			(at 0 -0.762)
			(size 0.2159 0.2159)
			(layers "F.Cu" "F.Mask" "F.Paste")
			(net "HDD_PRSNT_NET9")
			(options
				(clearance outline)
				(anchor circle)
			)
			(primitives
				(gr_poly
					(pts
						(arc
							(start -0.3302 -0.4318)
							(mid -0.402042 -0.402042)
							(end -0.4318 -0.3302)
						)
						(arc
							(start -0.4318 0.3302)
							(mid -0.402042 0.402042)
							(end -0.3302 0.4318)
						)
						(arc
							(start 0.3302 0.4318)
							(mid 0.402042 0.402042)
							(end 0.4318 0.3302)
						)
						(arc
							(start 0.4318 -0.3302)
							(mid 0.402042 -0.402042)
							(end 0.3302 -0.4318)
						)
					)
					(width 0)
					(fill yes)
				)
			)
		)
		(pad "2" smd custom
			(at 0 0.762)
			(size 0.2159 0.2159)
			(layers "F.Cu" "F.Mask" "F.Paste")
			(net "HDD_PRSNT9")
			(options
				(clearance outline)
				(anchor circle)
			)
			(primitives
				(gr_poly
					(pts
						(arc
							(start -0.3302 -0.4318)
							(mid -0.402042 -0.402042)
							(end -0.4318 -0.3302)
						)
						(arc
							(start -0.4318 0.3302)
							(mid -0.402042 0.402042)
							(end -0.3302 0.4318)
						)
						(arc
							(start 0.3302 0.4318)
							(mid 0.402042 0.402042)
							(end 0.4318 0.3302)
						)
						(arc
							(start 0.4318 -0.3302)
							(mid 0.402042 -0.402042)
							(end 0.3302 -0.4318)
						)
					)
					(width 0)
					(fill yes)
				)
			)
		)
	)
	(footprint ""
		(layer "F.Cu")
		(at 202.564746 -288.8107 -90)
		(property "Reference" "R431"
			(at 0 0 270)
			(layer "F.SilkS")
			(hide yes)
			(effects
				(font
					(size 1.27 1.27)
				)
			)
		)
		(property "Value" "4K7R2J-2-GP"
			(at 0.064008 -3.993896 270)
			(unlocked yes)
			(layer "F.Fab")
			(hide yes)
			(effects
				(font
					(size 1.016 1.016)
					(thickness 0.1524)
				)
			)
		)
		(property "Device Type" "R402H16"
			(at 0.064008 -5.517896 270)
			(unlocked yes)
			(layer "F.Fab")
			(hide yes)
			(effects
				(font
					(size 1.016 1.016)
					(thickness 0.1524)
				)
			)
		)
		(duplicate_pad_numbers_are_jumpers no)
		(fp_line
			(start -0.508 -0.9398)
			(end -0.508 0.9398)
			(stroke
				(width 0.1524)
				(type default)
			)
			(layer "F.SilkS")
		)
		(fp_line
			(start 0.508 -0.9398)
			(end -0.508 -0.9398)
			(stroke
				(width 0.1524)
				(type default)
			)
			(layer "F.SilkS")
		)
		(fp_rect
			(start -0.508 0.9398)
			(end 0.508 -0.9398)
			(stroke
				(width 0)
				(type default)
			)
			(fill no)
			(layer "F.CrtYd")
		)
		(fp_rect
			(start -0.508 0.9398)
			(end 0.508 -0.9398)
			(stroke
				(width 0)
				(type default)
			)
			(fill no)
			(layer "F.Fab")
		)
		(pad "1" smd custom
			(at 0 -0.4445 270)
			(size 0.1397 0.1397)
			(layers "F.Cu" "F.Mask" "F.Paste")
			(net "P3V3")
			(options
				(clearance outline)
				(anchor circle)
			)
			(primitives
				(gr_poly
					(pts
						(arc
							(start -0.1778 -0.2794)
							(mid -0.249642 -0.249642)
							(end -0.2794 -0.1778)
						)
						(arc
							(start -0.2794 0.1778)
							(mid -0.249642 0.249642)
							(end -0.1778 0.2794)
						)
						(arc
							(start 0.1778 0.2794)
							(mid 0.249642 0.249642)
							(end 0.2794 0.1778)
						)
						(arc
							(start 0.2794 -0.1778)
							(mid 0.249642 -0.249642)
							(end 0.1778 -0.2794)
						)
					)
					(width 0)
					(fill yes)
				)
			)
		)
		(pad "2" smd custom
			(at 0 0.4445 270)
			(size 0.1397 0.1397)
			(layers "F.Cu" "F.Mask" "F.Paste")
			(net "SAS2X28_A_HDD2_FLT")
			(options
				(clearance outline)
				(anchor circle)
			)
			(primitives
				(gr_poly
					(pts
						(arc
							(start -0.1778 -0.2794)
							(mid -0.249642 -0.249642)
							(end -0.2794 -0.1778)
						)
						(arc
							(start -0.2794 0.1778)
							(mid -0.249642 0.249642)
							(end -0.1778 0.2794)
						)
						(arc
							(start 0.1778 0.2794)
							(mid 0.249642 0.249642)
							(end 0.2794 0.1778)
						)
						(arc
							(start 0.2794 -0.1778)
							(mid 0.249642 -0.249642)
							(end 0.1778 -0.2794)
						)
					)
					(width 0)
					(fill yes)
				)
			)
		)
	)
	(footprint ""
		(layer "F.Cu")
		(at 221.360746 -346.3417 -90)
		(property "Reference" "R116"
			(at 0 0 270)
			(layer "F.SilkS")
			(hide yes)
			(effects
				(font
					(size 1.27 1.27)
				)
			)
		)
		(property "Value" "0R2J-2-GP"
			(at 0.064008 -3.993896 270)
			(unlocked yes)
			(layer "F.Fab")
			(hide yes)
			(effects
				(font
					(size 1.016 1.016)
					(thickness 0.1524)
				)
			)
		)
		(property "Device Type" "R402H16"
			(at 0.064008 -5.517896 270)
			(unlocked yes)
			(layer "F.Fab")
			(hide yes)
			(effects
				(font
					(size 1.016 1.016)
					(thickness 0.1524)
				)
			)
		)
		(duplicate_pad_numbers_are_jumpers no)
		(fp_line
			(start -0.508 -0.9398)
			(end -0.508 0.9398)
			(stroke
				(width 0.1524)
				(type default)
			)
			(layer "F.SilkS")
		)
		(fp_line
			(start 0.508 -0.9398)
			(end -0.508 -0.9398)
			(stroke
				(width 0.1524)
				(type default)
			)
			(layer "F.SilkS")
		)
		(fp_rect
			(start -0.508 0.9398)
			(end 0.508 -0.9398)
			(stroke
				(width 0)
				(type default)
			)
			(fill no)
			(layer "F.CrtYd")
		)
		(fp_rect
			(start -0.508 0.9398)
			(end 0.508 -0.9398)
			(stroke
				(width 0)
				(type default)
			)
			(fill no)
			(layer "F.Fab")
		)
		(pad "1" smd custom
			(at 0 -0.4445 270)
			(size 0.1397 0.1397)
			(layers "F.Cu" "F.Mask" "F.Paste")
			(net "DRV_ACT_NET1")
			(options
				(clearance outline)
				(anchor circle)
			)
			(primitives
				(gr_poly
					(pts
						(arc
							(start -0.1778 -0.2794)
							(mid -0.249642 -0.249642)
							(end -0.2794 -0.1778)
						)
						(arc
							(start -0.2794 0.1778)
							(mid -0.249642 0.249642)
							(end -0.1778 0.2794)
						)
						(arc
							(start 0.1778 0.2794)
							(mid 0.249642 0.249642)
							(end 0.2794 0.1778)
						)
						(arc
							(start 0.2794 -0.1778)
							(mid 0.249642 -0.249642)
							(end 0.1778 -0.2794)
						)
					)
					(width 0)
					(fill yes)
				)
			)
		)
		(pad "2" smd custom
			(at 0 0.4445 270)
			(size 0.1397 0.1397)
			(layers "F.Cu" "F.Mask" "F.Paste")
			(net "DRIVE_ACT_1")
			(options
				(clearance outline)
				(anchor circle)
			)
			(primitives
				(gr_poly
					(pts
						(arc
							(start -0.1778 -0.2794)
							(mid -0.249642 -0.249642)
							(end -0.2794 -0.1778)
						)
						(arc
							(start -0.2794 0.1778)
							(mid -0.249642 0.249642)
							(end -0.1778 0.2794)
						)
						(arc
							(start 0.1778 0.2794)
							(mid 0.249642 0.249642)
							(end 0.2794 0.1778)
						)
						(arc
							(start 0.2794 -0.1778)
							(mid 0.249642 -0.249642)
							(end 0.1778 -0.2794)
						)
					)
					(width 0)
					(fill yes)
				)
			)
		)
	)
	(footprint ""
		(layer "F.Cu")
		(at 226.9236 -435.9148 -90)
		(property "Reference" "PR54"
			(at 0 0 270)
			(layer "F.SilkS")
			(hide yes)
			(effects
				(font
					(size 1.27 1.27)
				)
			)
		)
		(property "Value" "0R3J-0-U-GP"
			(at -0.0254 -2.5146 270)
			(unlocked yes)
			(layer "F.Fab")
			(hide yes)
			(effects
				(font
					(size 1.016 1.016)
					(thickness 0.1524)
				)
			)
		)
		(property "Device Type" "R603H22"
			(at -0.0254 -4.0386 270)
			(unlocked yes)
			(layer "F.Fab")
			(hide yes)
			(effects
				(font
					(size 1.016 1.016)
					(thickness 0.1524)
				)
			)
		)
		(duplicate_pad_numbers_are_jumpers no)
		(fp_line
			(start -0.4826 0)
			(end -0.2032 0)
			(stroke
				(width 0.2032)
				(type default)
			)
			(layer "F.SilkS")
		)
		(fp_line
			(start 0.2032 0)
			(end 0.4826 0)
			(stroke
				(width 0.2032)
				(type default)
			)
			(layer "F.SilkS")
		)
		(fp_rect
			(start -0.5842 1.3335)
			(end 0.5842 -1.3335)
			(stroke
				(width 0)
				(type default)
			)
			(fill no)
			(layer "F.CrtYd")
		)
		(fp_rect
			(start -0.5842 1.3335)
			(end 0.5842 -1.3335)
			(stroke
				(width 0)
				(type default)
			)
			(fill no)
			(layer "F.Fab")
		)
		(pad "1" smd custom
			(at 0 -0.762 270)
			(size 0.2159 0.2159)
			(layers "F.Cu" "F.Mask" "F.Paste")
			(net "P3V3_LX_COOPER")
			(options
				(clearance outline)
				(anchor circle)
			)
			(primitives
				(gr_poly
					(pts
						(arc
							(start -0.3302 -0.4318)
							(mid -0.402042 -0.402042)
							(end -0.4318 -0.3302)
						)
						(arc
							(start -0.4318 0.3302)
							(mid -0.402042 0.402042)
							(end -0.3302 0.4318)
						)
						(arc
							(start 0.3302 0.4318)
							(mid 0.402042 0.402042)
							(end 0.4318 0.3302)
						)
						(arc
							(start 0.4318 -0.3302)
							(mid 0.402042 -0.402042)
							(end 0.3302 -0.4318)
						)
					)
					(width 0)
					(fill yes)
				)
			)
		)
		(pad "2" smd custom
			(at 0 0.762 270)
			(size 0.2159 0.2159)
			(layers "F.Cu" "F.Mask" "F.Paste")
			(net "P3V3_FB_R")
			(options
				(clearance outline)
				(anchor circle)
			)
			(primitives
				(gr_poly
					(pts
						(arc
							(start -0.3302 -0.4318)
							(mid -0.402042 -0.402042)
							(end -0.4318 -0.3302)
						)
						(arc
							(start -0.4318 0.3302)
							(mid -0.402042 0.402042)
							(end -0.3302 0.4318)
						)
						(arc
							(start 0.3302 0.4318)
							(mid 0.402042 0.402042)
							(end 0.4318 0.3302)
						)
						(arc
							(start 0.4318 -0.3302)
							(mid 0.402042 -0.402042)
							(end 0.3302 -0.4318)
						)
					)
					(width 0)
					(fill yes)
				)
			)
		)
	)
	(footprint ""
		(layer "F.Cu")
		(at 32.384746 -311.432702)
		(property "Reference" "R263"
			(at 0 0 0)
			(layer "F.SilkS")
			(hide yes)
			(effects
				(font
					(size 1.27 1.27)
				)
			)
		)
		(property "Value" "200KR2F-L-GP"
			(at 0.064008 -3.993896 0)
			(unlocked yes)
			(layer "F.Fab")
			(hide yes)
			(effects
				(font
					(size 1.016 1.016)
					(thickness 0.1524)
				)
			)
		)
		(property "Device Type" "R402H16"
			(at 0.064008 -5.517896 0)
			(unlocked yes)
			(layer "F.Fab")
			(hide yes)
			(effects
				(font
					(size 1.016 1.016)
					(thickness 0.1524)
				)
			)
		)
		(duplicate_pad_numbers_are_jumpers no)
		(fp_line
			(start -0.508 -0.9398)
			(end -0.508 0.9398)
			(stroke
				(width 0.1524)
				(type default)
			)
			(layer "F.SilkS")
		)
		(fp_line
			(start 0.508 -0.9398)
			(end -0.508 -0.9398)
			(stroke
				(width 0.1524)
				(type default)
			)
			(layer "F.SilkS")
		)
		(fp_rect
			(start -0.508 0.9398)
			(end 0.508 -0.9398)
			(stroke
				(width 0)
				(type default)
			)
			(fill no)
			(layer "F.CrtYd")
		)
		(fp_rect
			(start -0.508 0.9398)
			(end 0.508 -0.9398)
			(stroke
				(width 0)
				(type default)
			)
			(fill no)
			(layer "F.Fab")
		)
		(pad "1" smd custom
			(at 0 -0.4445)
			(size 0.1397 0.1397)
			(layers "F.Cu" "F.Mask" "F.Paste")
			(net "P12V")
			(options
				(clearance outline)
				(anchor circle)
			)
			(primitives
				(gr_poly
					(pts
						(arc
							(start -0.1778 -0.2794)
							(mid -0.249642 -0.249642)
							(end -0.2794 -0.1778)
						)
						(arc
							(start -0.2794 0.1778)
							(mid -0.249642 0.249642)
							(end -0.1778 0.2794)
						)
						(arc
							(start 0.1778 0.2794)
							(mid 0.249642 0.249642)
							(end 0.2794 0.1778)
						)
						(arc
							(start 0.2794 -0.1778)
							(mid 0.249642 -0.249642)
							(end 0.1778 -0.2794)
						)
					)
					(width 0)
					(fill yes)
				)
			)
		)
		(pad "2" smd custom
			(at 0 0.4445)
			(size 0.1397 0.1397)
			(layers "F.Cu" "F.Mask" "F.Paste")
			(net "SW_HDD11_P")
			(options
				(clearance outline)
				(anchor circle)
			)
			(primitives
				(gr_poly
					(pts
						(arc
							(start -0.1778 -0.2794)
							(mid -0.249642 -0.249642)
							(end -0.2794 -0.1778)
						)
						(arc
							(start -0.2794 0.1778)
							(mid -0.249642 0.249642)
							(end -0.1778 0.2794)
						)
						(arc
							(start 0.1778 0.2794)
							(mid 0.249642 0.249642)
							(end 0.2794 0.1778)
						)
						(arc
							(start 0.2794 -0.1778)
							(mid 0.249642 -0.249642)
							(end 0.1778 -0.2794)
						)
					)
					(width 0)
					(fill yes)
				)
			)
		)
	)
	(footprint ""
		(layer "F.Cu")
		(at 80.898492 -85.499956 -90)
		(property "Reference" "U30"
			(at 0 0 270)
			(layer "F.SilkS")
			(hide yes)
			(effects
				(font
					(size 1.27 1.27)
				)
			)
		)
		(property "Value" "74LVC1G08GW-1-GP"
			(at -2.3368 -8.6868 270)
			(unlocked yes)
			(layer "F.Fab")
			(hide yes)
			(effects
				(font
					(size 1.016 1.016)
					(thickness 0.1524)
				)
			)
		)
		(property "Device Type" "SC70-5H44"
			(at -2.3114 -10.414 270)
			(unlocked yes)
			(layer "F.Fab")
			(hide yes)
			(effects
				(font
					(size 1.016 1.016)
					(thickness 0.1524)
				)
			)
		)
		(duplicate_pad_numbers_are_jumpers no)
		(fp_line
			(start -1.27 1.7018)
			(end -1.27 -1.7018)
			(stroke
				(width 0.1524)
				(type default)
			)
			(layer "F.SilkS")
		)
		(fp_line
			(start 1.27 1.7018)
			(end -1.27 1.7018)
			(stroke
				(width 0.1524)
				(type default)
			)
			(layer "F.SilkS")
		)
		(fp_line
			(start -1.27 -1.7018)
			(end 1.27 -1.7018)
			(stroke
				(width 0.1524)
				(type default)
			)
			(layer "F.SilkS")
		)
		(fp_line
			(start 1.27 -1.7018)
			(end 1.27 1.7018)
			(stroke
				(width 0.1524)
				(type default)
			)
			(layer "F.SilkS")
		)
		(fp_line
			(start 0.6604 -1.8034)
			(end 1.3843 -1.8034)
			(stroke
				(width 0.3302)
				(type default)
			)
			(layer "F.SilkS")
		)
		(fp_line
			(start 1.3843 -1.8034)
			(end 1.3843 -1.1176)
			(stroke
				(width 0.3302)
				(type default)
			)
			(layer "F.SilkS")
		)
		(fp_rect
			(start -1.524 1.9558)
			(end 1.524 -1.9558)
			(stroke
				(width 0)
				(type default)
			)
			(fill no)
			(layer "F.CrtYd")
		)
		(fp_poly
			(pts
				(xy -1.524 -1.9558) (xy 1.524 -1.9558) (xy 1.524 1.9558) (xy -1.524 1.9558)
			)
			(stroke
				(width 0)
				(type default)
			)
			(fill no)
			(layer "F.Fab")
		)
		(pad "1" smd rect
			(at 0.65024 -0.8255 270)
			(size 0.4064 1.2192)
			(layers "F.Cu" "F.Mask" "F.Paste")
			(net "SAS_EXP_B_PWR9")
		)
		(pad "2" smd rect
			(at 0 -0.8255 270)
			(size 0.4064 1.2192)
			(layers "F.Cu" "F.Mask" "F.Paste")
			(net "SAS_EXP_A_PWR9")
		)
		(pad "3" smd rect
			(at -0.65024 -0.8255 270)
			(size 0.4064 1.2192)
			(layers "F.Cu" "F.Mask" "F.Paste")
			(net "GND")
		)
		(pad "4" smd rect
			(at -0.65024 0.8255 270)
			(size 0.4064 1.2192)
			(layers "F.Cu" "F.Mask" "F.Paste")
			(net "DRIVE_PWR9")
		)
		(pad "5" smd rect
			(at 0.65024 0.8255 270)
			(size 0.4064 1.2192)
			(layers "F.Cu" "F.Mask" "F.Paste")
			(net "P3V3")
		)
	)
	(footprint ""
		(layer "F.Cu")
		(at 29.590746 -311.305702)
		(property "Reference" "R266"
			(at 0 0 0)
			(layer "F.SilkS")
			(hide yes)
			(effects
				(font
					(size 1.27 1.27)
				)
			)
		)
		(property "Value" "0R2J-2-GP"
			(at 0.064008 -3.993896 0)
			(unlocked yes)
			(layer "F.Fab")
			(hide yes)
			(effects
				(font
					(size 1.016 1.016)
					(thickness 0.1524)
				)
			)
		)
		(property "Device Type" "R402H16"
			(at 0.064008 -5.517896 0)
			(unlocked yes)
			(layer "F.Fab")
			(hide yes)
			(effects
				(font
					(size 1.016 1.016)
					(thickness 0.1524)
				)
			)
		)
		(duplicate_pad_numbers_are_jumpers no)
		(fp_line
			(start -0.508 -0.9398)
			(end -0.508 0.9398)
			(stroke
				(width 0.1524)
				(type default)
			)
			(layer "F.SilkS")
		)
		(fp_line
			(start 0.508 -0.9398)
			(end -0.508 -0.9398)
			(stroke
				(width 0.1524)
				(type default)
			)
			(layer "F.SilkS")
		)
		(fp_rect
			(start -0.508 0.9398)
			(end 0.508 -0.9398)
			(stroke
				(width 0)
				(type default)
			)
			(fill no)
			(layer "F.CrtYd")
		)
		(fp_rect
			(start -0.508 0.9398)
			(end 0.508 -0.9398)
			(stroke
				(width 0)
				(type default)
			)
			(fill no)
			(layer "F.Fab")
		)
		(pad "1" smd custom
			(at 0 -0.4445)
			(size 0.1397 0.1397)
			(layers "F.Cu" "F.Mask" "F.Paste")
			(net "SW_PWR_HDD11")
			(options
				(clearance outline)
				(anchor circle)
			)
			(primitives
				(gr_poly
					(pts
						(arc
							(start -0.1778 -0.2794)
							(mid -0.249642 -0.249642)
							(end -0.2794 -0.1778)
						)
						(arc
							(start -0.2794 0.1778)
							(mid -0.249642 0.249642)
							(end -0.1778 0.2794)
						)
						(arc
							(start 0.1778 0.2794)
							(mid 0.249642 0.249642)
							(end 0.2794 0.1778)
						)
						(arc
							(start 0.2794 -0.1778)
							(mid 0.249642 -0.249642)
							(end 0.1778 -0.2794)
						)
					)
					(width 0)
					(fill yes)
				)
			)
		)
		(pad "2" smd custom
			(at 0 0.4445)
			(size 0.1397 0.1397)
			(layers "F.Cu" "F.Mask" "F.Paste")
			(net "SW_PWR_R_HDD11")
			(options
				(clearance outline)
				(anchor circle)
			)
			(primitives
				(gr_poly
					(pts
						(arc
							(start -0.1778 -0.2794)
							(mid -0.249642 -0.249642)
							(end -0.2794 -0.1778)
						)
						(arc
							(start -0.2794 0.1778)
							(mid -0.249642 0.249642)
							(end -0.1778 0.2794)
						)
						(arc
							(start 0.1778 0.2794)
							(mid 0.249642 0.249642)
							(end 0.2794 0.1778)
						)
						(arc
							(start 0.2794 -0.1778)
							(mid 0.249642 -0.249642)
							(end 0.1778 -0.2794)
						)
					)
					(width 0)
					(fill yes)
				)
			)
		)
	)
	(footprint ""
		(layer "F.Cu")
		(at 58.165492 -87.912956 180)
		(property "Reference" "C257"
			(at 0 0 180)
			(layer "F.SilkS")
			(hide yes)
			(effects
				(font
					(size 1.27 1.27)
				)
			)
		)
		(property "Value" "SC10U25V6KX-1GP"
			(at -0.0762 -5.1308 180)
			(unlocked yes)
			(layer "F.Fab")
			(hide yes)
			(effects
				(font
					(size 1.016 1.016)
					(thickness 0.1524)
				)
			)
		)
		(property "Device Type" "C1206H71"
			(at -0.127 -6.6548 180)
			(unlocked yes)
			(layer "F.Fab")
			(hide yes)
			(effects
				(font
					(size 1.016 1.016)
					(thickness 0.1524)
				)
			)
		)
		(duplicate_pad_numbers_are_jumpers no)
		(fp_line
			(start 1.016 2.2352)
			(end -1.016 2.2352)
			(stroke
				(width 0.1524)
				(type default)
			)
			(layer "F.SilkS")
		)
		(fp_line
			(start 1.016 0.8382)
			(end 1.016 2.2352)
			(stroke
				(width 0.1524)
				(type default)
			)
			(layer "F.SilkS")
		)
		(fp_line
			(start 1.016 -2.2352)
			(end 1.016 -0.8382)
			(stroke
				(width 0.1524)
				(type default)
			)
			(layer "F.SilkS")
		)
		(fp_line
			(start -1.016 2.2352)
			(end -1.016 0.8382)
			(stroke
				(width 0.1524)
				(type default)
			)
			(layer "F.SilkS")
		)
		(fp_line
			(start -1.016 -0.8382)
			(end -1.016 -2.2352)
			(stroke
				(width 0.1524)
				(type default)
			)
			(layer "F.SilkS")
		)
		(fp_line
			(start -1.016 -2.2352)
			(end 1.016 -2.2352)
			(stroke
				(width 0.1524)
				(type default)
			)
			(layer "F.SilkS")
		)
		(fp_rect
			(start -1.0922 2.3114)
			(end 1.0922 -2.3114)
			(stroke
				(width 0)
				(type default)
			)
			(fill no)
			(layer "F.CrtYd")
		)
		(fp_poly
			(pts
				(xy 1.0922 -2.3114) (xy 1.0922 2.3114) (xy -1.0922 2.3114) (xy -1.0922 -2.3114)
			)
			(stroke
				(width 0)
				(type default)
			)
			(fill no)
			(layer "F.Fab")
		)
		(pad "1" smd rect
			(at 0 -1.397 180)
			(size 1.651 1.27)
			(layers "F.Cu" "F.Mask" "F.Paste")
			(net "P12V_HDD9")
		)
		(pad "2" smd rect
			(at 0 1.397 180)
			(size 1.651 1.27)
			(layers "F.Cu" "F.Mask" "F.Paste")
			(net "GND")
		)
	)
	(footprint ""
		(layer "F.Cu")
		(at 194.322446 -458.504036 -90)
		(property "Reference" "U50"
			(at 0 0 270)
			(layer "F.SilkS")
			(hide yes)
			(effects
				(font
					(size 1.27 1.27)
				)
			)
		)
		(property "Value" "24LC64T-I-GP"
			(at 0 -12.1412 270)
			(unlocked yes)
			(layer "F.Fab")
			(hide yes)
			(effects
				(font
					(size 1.016 1.016)
					(thickness 0.1524)
				)
			)
		)
		(property "Device Type" "SSOIC8-1H44"
			(at 0 -13.6652 270)
			(unlocked yes)
			(layer "F.Fab")
			(hide yes)
			(effects
				(font
					(size 1.016 1.016)
					(thickness 0.1524)
				)
			)
		)
		(duplicate_pad_numbers_are_jumpers no)
		(fp_line
			(start -1.778 1.778)
			(end -1.778 3.81)
			(stroke
				(width 0.508)
				(type default)
			)
			(layer "F.SilkS")
		)
		(fp_line
			(start 1.397 1.778)
			(end -1.778 1.778)
			(stroke
				(width 0.2032)
				(type default)
			)
			(layer "F.SilkS")
		)
		(fp_line
			(start -1.143 0)
			(end -1.778 0.635)
			(stroke
				(width 0.2032)
				(type default)
			)
			(layer "F.SilkS")
		)
		(fp_line
			(start -1.143 0)
			(end -1.778 -0.635)
			(stroke
				(width 0.2032)
				(type default)
			)
			(layer "F.SilkS")
		)
		(fp_line
			(start -1.778 -1.778)
			(end -1.778 2.667)
			(stroke
				(width 0.2032)
				(type default)
			)
			(layer "F.SilkS")
		)
		(fp_line
			(start -1.778 -1.778)
			(end 1.397 -1.778)
			(stroke
				(width 0.2032)
				(type default)
			)
			(layer "F.SilkS")
		)
		(fp_line
			(start 1.397 -1.778)
			(end 1.397 1.778)
			(stroke
				(width 0.2032)
				(type default)
			)
			(layer "F.SilkS")
		)
		(fp_poly
			(pts
				(xy -2.032 3.81) (xy 2.032 3.81) (xy 2.032 -3.81) (xy -2.032 -3.81)
			)
			(stroke
				(width 0)
				(type default)
			)
			(fill no)
			(layer "F.CrtYd")
		)
		(fp_poly
			(pts
				(xy -2.032 -3.81) (xy 2.032 -3.81) (xy 2.032 3.81) (xy -2.032 3.81)
			)
			(stroke
				(width 0)
				(type default)
			)
			(fill no)
			(layer "F.Fab")
		)
		(pad "1" smd rect
			(at -0.97536 2.8194 270)
			(size 0.3556 1.524)
			(layers "F.Cu" "F.Mask" "F.Paste")
			(net "EEPROM_A0")
		)
		(pad "2" smd rect
			(at -0.32512 2.8194 270)
			(size 0.3556 1.524)
			(layers "F.Cu" "F.Mask" "F.Paste")
			(net "EEPROM_A1")
		)
		(pad "3" smd rect
			(at 0.32512 2.8194 270)
			(size 0.3556 1.524)
			(layers "F.Cu" "F.Mask" "F.Paste")
			(net "EEPROM_A2")
		)
		(pad "4" smd rect
			(at 0.97536 2.8194 270)
			(size 0.3556 1.524)
			(layers "F.Cu" "F.Mask" "F.Paste")
			(net "GND")
		)
		(pad "5" smd rect
			(at 0.97536 -2.8194 270)
			(size 0.3556 1.524)
			(layers "F.Cu" "F.Mask" "F.Paste")
			(net "EEPROM_SDA")
		)
		(pad "6" smd rect
			(at 0.32512 -2.8194 270)
			(size 0.3556 1.524)
			(layers "F.Cu" "F.Mask" "F.Paste")
			(net "EEPROM_SCL")
		)
		(pad "7" smd rect
			(at -0.32512 -2.8194 270)
			(size 0.3556 1.524)
			(layers "F.Cu" "F.Mask" "F.Paste")
			(net "EEPROM_WP")
		)
		(pad "8" smd rect
			(at -0.97536 -2.8194 270)
			(size 0.3556 1.524)
			(layers "F.Cu" "F.Mask" "F.Paste")
			(net "P3V3")
		)
	)
	(footprint ""
		(layer "F.Cu")
		(at 237.692946 -42.5958 90)
		(property "Reference" "Q38"
			(at 0 0 90)
			(layer "F.SilkS")
			(hide yes)
			(effects
				(font
					(size 1.27 1.27)
				)
			)
		)
		(property "Value" "PMBS3904-1-GP"
			(at 0 -9.0932 90)
			(unlocked yes)
			(layer "F.Fab")
			(hide yes)
			(effects
				(font
					(size 1.016 1.016)
					(thickness 0.1524)
				)
			)
		)
		(property "Device Type" "SOT-23-10H44"
			(at 0 -10.6172 90)
			(unlocked yes)
			(layer "F.Fab")
			(hide yes)
			(effects
				(font
					(size 1.016 1.016)
					(thickness 0.1524)
				)
			)
		)
		(duplicate_pad_numbers_are_jumpers no)
		(fp_line
			(start 1.651 -1.778)
			(end -1.651 -1.778)
			(stroke
				(width 0.1524)
				(type default)
			)
			(layer "F.SilkS")
		)
		(fp_line
			(start -1.651 -1.778)
			(end -1.651 1.778)
			(stroke
				(width 0.1524)
				(type default)
			)
			(layer "F.SilkS")
		)
		(fp_line
			(start 1.651 1.778)
			(end 1.651 -1.778)
			(stroke
				(width 0.1524)
				(type default)
			)
			(layer "F.SilkS")
		)
		(fp_line
			(start -1.651 1.778)
			(end 1.651 1.778)
			(stroke
				(width 0.1524)
				(type default)
			)
			(layer "F.SilkS")
		)
		(fp_line
			(start -0.9906 1.86309)
			(end -0.701294 2.15265)
			(stroke
				(width 0.0127)
				(type default)
			)
			(layer "F.SilkS")
		)
		(fp_line
			(start -0.994156 1.8669)
			(end -0.987044 1.8669)
			(stroke
				(width 0.0127)
				(type default)
			)
			(layer "F.SilkS")
		)
		(fp_line
			(start -1.003808 1.876552)
			(end -0.977646 1.876552)
			(stroke
				(width 0.0127)
				(type default)
			)
			(layer "F.SilkS")
		)
		(fp_line
			(start -0.635 1.8796)
			(end -1.7526 1.8796)
			(stroke
				(width 0.3302)
				(type default)
			)
			(layer "F.SilkS")
		)
		(fp_line
			(start -1.7526 1.8796)
			(end -1.7526 0.9906)
			(stroke
				(width 0.3302)
				(type default)
			)
			(layer "F.SilkS")
		)
		(fp_line
			(start -1.013206 1.88595)
			(end -0.967994 1.88595)
			(stroke
				(width 0.0127)
				(type default)
			)
			(layer "F.SilkS")
		)
		(fp_line
			(start -1.022858 1.895602)
			(end -0.958596 1.895602)
			(stroke
				(width 0.0127)
				(type default)
			)
			(layer "F.SilkS")
		)
		(fp_line
			(start -1.032256 1.905)
			(end -0.948944 1.905)
			(stroke
				(width 0.0127)
				(type default)
			)
			(layer "F.SilkS")
		)
		(fp_line
			(start -1.041908 1.914652)
			(end -0.939546 1.914652)
			(stroke
				(width 0.0127)
				(type default)
			)
			(layer "F.SilkS")
		)
		(fp_line
			(start -1.051306 1.92405)
			(end -0.929894 1.92405)
			(stroke
				(width 0.0127)
				(type default)
			)
			(layer "F.SilkS")
		)
		(fp_line
			(start -1.060958 1.933702)
			(end -0.920496 1.933702)
			(stroke
				(width 0.0127)
				(type default)
			)
			(layer "F.SilkS")
		)
		(fp_line
			(start -1.070356 1.9431)
			(end -0.910844 1.9431)
			(stroke
				(width 0.0127)
				(type default)
			)
			(layer "F.SilkS")
		)
		(fp_line
			(start -1.080008 1.952752)
			(end -0.901446 1.952752)
			(stroke
				(width 0.0127)
				(type default)
			)
			(layer "F.SilkS")
		)
		(fp_line
			(start -1.089406 1.96215)
			(end -0.891794 1.96215)
			(stroke
				(width 0.0127)
				(type default)
			)
			(layer "F.SilkS")
		)
		(fp_line
			(start -1.099058 1.971802)
			(end -0.882396 1.971802)
			(stroke
				(width 0.0127)
				(type default)
			)
			(layer "F.SilkS")
		)
		(fp_line
			(start -1.108456 1.9812)
			(end -0.872744 1.9812)
			(stroke
				(width 0.0127)
				(type default)
			)
			(layer "F.SilkS")
		)
		(fp_line
			(start -1.118108 1.990852)
			(end -0.863346 1.990852)
			(stroke
				(width 0.0127)
				(type default)
			)
			(layer "F.SilkS")
		)
		(fp_line
			(start -1.127506 2.00025)
			(end -0.853694 2.00025)
			(stroke
				(width 0.0127)
				(type default)
			)
			(layer "F.SilkS")
		)
		(fp_line
			(start -1.137158 2.009902)
			(end -0.844296 2.009902)
			(stroke
				(width 0.0127)
				(type default)
			)
			(layer "F.SilkS")
		)
		(fp_line
			(start -1.146556 2.0193)
			(end -0.834644 2.0193)
			(stroke
				(width 0.0127)
				(type default)
			)
			(layer "F.SilkS")
		)
		(fp_line
			(start -1.156208 2.028952)
			(end -0.825246 2.028952)
			(stroke
				(width 0.0127)
				(type default)
			)
			(layer "F.SilkS")
		)
		(fp_line
			(start -1.165606 2.03835)
			(end -0.815594 2.03835)
			(stroke
				(width 0.0127)
				(type default)
			)
			(layer "F.SilkS")
		)
		(fp_line
			(start -1.175258 2.048002)
			(end -0.806196 2.048002)
			(stroke
				(width 0.0127)
				(type default)
			)
			(layer "F.SilkS")
		)
		(fp_line
			(start -1.184656 2.0574)
			(end -0.796544 2.0574)
			(stroke
				(width 0.0127)
				(type default)
			)
			(layer "F.SilkS")
		)
		(fp_line
			(start -1.194308 2.067052)
			(end -0.787146 2.067052)
			(stroke
				(width 0.0127)
				(type default)
			)
			(layer "F.SilkS")
		)
		(fp_line
			(start -1.203706 2.07645)
			(end -0.777494 2.07645)
			(stroke
				(width 0.0127)
				(type default)
			)
			(layer "F.SilkS")
		)
		(fp_line
			(start -1.213358 2.086102)
			(end -0.768096 2.086102)
			(stroke
				(width 0.0127)
				(type default)
			)
			(layer "F.SilkS")
		)
		(fp_line
			(start -1.222756 2.0955)
			(end -0.758444 2.0955)
			(stroke
				(width 0.0127)
				(type default)
			)
			(layer "F.SilkS")
		)
		(fp_line
			(start -1.232408 2.105152)
			(end -0.749046 2.105152)
			(stroke
				(width 0.0127)
				(type default)
			)
			(layer "F.SilkS")
		)
		(fp_line
			(start -1.241806 2.11455)
			(end -0.739394 2.11455)
			(stroke
				(width 0.0127)
				(type default)
			)
			(layer "F.SilkS")
		)
		(fp_line
			(start -1.251458 2.124202)
			(end -0.729996 2.124202)
			(stroke
				(width 0.0127)
				(type default)
			)
			(layer "F.SilkS")
		)
		(fp_line
			(start -1.260856 2.1336)
			(end -0.720344 2.1336)
			(stroke
				(width 0.0127)
				(type default)
			)
			(layer "F.SilkS")
		)
		(fp_line
			(start -0.719074 2.145538)
			(end -1.265936 2.14122)
			(stroke
				(width 0.0127)
				(type default)
			)
			(layer "F.SilkS")
		)
		(fp_line
			(start -1.279398 2.152142)
			(end -0.9906 1.86309)
			(stroke
				(width 0.0127)
				(type default)
			)
			(layer "F.SilkS")
		)
		(fp_line
			(start -0.71628 2.15265)
			(end -1.26492 2.15265)
			(stroke
				(width 0.0127)
				(type default)
			)
			(layer "F.SilkS")
		)
		(fp_line
			(start -1.279144 2.15265)
			(end -0.701294 2.15265)
			(stroke
				(width 0.0127)
				(type default)
			)
			(layer "F.SilkS")
		)
		(fp_poly
			(pts
				(xy -1.285748 2.159) (xy -1.285748 1.8796) (xy -1.778 1.8796) (xy -1.778 -1.8796) (xy 1.778 -1.8796)
				(xy 1.778 1.8796) (xy -0.694944 1.8796) (xy -0.694944 2.159)
			)
			(stroke
				(width 0)
				(type default)
			)
			(fill no)
			(layer "F.CrtYd")
		)
		(fp_poly
			(pts
				(xy -1.285748 2.159) (xy -1.285748 1.8796) (xy -1.778 1.8796) (xy -1.778 -1.8796) (xy 1.778 -1.8796)
				(xy 1.778 1.8796) (xy -0.694944 1.8796) (xy -0.694944 2.159)
			)
			(stroke
				(width 0)
				(type default)
			)
			(fill no)
			(layer "F.Fab")
		)
		(pad "1" smd rect
			(at -0.98425 0.9525 90)
			(size 0.762 1.143)
			(layers "F.Cu" "F.Mask" "F.Paste")
			(net "FLT_HDD4_B")
		)
		(pad "2" smd rect
			(at 0.98425 0.9525 90)
			(size 0.762 1.143)
			(layers "F.Cu" "F.Mask" "F.Paste")
			(net "GND")
		)
		(pad "3" smd rect
			(at 0 -0.9525 90)
			(size 0.762 1.143)
			(layers "F.Cu" "F.Mask" "F.Paste")
			(net "DRIVE_ACT_4")
		)
	)
	(footprint ""
		(layer "F.Cu")
		(at 27.355546 -383.7813)
		(property "Reference" "TP1"
			(at 0 0 0)
			(layer "F.SilkS")
			(hide yes)
			(effects
				(font
					(size 1.27 1.27)
				)
			)
		)
		(property "Value" "TPAD32-GP"
			(at 0 -3.166364 0)
			(unlocked yes)
			(layer "F.Fab")
			(hide yes)
			(effects
				(font
					(size 1.016 1.016)
					(thickness 0.1524)
				)
			)
		)
		(property "Device Type" "TPAD32"
			(at 0 -4.690618 0)
			(unlocked yes)
			(layer "F.Fab")
			(hide yes)
			(effects
				(font
					(size 1.016 1.016)
					(thickness 0.1524)
				)
			)
		)
		(duplicate_pad_numbers_are_jumpers no)
		(fp_poly
			(pts
				(arc
					(start 0.4064 0)
					(mid -0.4064 0)
					(end 0.4064 0)
				)
			)
			(stroke
				(width 0)
				(type default)
			)
			(fill no)
			(layer "F.CrtYd")
		)
		(fp_poly
			(pts
				(arc
					(start 0.7112 0)
					(mid -0.7112 0)
					(end 0.7112 0)
				)
			)
			(stroke
				(width 0)
				(type default)
			)
			(fill no)
			(layer "F.Fab")
		)
		(pad "1" smd circle
			(at 0 0)
			(size 0.8128 0.8128)
			(layers "F.Cu" "F.Mask" "F.Paste")
			(net "I2C_B_TMP1_ALERT")
		)
	)
	(footprint ""
		(layer "F.Cu")
		(at 252.499876 -271.499838)
		(property "Reference" "H14"
			(at 0 0 0)
			(layer "F.SilkS")
			(hide yes)
			(effects
				(font
					(size 1.27 1.27)
				)
			)
		)
		(property "Value" "HOLE315R140"
			(at 0 -7.5692 0)
			(unlocked yes)
			(layer "F.Fab")
			(hide yes)
			(effects
				(font
					(size 1.016 1.016)
					(thickness 0.1524)
				)
			)
		)
		(property "Device Type" "HOLE315R140"
			(at 0 -9.0932 0)
			(unlocked yes)
			(layer "F.Fab")
			(hide yes)
			(effects
				(font
					(size 1.016 1.016)
					(thickness 0.1524)
				)
			)
		)
		(duplicate_pad_numbers_are_jumpers no)
		(fp_poly
			(pts
				(arc
					(start 4.3053 0)
					(mid -4.3053 0)
					(end 4.3053 0)
				)
			)
			(stroke
				(width 0)
				(type default)
			)
			(fill no)
			(layer "F.CrtYd")
		)
		(fp_poly
			(pts
				(arc
					(start 4.3053 0)
					(mid -4.3053 0)
					(end 4.3053 0)
				)
			)
			(stroke
				(width 0)
				(type default)
			)
			(fill no)
			(layer "F.Fab")
		)
		(pad "1" thru_hole circle
			(at 0.00127 0.00127)
			(size 8.001 8.001)
			(drill 3.556)
			(layers "*.Cu" "*.Mask")
			(remove_unused_layers no)
			(net "GND")
			(clearance -1.7145)
			(thermal_gap 0.3048)
			(padstack
				(mode front_inner_back)
				(layer "Inner"
					(shape circle)
					(size 3.9624 3.9624)
					(clearance 0.3048)
				)
				(layer "B.Cu"
					(shape circle)
					(size 8.001 8.001)
					(clearance -1.7145)
				)
			)
		)
	)
	(footprint ""
		(layer "F.Cu")
		(at 97.789746 -6.6167 90)
		(property "Reference" "R307"
			(at 0 0 90)
			(layer "F.SilkS")
			(hide yes)
			(effects
				(font
					(size 1.27 1.27)
				)
			)
		)
		(property "Value" "200KR2F-L-GP"
			(at 0.064008 -3.993896 90)
			(unlocked yes)
			(layer "F.Fab")
			(hide yes)
			(effects
				(font
					(size 1.016 1.016)
					(thickness 0.1524)
				)
			)
		)
		(property "Device Type" "R402H16"
			(at 0.064008 -5.517896 90)
			(unlocked yes)
			(layer "F.Fab")
			(hide yes)
			(effects
				(font
					(size 1.016 1.016)
					(thickness 0.1524)
				)
			)
		)
		(duplicate_pad_numbers_are_jumpers no)
		(fp_line
			(start 0.508 -0.9398)
			(end -0.508 -0.9398)
			(stroke
				(width 0.1524)
				(type default)
			)
			(layer "F.SilkS")
		)
		(fp_line
			(start -0.508 -0.9398)
			(end -0.508 0.9398)
			(stroke
				(width 0.1524)
				(type default)
			)
			(layer "F.SilkS")
		)
		(fp_rect
			(start -0.508 0.9398)
			(end 0.508 -0.9398)
			(stroke
				(width 0)
				(type default)
			)
			(fill no)
			(layer "F.CrtYd")
		)
		(fp_rect
			(start -0.508 0.9398)
			(end 0.508 -0.9398)
			(stroke
				(width 0)
				(type default)
			)
			(fill no)
			(layer "F.Fab")
		)
		(pad "1" smd custom
			(at 0 -0.4445 90)
			(size 0.1397 0.1397)
			(layers "F.Cu" "F.Mask" "F.Paste")
			(net "P12V")
			(options
				(clearance outline)
				(anchor circle)
			)
			(primitives
				(gr_poly
					(pts
						(arc
							(start -0.1778 -0.2794)
							(mid -0.249642 -0.249642)
							(end -0.2794 -0.1778)
						)
						(arc
							(start -0.2794 0.1778)
							(mid -0.249642 0.249642)
							(end -0.1778 0.2794)
						)
						(arc
							(start 0.1778 0.2794)
							(mid 0.249642 0.249642)
							(end 0.2794 0.1778)
						)
						(arc
							(start 0.2794 -0.1778)
							(mid 0.249642 -0.249642)
							(end 0.1778 -0.2794)
						)
					)
					(width 0)
					(fill yes)
				)
			)
		)
		(pad "2" smd custom
			(at 0 0.4445 90)
			(size 0.1397 0.1397)
			(layers "F.Cu" "F.Mask" "F.Paste")
			(net "SW_HDD14_P")
			(options
				(clearance outline)
				(anchor circle)
			)
			(primitives
				(gr_poly
					(pts
						(arc
							(start -0.1778 -0.2794)
							(mid -0.249642 -0.249642)
							(end -0.2794 -0.1778)
						)
						(arc
							(start -0.2794 0.1778)
							(mid -0.249642 0.249642)
							(end -0.1778 0.2794)
						)
						(arc
							(start 0.1778 0.2794)
							(mid 0.249642 0.249642)
							(end 0.2794 0.1778)
						)
						(arc
							(start 0.2794 -0.1778)
							(mid 0.249642 -0.249642)
							(end 0.1778 -0.2794)
						)
					)
					(width 0)
					(fill yes)
				)
			)
		)
	)
	(footprint ""
		(layer "F.Cu")
		(at 78.358746 -189.4967 -90)
		(property "Reference" "R225"
			(at 0 0 270)
			(layer "F.SilkS")
			(hide yes)
			(effects
				(font
					(size 1.27 1.27)
				)
			)
		)
		(property "Value" "0R2J-2-GP"
			(at 0.064008 -3.993896 270)
			(unlocked yes)
			(layer "F.Fab")
			(hide yes)
			(effects
				(font
					(size 1.016 1.016)
					(thickness 0.1524)
				)
			)
		)
		(property "Device Type" "R402H16"
			(at 0.064008 -5.517896 270)
			(unlocked yes)
			(layer "F.Fab")
			(hide yes)
			(effects
				(font
					(size 1.016 1.016)
					(thickness 0.1524)
				)
			)
		)
		(duplicate_pad_numbers_are_jumpers no)
		(fp_line
			(start -0.508 -0.9398)
			(end -0.508 0.9398)
			(stroke
				(width 0.1524)
				(type default)
			)
			(layer "F.SilkS")
		)
		(fp_line
			(start 0.508 -0.9398)
			(end -0.508 -0.9398)
			(stroke
				(width 0.1524)
				(type default)
			)
			(layer "F.SilkS")
		)
		(fp_rect
			(start -0.508 0.9398)
			(end 0.508 -0.9398)
			(stroke
				(width 0)
				(type default)
			)
			(fill no)
			(layer "F.CrtYd")
		)
		(fp_rect
			(start -0.508 0.9398)
			(end 0.508 -0.9398)
			(stroke
				(width 0)
				(type default)
			)
			(fill no)
			(layer "F.Fab")
		)
		(pad "1" smd custom
			(at 0 -0.4445 270)
			(size 0.1397 0.1397)
			(layers "F.Cu" "F.Mask" "F.Paste")
			(net "DRIVE_PWR8")
			(options
				(clearance outline)
				(anchor circle)
			)
			(primitives
				(gr_poly
					(pts
						(arc
							(start -0.1778 -0.2794)
							(mid -0.249642 -0.249642)
							(end -0.2794 -0.1778)
						)
						(arc
							(start -0.2794 0.1778)
							(mid -0.249642 0.249642)
							(end -0.1778 0.2794)
						)
						(arc
							(start 0.1778 0.2794)
							(mid 0.249642 0.249642)
							(end 0.2794 0.1778)
						)
						(arc
							(start 0.2794 -0.1778)
							(mid 0.249642 -0.249642)
							(end 0.1778 -0.2794)
						)
					)
					(width 0)
					(fill yes)
				)
			)
		)
		(pad "2" smd custom
			(at 0 0.4445 270)
			(size 0.1397 0.1397)
			(layers "F.Cu" "F.Mask" "F.Paste")
			(net "SW_PWR_HDD8")
			(options
				(clearance outline)
				(anchor circle)
			)
			(primitives
				(gr_poly
					(pts
						(arc
							(start -0.1778 -0.2794)
							(mid -0.249642 -0.249642)
							(end -0.2794 -0.1778)
						)
						(arc
							(start -0.2794 0.1778)
							(mid -0.249642 0.249642)
							(end -0.1778 0.2794)
						)
						(arc
							(start 0.1778 0.2794)
							(mid 0.249642 0.249642)
							(end 0.2794 0.1778)
						)
						(arc
							(start 0.2794 -0.1778)
							(mid 0.249642 -0.249642)
							(end 0.1778 -0.2794)
						)
					)
					(width 0)
					(fill yes)
				)
			)
		)
	)
	(footprint ""
		(layer "F.Cu")
		(at 30.606746 -285.7627 90)
		(property "Reference" "R207"
			(at 0 0 90)
			(layer "F.SilkS")
			(hide yes)
			(effects
				(font
					(size 1.27 1.27)
				)
			)
		)
		(property "Value" "200KR2F-L-GP"
			(at 0.064008 -3.993896 90)
			(unlocked yes)
			(layer "F.Fab")
			(hide yes)
			(effects
				(font
					(size 1.016 1.016)
					(thickness 0.1524)
				)
			)
		)
		(property "Device Type" "R402H16"
			(at 0.064008 -5.517896 90)
			(unlocked yes)
			(layer "F.Fab")
			(hide yes)
			(effects
				(font
					(size 1.016 1.016)
					(thickness 0.1524)
				)
			)
		)
		(duplicate_pad_numbers_are_jumpers no)
		(fp_line
			(start 0.508 -0.9398)
			(end -0.508 -0.9398)
			(stroke
				(width 0.1524)
				(type default)
			)
			(layer "F.SilkS")
		)
		(fp_line
			(start -0.508 -0.9398)
			(end -0.508 0.9398)
			(stroke
				(width 0.1524)
				(type default)
			)
			(layer "F.SilkS")
		)
		(fp_rect
			(start -0.508 0.9398)
			(end 0.508 -0.9398)
			(stroke
				(width 0)
				(type default)
			)
			(fill no)
			(layer "F.CrtYd")
		)
		(fp_rect
			(start -0.508 0.9398)
			(end 0.508 -0.9398)
			(stroke
				(width 0)
				(type default)
			)
			(fill no)
			(layer "F.Fab")
		)
		(pad "1" smd custom
			(at 0 -0.4445 90)
			(size 0.1397 0.1397)
			(layers "F.Cu" "F.Mask" "F.Paste")
			(net "P12V")
			(options
				(clearance outline)
				(anchor circle)
			)
			(primitives
				(gr_poly
					(pts
						(arc
							(start -0.1778 -0.2794)
							(mid -0.249642 -0.249642)
							(end -0.2794 -0.1778)
						)
						(arc
							(start -0.2794 0.1778)
							(mid -0.249642 0.249642)
							(end -0.1778 0.2794)
						)
						(arc
							(start 0.1778 0.2794)
							(mid 0.249642 0.249642)
							(end 0.2794 0.1778)
						)
						(arc
							(start 0.2794 -0.1778)
							(mid 0.249642 -0.249642)
							(end 0.1778 -0.2794)
						)
					)
					(width 0)
					(fill yes)
				)
			)
		)
		(pad "2" smd custom
			(at 0 0.4445 90)
			(size 0.1397 0.1397)
			(layers "F.Cu" "F.Mask" "F.Paste")
			(net "SW_HDD7_P")
			(options
				(clearance outline)
				(anchor circle)
			)
			(primitives
				(gr_poly
					(pts
						(arc
							(start -0.1778 -0.2794)
							(mid -0.249642 -0.249642)
							(end -0.2794 -0.1778)
						)
						(arc
							(start -0.2794 0.1778)
							(mid -0.249642 0.249642)
							(end -0.1778 0.2794)
						)
						(arc
							(start 0.1778 0.2794)
							(mid 0.249642 0.249642)
							(end 0.2794 0.1778)
						)
						(arc
							(start 0.2794 -0.1778)
							(mid 0.249642 -0.249642)
							(end 0.1778 -0.2794)
						)
					)
					(width 0)
					(fill yes)
				)
			)
		)
	)
	(footprint ""
		(layer "F.Cu")
		(at 49.403 -127.254 180)
		(property "Reference" "C309"
			(at 0 0 180)
			(layer "F.SilkS")
			(hide yes)
			(effects
				(font
					(size 1.27 1.27)
				)
			)
		)
		(property "Value" "SCD1U10V2KX-5GP"
			(at 1.1811 -2.7051 180)
			(unlocked yes)
			(layer "F.Fab")
			(hide yes)
			(effects
				(font
					(size 1.016 1.016)
					(thickness 0.1524)
				)
			)
		)
		(property "Device Type" "C402H22"
			(at 1.1811 -4.2291 180)
			(unlocked yes)
			(layer "F.Fab")
			(hide yes)
			(effects
				(font
					(size 1.016 1.016)
					(thickness 0.1524)
				)
			)
		)
		(duplicate_pad_numbers_are_jumpers no)
		(fp_rect
			(start -0.4318 0.9525)
			(end 0.4318 -0.9525)
			(stroke
				(width 0)
				(type default)
			)
			(fill no)
			(layer "F.CrtYd")
		)
		(fp_rect
			(start -0.4318 0.9525)
			(end 0.4318 -0.9525)
			(stroke
				(width 0)
				(type default)
			)
			(fill no)
			(layer "F.Fab")
		)
		(pad "1" smd custom
			(at 0 -0.4445 180)
			(size 0.1524 0.1524)
			(layers "F.Cu" "F.Mask" "F.Paste")
			(net "P3V3")
			(options
				(clearance outline)
				(anchor circle)
			)
			(primitives
				(gr_poly
					(pts
						(arc
							(start 0.3048 -0.2032)
							(mid 0.275042 -0.275042)
							(end 0.2032 -0.3048)
						)
						(arc
							(start -0.2032 -0.3048)
							(mid -0.275042 -0.275042)
							(end -0.3048 -0.2032)
						)
						(arc
							(start -0.3048 0.2032)
							(mid -0.275042 0.275042)
							(end -0.2032 0.3048)
						)
						(arc
							(start 0.2032 0.3048)
							(mid 0.275042 0.275042)
							(end 0.3048 0.2032)
						)
					)
					(width 0)
					(fill yes)
				)
			)
		)
		(pad "2" smd custom
			(at 0 0.4445 180)
			(size 0.1524 0.1524)
			(layers "F.Cu" "F.Mask" "F.Paste")
			(net "GND")
			(options
				(clearance outline)
				(anchor circle)
			)
			(primitives
				(gr_poly
					(pts
						(arc
							(start 0.3048 -0.2032)
							(mid 0.275042 -0.275042)
							(end 0.2032 -0.3048)
						)
						(arc
							(start -0.2032 -0.3048)
							(mid -0.275042 -0.275042)
							(end -0.3048 -0.2032)
						)
						(arc
							(start -0.3048 0.2032)
							(mid -0.275042 0.275042)
							(end -0.2032 0.3048)
						)
						(arc
							(start 0.2032 0.3048)
							(mid 0.275042 0.275042)
							(end 0.3048 0.2032)
						)
					)
					(width 0)
					(fill yes)
				)
			)
		)
	)
	(footprint ""
		(layer "F.Cu")
		(at 81.69656 -498.544088)
		(property "Reference" "Q12"
			(at 0 0 0)
			(layer "F.SilkS")
			(hide yes)
			(effects
				(font
					(size 1.27 1.27)
				)
			)
		)
		(property "Value" "2N7002DW-7F-GP"
			(at -2.3622 -8.2042 0)
			(unlocked yes)
			(layer "F.Fab")
			(hide yes)
			(effects
				(font
					(size 1.016 1.016)
					(thickness 0.1524)
				)
			)
		)
		(property "Device Type" "SOT-363H44"
			(at -2.3622 -10.1092 0)
			(unlocked yes)
			(layer "F.Fab")
			(hide yes)
			(effects
				(font
					(size 1.016 1.016)
					(thickness 0.1524)
				)
			)
		)
		(duplicate_pad_numbers_are_jumpers no)
		(fp_line
			(start -1.4478 -1.7018)
			(end -1.4478 1.7018)
			(stroke
				(width 0.1524)
				(type default)
			)
			(layer "F.SilkS")
		)
		(fp_line
			(start -1.4478 1.7018)
			(end 1.4478 1.7018)
			(stroke
				(width 0.1524)
				(type default)
			)
			(layer "F.SilkS")
		)
		(fp_line
			(start -1.27 1.524)
			(end -1.27 0.6604)
			(stroke
				(width 0.4826)
				(type default)
			)
			(layer "F.SilkS")
		)
		(fp_line
			(start 1.4478 -1.7018)
			(end -1.4478 -1.7018)
			(stroke
				(width 0.1524)
				(type default)
			)
			(layer "F.SilkS")
		)
		(fp_line
			(start 1.4478 1.7018)
			(end 1.4478 -1.7018)
			(stroke
				(width 0.1524)
				(type default)
			)
			(layer "F.SilkS")
		)
		(fp_poly
			(pts
				(xy -1.524 -1.778) (xy 1.524 -1.778) (xy 1.524 1.778) (xy -1.524 1.778)
			)
			(stroke
				(width 0)
				(type default)
			)
			(fill no)
			(layer "F.CrtYd")
		)
		(fp_poly
			(pts
				(xy -1.524 -1.778) (xy 1.524 -1.778) (xy 1.524 1.778) (xy -1.524 1.778)
			)
			(stroke
				(width 0)
				(type default)
			)
			(fill no)
			(layer "F.Fab")
		)
		(pad "1" smd rect
			(at -0.65024 0.9398)
			(size 0.4064 1.016)
			(layers "F.Cu" "F.Mask" "F.Paste")
			(net "GND")
		)
		(pad "2" smd rect
			(at 0 0.9398)
			(size 0.4064 1.016)
			(layers "F.Cu" "F.Mask" "F.Paste")
			(net "SW_PWR_R_HDD5")
		)
		(pad "3" smd rect
			(at 0.65024 0.9398)
			(size 0.4064 1.016)
			(layers "F.Cu" "F.Mask" "F.Paste")
			(net "SW_HDD5_P")
		)
		(pad "4" smd rect
			(at 0.65024 -0.9398)
			(size 0.4064 1.016)
			(layers "F.Cu" "F.Mask" "F.Paste")
			(net "GND")
		)
		(pad "5" smd rect
			(at 0 -0.9398)
			(size 0.4064 1.016)
			(layers "F.Cu" "F.Mask" "F.Paste")
			(net "SW_HDD5_G")
		)
		(pad "6" smd rect
			(at -0.65024 -0.9398)
			(size 0.4064 1.016)
			(layers "F.Cu" "F.Mask" "F.Paste")
			(net "SW_HDD5_R")
		)
	)
	(footprint ""
		(layer "F.Cu")
		(at 209.7278 -273.685)
		(property "Reference" "R363"
			(at 0 0 0)
			(layer "F.SilkS")
			(hide yes)
			(effects
				(font
					(size 1.27 1.27)
				)
			)
		)
		(property "Value" "10KR2F-2-GP"
			(at 0.064008 -3.993896 0)
			(unlocked yes)
			(layer "F.Fab")
			(hide yes)
			(effects
				(font
					(size 1.016 1.016)
					(thickness 0.1524)
				)
			)
		)
		(property "Device Type" "R402H16"
			(at 0.064008 -5.517896 0)
			(unlocked yes)
			(layer "F.Fab")
			(hide yes)
			(effects
				(font
					(size 1.016 1.016)
					(thickness 0.1524)
				)
			)
		)
		(duplicate_pad_numbers_are_jumpers no)
		(fp_line
			(start -0.508 -0.9398)
			(end -0.508 0.9398)
			(stroke
				(width 0.1524)
				(type default)
			)
			(layer "F.SilkS")
		)
		(fp_line
			(start 0.508 -0.9398)
			(end -0.508 -0.9398)
			(stroke
				(width 0.1524)
				(type default)
			)
			(layer "F.SilkS")
		)
		(fp_rect
			(start -0.508 0.9398)
			(end 0.508 -0.9398)
			(stroke
				(width 0)
				(type default)
			)
			(fill no)
			(layer "F.CrtYd")
		)
		(fp_rect
			(start -0.508 0.9398)
			(end 0.508 -0.9398)
			(stroke
				(width 0)
				(type default)
			)
			(fill no)
			(layer "F.Fab")
		)
		(pad "1" smd custom
			(at 0 -0.4445)
			(size 0.1397 0.1397)
			(layers "F.Cu" "F.Mask" "F.Paste")
			(net "P12V")
			(options
				(clearance outline)
				(anchor circle)
			)
			(primitives
				(gr_poly
					(pts
						(arc
							(start -0.1778 -0.2794)
							(mid -0.249642 -0.249642)
							(end -0.2794 -0.1778)
						)
						(arc
							(start -0.2794 0.1778)
							(mid -0.249642 0.249642)
							(end -0.1778 0.2794)
						)
						(arc
							(start 0.1778 0.2794)
							(mid 0.249642 0.249642)
							(end 0.2794 0.1778)
						)
						(arc
							(start 0.2794 -0.1778)
							(mid 0.249642 -0.249642)
							(end 0.1778 -0.2794)
						)
					)
					(width 0)
					(fill yes)
				)
			)
		)
		(pad "2" smd custom
			(at 0 0.4445)
			(size 0.1397 0.1397)
			(layers "F.Cu" "F.Mask" "F.Paste")
			(net "HDD2_LED_G")
			(options
				(clearance outline)
				(anchor circle)
			)
			(primitives
				(gr_poly
					(pts
						(arc
							(start -0.1778 -0.2794)
							(mid -0.249642 -0.249642)
							(end -0.2794 -0.1778)
						)
						(arc
							(start -0.2794 0.1778)
							(mid -0.249642 0.249642)
							(end -0.1778 0.2794)
						)
						(arc
							(start 0.1778 0.2794)
							(mid 0.249642 0.249642)
							(end 0.2794 0.1778)
						)
						(arc
							(start 0.2794 -0.1778)
							(mid 0.249642 -0.249642)
							(end 0.1778 -0.2794)
						)
					)
					(width 0)
					(fill yes)
				)
			)
		)
	)
	(footprint ""
		(layer "F.Cu")
		(at 23.114 -395.605 90)
		(property "Reference" "R511"
			(at 0 0 90)
			(layer "F.SilkS")
			(hide yes)
			(effects
				(font
					(size 1.27 1.27)
				)
			)
		)
		(property "Value" "0R2J-2-GP"
			(at 0.064008 -3.993896 90)
			(unlocked yes)
			(layer "F.Fab")
			(hide yes)
			(effects
				(font
					(size 1.016 1.016)
					(thickness 0.1524)
				)
			)
		)
		(property "Device Type" "R402H16"
			(at 0.064008 -5.517896 90)
			(unlocked yes)
			(layer "F.Fab")
			(hide yes)
			(effects
				(font
					(size 1.016 1.016)
					(thickness 0.1524)
				)
			)
		)
		(duplicate_pad_numbers_are_jumpers no)
		(fp_line
			(start 0.508 -0.9398)
			(end -0.508 -0.9398)
			(stroke
				(width 0.1524)
				(type default)
			)
			(layer "F.SilkS")
		)
		(fp_line
			(start -0.508 -0.9398)
			(end -0.508 0.9398)
			(stroke
				(width 0.1524)
				(type default)
			)
			(layer "F.SilkS")
		)
		(fp_rect
			(start -0.508 0.9398)
			(end 0.508 -0.9398)
			(stroke
				(width 0)
				(type default)
			)
			(fill no)
			(layer "F.CrtYd")
		)
		(fp_rect
			(start -0.508 0.9398)
			(end 0.508 -0.9398)
			(stroke
				(width 0)
				(type default)
			)
			(fill no)
			(layer "F.Fab")
		)
		(pad "1" smd custom
			(at 0 -0.4445 90)
			(size 0.1397 0.1397)
			(layers "F.Cu" "F.Mask" "F.Paste")
			(net "I2C_B_SDA_DAMP_A")
			(options
				(clearance outline)
				(anchor circle)
			)
			(primitives
				(gr_poly
					(pts
						(arc
							(start -0.1778 -0.2794)
							(mid -0.249642 -0.249642)
							(end -0.2794 -0.1778)
						)
						(arc
							(start -0.2794 0.1778)
							(mid -0.249642 0.249642)
							(end -0.1778 0.2794)
						)
						(arc
							(start 0.1778 0.2794)
							(mid 0.249642 0.249642)
							(end 0.2794 0.1778)
						)
						(arc
							(start 0.2794 -0.1778)
							(mid 0.249642 -0.249642)
							(end 0.1778 -0.2794)
						)
					)
					(width 0)
					(fill yes)
				)
			)
		)
		(pad "2" smd custom
			(at 0 0.4445 90)
			(size 0.1397 0.1397)
			(layers "F.Cu" "F.Mask" "F.Paste")
			(net "I2C_B_SDA")
			(options
				(clearance outline)
				(anchor circle)
			)
			(primitives
				(gr_poly
					(pts
						(arc
							(start -0.1778 -0.2794)
							(mid -0.249642 -0.249642)
							(end -0.2794 -0.1778)
						)
						(arc
							(start -0.2794 0.1778)
							(mid -0.249642 0.249642)
							(end -0.1778 0.2794)
						)
						(arc
							(start 0.1778 0.2794)
							(mid 0.249642 0.249642)
							(end 0.2794 0.1778)
						)
						(arc
							(start 0.2794 -0.1778)
							(mid 0.249642 -0.249642)
							(end 0.1778 -0.2794)
						)
					)
					(width 0)
					(fill yes)
				)
			)
		)
	)
	(footprint ""
		(layer "F.Cu")
		(at 35.052 -307.34 90)
		(property "Reference" "R559"
			(at 0 0 90)
			(layer "F.SilkS")
			(hide yes)
			(effects
				(font
					(size 1.27 1.27)
				)
			)
		)
		(property "Value" "200KR2F-L-GP"
			(at 0.064008 -3.993896 90)
			(unlocked yes)
			(layer "F.Fab")
			(hide yes)
			(effects
				(font
					(size 1.016 1.016)
					(thickness 0.1524)
				)
			)
		)
		(property "Device Type" "R402H16"
			(at 0.064008 -5.517896 90)
			(unlocked yes)
			(layer "F.Fab")
			(hide yes)
			(effects
				(font
					(size 1.016 1.016)
					(thickness 0.1524)
				)
			)
		)
		(duplicate_pad_numbers_are_jumpers no)
		(fp_line
			(start 0.508 -0.9398)
			(end -0.508 -0.9398)
			(stroke
				(width 0.1524)
				(type default)
			)
			(layer "F.SilkS")
		)
		(fp_line
			(start -0.508 -0.9398)
			(end -0.508 0.9398)
			(stroke
				(width 0.1524)
				(type default)
			)
			(layer "F.SilkS")
		)
		(fp_rect
			(start -0.508 0.9398)
			(end 0.508 -0.9398)
			(stroke
				(width 0)
				(type default)
			)
			(fill no)
			(layer "F.CrtYd")
		)
		(fp_rect
			(start -0.508 0.9398)
			(end 0.508 -0.9398)
			(stroke
				(width 0)
				(type default)
			)
			(fill no)
			(layer "F.Fab")
		)
		(pad "1" smd custom
			(at 0 -0.4445 90)
			(size 0.1397 0.1397)
			(layers "F.Cu" "F.Mask" "F.Paste")
			(net "SW_HDD11_R")
			(options
				(clearance outline)
				(anchor circle)
			)
			(primitives
				(gr_poly
					(pts
						(arc
							(start -0.1778 -0.2794)
							(mid -0.249642 -0.249642)
							(end -0.2794 -0.1778)
						)
						(arc
							(start -0.2794 0.1778)
							(mid -0.249642 0.249642)
							(end -0.1778 0.2794)
						)
						(arc
							(start 0.1778 0.2794)
							(mid 0.249642 0.249642)
							(end 0.2794 0.1778)
						)
						(arc
							(start 0.2794 -0.1778)
							(mid 0.249642 -0.249642)
							(end 0.1778 -0.2794)
						)
					)
					(width 0)
					(fill yes)
				)
			)
		)
		(pad "2" smd custom
			(at 0 0.4445 90)
			(size 0.1397 0.1397)
			(layers "F.Cu" "F.Mask" "F.Paste")
			(net "SW_HDD11_N")
			(options
				(clearance outline)
				(anchor circle)
			)
			(primitives
				(gr_poly
					(pts
						(arc
							(start -0.1778 -0.2794)
							(mid -0.249642 -0.249642)
							(end -0.2794 -0.1778)
						)
						(arc
							(start -0.2794 0.1778)
							(mid -0.249642 0.249642)
							(end -0.1778 0.2794)
						)
						(arc
							(start 0.1778 0.2794)
							(mid 0.249642 0.249642)
							(end 0.2794 0.1778)
						)
						(arc
							(start 0.2794 -0.1778)
							(mid 0.249642 -0.249642)
							(end 0.1778 -0.2794)
						)
					)
					(width 0)
					(fill yes)
				)
			)
		)
	)
	(footprint ""
		(layer "F.Cu")
		(at 46.736 -107.315)
		(property "Reference" "C392"
			(at 0 0 0)
			(layer "F.SilkS")
			(hide yes)
			(effects
				(font
					(size 1.27 1.27)
				)
			)
		)
		(property "Value" "SCD033U25V2KX-GP"
			(at 1.1811 -2.7051 0)
			(unlocked yes)
			(layer "F.Fab")
			(hide yes)
			(effects
				(font
					(size 1.016 1.016)
					(thickness 0.1524)
				)
			)
		)
		(property "Device Type" "C402H22"
			(at 1.1811 -4.2291 0)
			(unlocked yes)
			(layer "F.Fab")
			(hide yes)
			(effects
				(font
					(size 1.016 1.016)
					(thickness 0.1524)
				)
			)
		)
		(duplicate_pad_numbers_are_jumpers no)
		(fp_rect
			(start -0.4318 0.9525)
			(end 0.4318 -0.9525)
			(stroke
				(width 0)
				(type default)
			)
			(fill no)
			(layer "F.CrtYd")
		)
		(fp_rect
			(start -0.4318 0.9525)
			(end 0.4318 -0.9525)
			(stroke
				(width 0)
				(type default)
			)
			(fill no)
			(layer "F.Fab")
		)
		(pad "1" smd custom
			(at 0 -0.4445)
			(size 0.1524 0.1524)
			(layers "F.Cu" "F.Mask" "F.Paste")
			(net "P12V")
			(options
				(clearance outline)
				(anchor circle)
			)
			(primitives
				(gr_poly
					(pts
						(arc
							(start 0.3048 -0.2032)
							(mid 0.275042 -0.275042)
							(end 0.2032 -0.3048)
						)
						(arc
							(start -0.2032 -0.3048)
							(mid -0.275042 -0.275042)
							(end -0.3048 -0.2032)
						)
						(arc
							(start -0.3048 0.2032)
							(mid -0.275042 0.275042)
							(end -0.2032 0.3048)
						)
						(arc
							(start 0.2032 0.3048)
							(mid 0.275042 0.275042)
							(end 0.3048 0.2032)
						)
					)
					(width 0)
					(fill yes)
				)
			)
		)
		(pad "2" smd custom
			(at 0 0.4445)
			(size 0.1524 0.1524)
			(layers "F.Cu" "F.Mask" "F.Paste")
			(net "SW_HDD13_N")
			(options
				(clearance outline)
				(anchor circle)
			)
			(primitives
				(gr_poly
					(pts
						(arc
							(start 0.3048 -0.2032)
							(mid 0.275042 -0.275042)
							(end 0.2032 -0.3048)
						)
						(arc
							(start -0.2032 -0.3048)
							(mid -0.275042 -0.275042)
							(end -0.3048 -0.2032)
						)
						(arc
							(start -0.3048 0.2032)
							(mid -0.275042 0.275042)
							(end -0.2032 0.3048)
						)
						(arc
							(start 0.2032 0.3048)
							(mid 0.275042 0.275042)
							(end 0.3048 0.2032)
						)
					)
					(width 0)
					(fill yes)
				)
			)
		)
	)
	(footprint ""
		(layer "F.Cu")
		(at 179.463446 -457.107036)
		(property "Reference" "R484"
			(at 0 0 0)
			(layer "F.SilkS")
			(hide yes)
			(effects
				(font
					(size 1.27 1.27)
				)
			)
		)
		(property "Value" "10KR2F-2-GP"
			(at 0.064008 -3.993896 0)
			(unlocked yes)
			(layer "F.Fab")
			(hide yes)
			(effects
				(font
					(size 1.016 1.016)
					(thickness 0.1524)
				)
			)
		)
		(property "Device Type" "R402H16"
			(at 0.064008 -5.517896 0)
			(unlocked yes)
			(layer "F.Fab")
			(hide yes)
			(effects
				(font
					(size 1.016 1.016)
					(thickness 0.1524)
				)
			)
		)
		(duplicate_pad_numbers_are_jumpers no)
		(fp_line
			(start -0.508 -0.9398)
			(end -0.508 0.9398)
			(stroke
				(width 0.1524)
				(type default)
			)
			(layer "F.SilkS")
		)
		(fp_line
			(start 0.508 -0.9398)
			(end -0.508 -0.9398)
			(stroke
				(width 0.1524)
				(type default)
			)
			(layer "F.SilkS")
		)
		(fp_rect
			(start -0.508 0.9398)
			(end 0.508 -0.9398)
			(stroke
				(width 0)
				(type default)
			)
			(fill no)
			(layer "F.CrtYd")
		)
		(fp_rect
			(start -0.508 0.9398)
			(end 0.508 -0.9398)
			(stroke
				(width 0)
				(type default)
			)
			(fill no)
			(layer "F.Fab")
		)
		(pad "1" smd custom
			(at 0 -0.4445)
			(size 0.1397 0.1397)
			(layers "F.Cu" "F.Mask" "F.Paste")
			(net "P5VC_DIV")
			(options
				(clearance outline)
				(anchor circle)
			)
			(primitives
				(gr_poly
					(pts
						(arc
							(start -0.1778 -0.2794)
							(mid -0.249642 -0.249642)
							(end -0.2794 -0.1778)
						)
						(arc
							(start -0.2794 0.1778)
							(mid -0.249642 0.249642)
							(end -0.1778 0.2794)
						)
						(arc
							(start 0.1778 0.2794)
							(mid 0.249642 0.249642)
							(end 0.2794 0.1778)
						)
						(arc
							(start 0.2794 -0.1778)
							(mid 0.249642 -0.249642)
							(end 0.1778 -0.2794)
						)
					)
					(width 0)
					(fill yes)
				)
			)
		)
		(pad "2" smd custom
			(at 0 0.4445)
			(size 0.1397 0.1397)
			(layers "F.Cu" "F.Mask" "F.Paste")
			(net "GND")
			(options
				(clearance outline)
				(anchor circle)
			)
			(primitives
				(gr_poly
					(pts
						(arc
							(start -0.1778 -0.2794)
							(mid -0.249642 -0.249642)
							(end -0.2794 -0.1778)
						)
						(arc
							(start -0.2794 0.1778)
							(mid -0.249642 0.249642)
							(end -0.1778 0.2794)
						)
						(arc
							(start 0.1778 0.2794)
							(mid 0.249642 0.249642)
							(end 0.2794 0.1778)
						)
						(arc
							(start 0.2794 -0.1778)
							(mid 0.249642 -0.249642)
							(end 0.1778 -0.2794)
						)
					)
					(width 0)
					(fill yes)
				)
			)
		)
	)
	(footprint ""
		(layer "F.Cu")
		(at 215.9508 -393.9032 180)
		(property "Reference" "C128"
			(at 0 0 180)
			(layer "F.SilkS")
			(hide yes)
			(effects
				(font
					(size 1.27 1.27)
				)
			)
		)
		(property "Value" "SC10U25V6KX-1GP"
			(at -0.0762 -5.1308 180)
			(unlocked yes)
			(layer "F.Fab")
			(hide yes)
			(effects
				(font
					(size 1.016 1.016)
					(thickness 0.1524)
				)
			)
		)
		(property "Device Type" "C1206H71"
			(at -0.127 -6.6548 180)
			(unlocked yes)
			(layer "F.Fab")
			(hide yes)
			(effects
				(font
					(size 1.016 1.016)
					(thickness 0.1524)
				)
			)
		)
		(duplicate_pad_numbers_are_jumpers no)
		(fp_line
			(start 1.016 2.2352)
			(end -1.016 2.2352)
			(stroke
				(width 0.1524)
				(type default)
			)
			(layer "F.SilkS")
		)
		(fp_line
			(start 1.016 0.8382)
			(end 1.016 2.2352)
			(stroke
				(width 0.1524)
				(type default)
			)
			(layer "F.SilkS")
		)
		(fp_line
			(start 1.016 -2.2352)
			(end 1.016 -0.8382)
			(stroke
				(width 0.1524)
				(type default)
			)
			(layer "F.SilkS")
		)
		(fp_line
			(start -1.016 2.2352)
			(end -1.016 0.8382)
			(stroke
				(width 0.1524)
				(type default)
			)
			(layer "F.SilkS")
		)
		(fp_line
			(start -1.016 -0.8382)
			(end -1.016 -2.2352)
			(stroke
				(width 0.1524)
				(type default)
			)
			(layer "F.SilkS")
		)
		(fp_line
			(start -1.016 -2.2352)
			(end 1.016 -2.2352)
			(stroke
				(width 0.1524)
				(type default)
			)
			(layer "F.SilkS")
		)
		(fp_rect
			(start -1.0922 2.3114)
			(end 1.0922 -2.3114)
			(stroke
				(width 0)
				(type default)
			)
			(fill no)
			(layer "F.CrtYd")
		)
		(fp_poly
			(pts
				(xy 1.0922 -2.3114) (xy 1.0922 2.3114) (xy -1.0922 2.3114) (xy -1.0922 -2.3114)
			)
			(stroke
				(width 0)
				(type default)
			)
			(fill no)
			(layer "F.Fab")
		)
		(pad "1" smd rect
			(at 0 -1.397 180)
			(size 1.651 1.27)
			(layers "F.Cu" "F.Mask" "F.Paste")
			(net "P12V_HDD1")
		)
		(pad "2" smd rect
			(at 0 1.397 180)
			(size 1.651 1.27)
			(layers "F.Cu" "F.Mask" "F.Paste")
			(net "GND")
		)
	)
	(footprint ""
		(layer "F.Cu")
		(at 52.323746 -228.603302)
		(property "Reference" "R468"
			(at 0 0 0)
			(layer "F.SilkS")
			(hide yes)
			(effects
				(font
					(size 1.27 1.27)
				)
			)
		)
		(property "Value" "4K7R2J-2-GP"
			(at 0.064008 -3.993896 0)
			(unlocked yes)
			(layer "F.Fab")
			(hide yes)
			(effects
				(font
					(size 1.016 1.016)
					(thickness 0.1524)
				)
			)
		)
		(property "Device Type" "R402H16"
			(at 0.064008 -5.517896 0)
			(unlocked yes)
			(layer "F.Fab")
			(hide yes)
			(effects
				(font
					(size 1.016 1.016)
					(thickness 0.1524)
				)
			)
		)
		(duplicate_pad_numbers_are_jumpers no)
		(fp_line
			(start -0.508 -0.9398)
			(end -0.508 0.9398)
			(stroke
				(width 0.1524)
				(type default)
			)
			(layer "F.SilkS")
		)
		(fp_line
			(start 0.508 -0.9398)
			(end -0.508 -0.9398)
			(stroke
				(width 0.1524)
				(type default)
			)
			(layer "F.SilkS")
		)
		(fp_rect
			(start -0.508 0.9398)
			(end 0.508 -0.9398)
			(stroke
				(width 0)
				(type default)
			)
			(fill no)
			(layer "F.CrtYd")
		)
		(fp_rect
			(start -0.508 0.9398)
			(end 0.508 -0.9398)
			(stroke
				(width 0)
				(type default)
			)
			(fill no)
			(layer "F.Fab")
		)
		(pad "1" smd custom
			(at 0 -0.4445)
			(size 0.1397 0.1397)
			(layers "F.Cu" "F.Mask" "F.Paste")
			(net "P3V3")
			(options
				(clearance outline)
				(anchor circle)
			)
			(primitives
				(gr_poly
					(pts
						(arc
							(start -0.1778 -0.2794)
							(mid -0.249642 -0.249642)
							(end -0.2794 -0.1778)
						)
						(arc
							(start -0.2794 0.1778)
							(mid -0.249642 0.249642)
							(end -0.1778 0.2794)
						)
						(arc
							(start 0.1778 0.2794)
							(mid 0.249642 0.249642)
							(end 0.2794 0.1778)
						)
						(arc
							(start 0.2794 -0.1778)
							(mid 0.249642 -0.249642)
							(end 0.1778 -0.2794)
						)
					)
					(width 0)
					(fill yes)
				)
			)
		)
		(pad "2" smd custom
			(at 0 0.4445)
			(size 0.1397 0.1397)
			(layers "F.Cu" "F.Mask" "F.Paste")
			(net "SAS2X28_A_HDD12_FLT")
			(options
				(clearance outline)
				(anchor circle)
			)
			(primitives
				(gr_poly
					(pts
						(arc
							(start -0.1778 -0.2794)
							(mid -0.249642 -0.249642)
							(end -0.2794 -0.1778)
						)
						(arc
							(start -0.2794 0.1778)
							(mid -0.249642 0.249642)
							(end -0.1778 0.2794)
						)
						(arc
							(start 0.1778 0.2794)
							(mid 0.249642 0.249642)
							(end 0.2794 0.1778)
						)
						(arc
							(start 0.2794 -0.1778)
							(mid 0.249642 -0.249642)
							(end 0.1778 -0.2794)
						)
					)
					(width 0)
					(fill yes)
				)
			)
		)
	)
	(footprint ""
		(layer "F.Cu")
		(at 191.389 -293.243 90)
		(property "Reference" "R136"
			(at 0 0 90)
			(layer "F.SilkS")
			(hide yes)
			(effects
				(font
					(size 1.27 1.27)
				)
			)
		)
		(property "Value" "4K7R2J-2-GP"
			(at 0.064008 -3.993896 90)
			(unlocked yes)
			(layer "F.Fab")
			(hide yes)
			(effects
				(font
					(size 1.016 1.016)
					(thickness 0.1524)
				)
			)
		)
		(property "Device Type" "R402H16"
			(at 0.064008 -5.517896 90)
			(unlocked yes)
			(layer "F.Fab")
			(hide yes)
			(effects
				(font
					(size 1.016 1.016)
					(thickness 0.1524)
				)
			)
		)
		(duplicate_pad_numbers_are_jumpers no)
		(fp_line
			(start 0.508 -0.9398)
			(end -0.508 -0.9398)
			(stroke
				(width 0.1524)
				(type default)
			)
			(layer "F.SilkS")
		)
		(fp_line
			(start -0.508 -0.9398)
			(end -0.508 0.9398)
			(stroke
				(width 0.1524)
				(type default)
			)
			(layer "F.SilkS")
		)
		(fp_rect
			(start -0.508 0.9398)
			(end 0.508 -0.9398)
			(stroke
				(width 0)
				(type default)
			)
			(fill no)
			(layer "F.CrtYd")
		)
		(fp_rect
			(start -0.508 0.9398)
			(end 0.508 -0.9398)
			(stroke
				(width 0)
				(type default)
			)
			(fill no)
			(layer "F.Fab")
		)
		(pad "1" smd custom
			(at 0 -0.4445 90)
			(size 0.1397 0.1397)
			(layers "F.Cu" "F.Mask" "F.Paste")
			(net "P12V")
			(options
				(clearance outline)
				(anchor circle)
			)
			(primitives
				(gr_poly
					(pts
						(arc
							(start -0.1778 -0.2794)
							(mid -0.249642 -0.249642)
							(end -0.2794 -0.1778)
						)
						(arc
							(start -0.2794 0.1778)
							(mid -0.249642 0.249642)
							(end -0.1778 0.2794)
						)
						(arc
							(start 0.1778 0.2794)
							(mid 0.249642 0.249642)
							(end 0.2794 0.1778)
						)
						(arc
							(start 0.2794 -0.1778)
							(mid 0.249642 -0.249642)
							(end 0.1778 -0.2794)
						)
					)
					(width 0)
					(fill yes)
				)
			)
		)
		(pad "2" smd custom
			(at 0 0.4445 90)
			(size 0.1397 0.1397)
			(layers "F.Cu" "F.Mask" "F.Paste")
			(net "SW_HDD2_R")
			(options
				(clearance outline)
				(anchor circle)
			)
			(primitives
				(gr_poly
					(pts
						(arc
							(start -0.1778 -0.2794)
							(mid -0.249642 -0.249642)
							(end -0.2794 -0.1778)
						)
						(arc
							(start -0.2794 0.1778)
							(mid -0.249642 0.249642)
							(end -0.1778 0.2794)
						)
						(arc
							(start 0.1778 0.2794)
							(mid 0.249642 0.249642)
							(end 0.2794 0.1778)
						)
						(arc
							(start 0.2794 -0.1778)
							(mid 0.249642 -0.249642)
							(end 0.1778 -0.2794)
						)
					)
					(width 0)
					(fill yes)
				)
			)
		)
	)
	(footprint ""
		(layer "F.Cu")
		(at 56.260746 -175.3997)
		(property "Reference" "R219"
			(at 0 0 0)
			(layer "F.SilkS")
			(hide yes)
			(effects
				(font
					(size 1.27 1.27)
				)
			)
		)
		(property "Value" "220R3F-1-GP"
			(at -0.0254 -2.5146 0)
			(unlocked yes)
			(layer "F.Fab")
			(hide yes)
			(effects
				(font
					(size 1.016 1.016)
					(thickness 0.1524)
				)
			)
		)
		(property "Device Type" "R603H22"
			(at -0.0254 -4.0386 0)
			(unlocked yes)
			(layer "F.Fab")
			(hide yes)
			(effects
				(font
					(size 1.016 1.016)
					(thickness 0.1524)
				)
			)
		)
		(duplicate_pad_numbers_are_jumpers no)
		(fp_line
			(start -0.4826 0)
			(end -0.2032 0)
			(stroke
				(width 0.2032)
				(type default)
			)
			(layer "F.SilkS")
		)
		(fp_line
			(start 0.2032 0)
			(end 0.4826 0)
			(stroke
				(width 0.2032)
				(type default)
			)
			(layer "F.SilkS")
		)
		(fp_rect
			(start -0.5842 1.3335)
			(end 0.5842 -1.3335)
			(stroke
				(width 0)
				(type default)
			)
			(fill no)
			(layer "F.CrtYd")
		)
		(fp_rect
			(start -0.5842 1.3335)
			(end 0.5842 -1.3335)
			(stroke
				(width 0)
				(type default)
			)
			(fill no)
			(layer "F.Fab")
		)
		(pad "1" smd custom
			(at 0 -0.762)
			(size 0.2159 0.2159)
			(layers "F.Cu" "F.Mask" "F.Paste")
			(net "HDD_PRSNT_NET8")
			(options
				(clearance outline)
				(anchor circle)
			)
			(primitives
				(gr_poly
					(pts
						(arc
							(start -0.3302 -0.4318)
							(mid -0.402042 -0.402042)
							(end -0.4318 -0.3302)
						)
						(arc
							(start -0.4318 0.3302)
							(mid -0.402042 0.402042)
							(end -0.3302 0.4318)
						)
						(arc
							(start 0.3302 0.4318)
							(mid 0.402042 0.402042)
							(end 0.4318 0.3302)
						)
						(arc
							(start 0.4318 -0.3302)
							(mid 0.402042 -0.402042)
							(end 0.3302 -0.4318)
						)
					)
					(width 0)
					(fill yes)
				)
			)
		)
		(pad "2" smd custom
			(at 0 0.762)
			(size 0.2159 0.2159)
			(layers "F.Cu" "F.Mask" "F.Paste")
			(net "HDD_PRSNT8")
			(options
				(clearance outline)
				(anchor circle)
			)
			(primitives
				(gr_poly
					(pts
						(arc
							(start -0.3302 -0.4318)
							(mid -0.402042 -0.402042)
							(end -0.4318 -0.3302)
						)
						(arc
							(start -0.4318 0.3302)
							(mid -0.402042 0.402042)
							(end -0.3302 0.4318)
						)
						(arc
							(start 0.3302 0.4318)
							(mid 0.402042 0.402042)
							(end 0.4318 0.3302)
						)
						(arc
							(start 0.4318 -0.3302)
							(mid 0.402042 -0.402042)
							(end 0.3302 -0.4318)
						)
					)
					(width 0)
					(fill yes)
				)
			)
		)
	)
	(footprint ""
		(layer "F.Cu")
		(at 59.943746 -8.5217 90)
		(property "Reference" "PC18"
			(at 0 0 90)
			(layer "F.SilkS")
			(hide yes)
			(effects
				(font
					(size 1.27 1.27)
				)
			)
		)
		(property "Value" "SC22U25V5MX-GP"
			(at -0.0762 -6.1214 90)
			(unlocked yes)
			(layer "F.Fab")
			(hide yes)
			(effects
				(font
					(size 1.016 1.016)
					(thickness 0.1524)
				)
			)
		)
		(property "Device Type" "C805H58"
			(at -0.0762 -8.1534 90)
			(unlocked yes)
			(layer "F.Fab")
			(hide yes)
			(effects
				(font
					(size 1.016 1.016)
					(thickness 0.1524)
				)
			)
		)
		(duplicate_pad_numbers_are_jumpers no)
		(fp_line
			(start 0.635 0)
			(end -0.635 0)
			(stroke
				(width 0.508)
				(type default)
			)
			(layer "F.SilkS")
		)
		(fp_rect
			(start -0.9652 1.778)
			(end 0.9652 -1.778)
			(stroke
				(width 0)
				(type default)
			)
			(fill no)
			(layer "F.CrtYd")
		)
		(fp_poly
			(pts
				(xy -0.9652 -1.778) (xy 0.9652 -1.778) (xy 0.9652 1.778) (xy -0.9652 1.778)
			)
			(stroke
				(width 0)
				(type default)
			)
			(fill no)
			(layer "F.Fab")
		)
		(pad "1" smd rect
			(at 0 -0.9652 90)
			(size 1.397 1.143)
			(layers "F.Cu" "F.Mask" "F.Paste")
			(net "P5VB_12VIN")
		)
		(pad "2" smd rect
			(at 0 0.9652 90)
			(size 1.397 1.143)
			(layers "F.Cu" "F.Mask" "F.Paste")
			(net "GND")
		)
	)
	(footprint ""
		(layer "F.Cu")
		(at 27.876246 -374.9167 -90)
		(property "Reference" "R321"
			(at 0 0 270)
			(layer "F.SilkS")
			(hide yes)
			(effects
				(font
					(size 1.27 1.27)
				)
			)
		)
		(property "Value" "4K7R2J-2-GP"
			(at 0.064008 -3.993896 270)
			(unlocked yes)
			(layer "F.Fab")
			(hide yes)
			(effects
				(font
					(size 1.016 1.016)
					(thickness 0.1524)
				)
			)
		)
		(property "Device Type" "R402H16"
			(at 0.064008 -5.517896 270)
			(unlocked yes)
			(layer "F.Fab")
			(hide yes)
			(effects
				(font
					(size 1.016 1.016)
					(thickness 0.1524)
				)
			)
		)
		(duplicate_pad_numbers_are_jumpers no)
		(fp_line
			(start -0.508 -0.9398)
			(end -0.508 0.9398)
			(stroke
				(width 0.1524)
				(type default)
			)
			(layer "F.SilkS")
		)
		(fp_line
			(start 0.508 -0.9398)
			(end -0.508 -0.9398)
			(stroke
				(width 0.1524)
				(type default)
			)
			(layer "F.SilkS")
		)
		(fp_rect
			(start -0.508 0.9398)
			(end 0.508 -0.9398)
			(stroke
				(width 0)
				(type default)
			)
			(fill no)
			(layer "F.CrtYd")
		)
		(fp_rect
			(start -0.508 0.9398)
			(end 0.508 -0.9398)
			(stroke
				(width 0)
				(type default)
			)
			(fill no)
			(layer "F.Fab")
		)
		(pad "1" smd custom
			(at 0 -0.4445 270)
			(size 0.1397 0.1397)
			(layers "F.Cu" "F.Mask" "F.Paste")
			(net "I2C_B_TMP1_A1")
			(options
				(clearance outline)
				(anchor circle)
			)
			(primitives
				(gr_poly
					(pts
						(arc
							(start -0.1778 -0.2794)
							(mid -0.249642 -0.249642)
							(end -0.2794 -0.1778)
						)
						(arc
							(start -0.2794 0.1778)
							(mid -0.249642 0.249642)
							(end -0.1778 0.2794)
						)
						(arc
							(start 0.1778 0.2794)
							(mid 0.249642 0.249642)
							(end 0.2794 0.1778)
						)
						(arc
							(start 0.2794 -0.1778)
							(mid 0.249642 -0.249642)
							(end 0.1778 -0.2794)
						)
					)
					(width 0)
					(fill yes)
				)
			)
		)
		(pad "2" smd custom
			(at 0 0.4445 270)
			(size 0.1397 0.1397)
			(layers "F.Cu" "F.Mask" "F.Paste")
			(net "GND")
			(options
				(clearance outline)
				(anchor circle)
			)
			(primitives
				(gr_poly
					(pts
						(arc
							(start -0.1778 -0.2794)
							(mid -0.249642 -0.249642)
							(end -0.2794 -0.1778)
						)
						(arc
							(start -0.2794 0.1778)
							(mid -0.249642 0.249642)
							(end -0.1778 0.2794)
						)
						(arc
							(start 0.1778 0.2794)
							(mid 0.249642 0.249642)
							(end 0.2794 0.1778)
						)
						(arc
							(start 0.2794 -0.1778)
							(mid 0.249642 -0.249642)
							(end 0.1778 -0.2794)
						)
					)
					(width 0)
					(fill yes)
				)
			)
		)
	)
	(footprint ""
		(layer "F.Cu")
		(at 57.768236 -493.518698 90)
		(property "Reference" "R178"
			(at 0 0 90)
			(layer "F.SilkS")
			(hide yes)
			(effects
				(font
					(size 1.27 1.27)
				)
			)
		)
		(property "Value" "2R2010J-1-GP"
			(at 0.254 -8.0772 90)
			(unlocked yes)
			(layer "F.Fab")
			(hide yes)
			(effects
				(font
					(size 1.016 1.016)
					(thickness 0.1524)
				)
			)
		)
		(property "Device Type" "R2010H28"
			(at 0.254 -9.6774 90)
			(unlocked yes)
			(layer "F.Fab")
			(hide yes)
			(effects
				(font
					(size 1.016 1.016)
					(thickness 0.1524)
				)
			)
		)
		(duplicate_pad_numbers_are_jumpers no)
		(fp_line
			(start 1.651 -3.302)
			(end -1.651 -3.302)
			(stroke
				(width 0.1524)
				(type default)
			)
			(layer "F.SilkS")
		)
		(fp_line
			(start -1.651 -3.302)
			(end -1.651 3.302)
			(stroke
				(width 0.1524)
				(type default)
			)
			(layer "F.SilkS")
		)
		(fp_line
			(start 1.651 3.302)
			(end 1.651 -3.302)
			(stroke
				(width 0.1524)
				(type default)
			)
			(layer "F.SilkS")
		)
		(fp_line
			(start -1.651 3.302)
			(end 1.651 3.302)
			(stroke
				(width 0.1524)
				(type default)
			)
			(layer "F.SilkS")
		)
		(fp_rect
			(start -1.7272 -3.3782)
			(end 1.7272 3.3782)
			(stroke
				(width 0)
				(type default)
			)
			(fill no)
			(layer "F.CrtYd")
		)
		(fp_poly
			(pts
				(xy 1.7272 3.3782) (xy 1.7272 -3.3782) (xy -1.7272 -3.3782) (xy -1.7272 3.3782)
			)
			(stroke
				(width 0)
				(type default)
			)
			(fill no)
			(layer "F.Fab")
		)
		(pad "1" smd rect
			(at 0 -2.3495 90)
			(size 2.794 1.143)
			(layers "F.Cu" "F.Mask" "F.Paste")
			(net "12V_PRE_5")
		)
		(pad "2" smd rect
			(at 0 2.3495 90)
			(size 2.794 1.143)
			(layers "F.Cu" "F.Mask" "F.Paste")
			(net "P12V_HDD5")
		)
	)
	(footprint ""
		(layer "F.Cu")
		(at 209.295746 -40.9067 180)
		(property "Reference" "R332"
			(at 0 0 180)
			(layer "F.SilkS")
			(hide yes)
			(effects
				(font
					(size 1.27 1.27)
				)
			)
		)
		(property "Value" "4K7R2J-2-GP"
			(at 0.064008 -3.993896 180)
			(unlocked yes)
			(layer "F.Fab")
			(hide yes)
			(effects
				(font
					(size 1.016 1.016)
					(thickness 0.1524)
				)
			)
		)
		(property "Device Type" "R402H16"
			(at 0.064008 -5.517896 180)
			(unlocked yes)
			(layer "F.Fab")
			(hide yes)
			(effects
				(font
					(size 1.016 1.016)
					(thickness 0.1524)
				)
			)
		)
		(duplicate_pad_numbers_are_jumpers no)
		(fp_line
			(start 0.508 -0.9398)
			(end -0.508 -0.9398)
			(stroke
				(width 0.1524)
				(type default)
			)
			(layer "F.SilkS")
		)
		(fp_line
			(start -0.508 -0.9398)
			(end -0.508 0.9398)
			(stroke
				(width 0.1524)
				(type default)
			)
			(layer "F.SilkS")
		)
		(fp_rect
			(start -0.508 0.9398)
			(end 0.508 -0.9398)
			(stroke
				(width 0)
				(type default)
			)
			(fill no)
			(layer "F.CrtYd")
		)
		(fp_rect
			(start -0.508 0.9398)
			(end 0.508 -0.9398)
			(stroke
				(width 0)
				(type default)
			)
			(fill no)
			(layer "F.Fab")
		)
		(pad "1" smd custom
			(at 0 -0.4445 180)
			(size 0.1397 0.1397)
			(layers "F.Cu" "F.Mask" "F.Paste")
			(net "P3V3")
			(options
				(clearance outline)
				(anchor circle)
			)
			(primitives
				(gr_poly
					(pts
						(arc
							(start -0.1778 -0.2794)
							(mid -0.249642 -0.249642)
							(end -0.2794 -0.1778)
						)
						(arc
							(start -0.2794 0.1778)
							(mid -0.249642 0.249642)
							(end -0.1778 0.2794)
						)
						(arc
							(start 0.1778 0.2794)
							(mid 0.249642 0.249642)
							(end 0.2794 0.1778)
						)
						(arc
							(start 0.2794 -0.1778)
							(mid 0.249642 -0.249642)
							(end 0.1778 -0.2794)
						)
					)
					(width 0)
					(fill yes)
				)
			)
		)
		(pad "2" smd custom
			(at 0 0.4445 180)
			(size 0.1397 0.1397)
			(layers "F.Cu" "F.Mask" "F.Paste")
			(net "I2C_B_TMP4_A1")
			(options
				(clearance outline)
				(anchor circle)
			)
			(primitives
				(gr_poly
					(pts
						(arc
							(start -0.1778 -0.2794)
							(mid -0.249642 -0.249642)
							(end -0.2794 -0.1778)
						)
						(arc
							(start -0.2794 0.1778)
							(mid -0.249642 0.249642)
							(end -0.1778 0.2794)
						)
						(arc
							(start 0.1778 0.2794)
							(mid 0.249642 0.249642)
							(end 0.2794 0.1778)
						)
						(arc
							(start 0.2794 -0.1778)
							(mid 0.249642 -0.249642)
							(end 0.1778 -0.2794)
						)
					)
					(width 0)
					(fill yes)
				)
			)
		)
	)
	(footprint ""
		(layer "F.Cu")
		(at 60.375292 -87.912956 180)
		(property "Reference" "C256"
			(at 0 0 180)
			(layer "F.SilkS")
			(hide yes)
			(effects
				(font
					(size 1.27 1.27)
				)
			)
		)
		(property "Value" "SC10U25V6KX-1GP"
			(at -0.0762 -5.1308 180)
			(unlocked yes)
			(layer "F.Fab")
			(hide yes)
			(effects
				(font
					(size 1.016 1.016)
					(thickness 0.1524)
				)
			)
		)
		(property "Device Type" "C1206H71"
			(at -0.127 -6.6548 180)
			(unlocked yes)
			(layer "F.Fab")
			(hide yes)
			(effects
				(font
					(size 1.016 1.016)
					(thickness 0.1524)
				)
			)
		)
		(duplicate_pad_numbers_are_jumpers no)
		(fp_line
			(start 1.016 2.2352)
			(end -1.016 2.2352)
			(stroke
				(width 0.1524)
				(type default)
			)
			(layer "F.SilkS")
		)
		(fp_line
			(start 1.016 0.8382)
			(end 1.016 2.2352)
			(stroke
				(width 0.1524)
				(type default)
			)
			(layer "F.SilkS")
		)
		(fp_line
			(start 1.016 -2.2352)
			(end 1.016 -0.8382)
			(stroke
				(width 0.1524)
				(type default)
			)
			(layer "F.SilkS")
		)
		(fp_line
			(start -1.016 2.2352)
			(end -1.016 0.8382)
			(stroke
				(width 0.1524)
				(type default)
			)
			(layer "F.SilkS")
		)
		(fp_line
			(start -1.016 -0.8382)
			(end -1.016 -2.2352)
			(stroke
				(width 0.1524)
				(type default)
			)
			(layer "F.SilkS")
		)
		(fp_line
			(start -1.016 -2.2352)
			(end 1.016 -2.2352)
			(stroke
				(width 0.1524)
				(type default)
			)
			(layer "F.SilkS")
		)
		(fp_rect
			(start -1.0922 2.3114)
			(end 1.0922 -2.3114)
			(stroke
				(width 0)
				(type default)
			)
			(fill no)
			(layer "F.CrtYd")
		)
		(fp_poly
			(pts
				(xy 1.0922 -2.3114) (xy 1.0922 2.3114) (xy -1.0922 2.3114) (xy -1.0922 -2.3114)
			)
			(stroke
				(width 0)
				(type default)
			)
			(fill no)
			(layer "F.Fab")
		)
		(pad "1" smd rect
			(at 0 -1.397 180)
			(size 1.651 1.27)
			(layers "F.Cu" "F.Mask" "F.Paste")
			(net "P12V_HDD9")
		)
		(pad "2" smd rect
			(at 0 1.397 180)
			(size 1.651 1.27)
			(layers "F.Cu" "F.Mask" "F.Paste")
			(net "GND")
		)
	)
	(footprint ""
		(layer "F.Cu")
		(at 78.5622 -500.907304 180)
		(property "Reference" "C384"
			(at 0 0 180)
			(layer "F.SilkS")
			(hide yes)
			(effects
				(font
					(size 1.27 1.27)
				)
			)
		)
		(property "Value" "SCD033U25V2KX-GP"
			(at 1.1811 -2.7051 180)
			(unlocked yes)
			(layer "F.Fab")
			(hide yes)
			(effects
				(font
					(size 1.016 1.016)
					(thickness 0.1524)
				)
			)
		)
		(property "Device Type" "C402H22"
			(at 1.1811 -4.2291 180)
			(unlocked yes)
			(layer "F.Fab")
			(hide yes)
			(effects
				(font
					(size 1.016 1.016)
					(thickness 0.1524)
				)
			)
		)
		(duplicate_pad_numbers_are_jumpers no)
		(fp_rect
			(start -0.4318 0.9525)
			(end 0.4318 -0.9525)
			(stroke
				(width 0)
				(type default)
			)
			(fill no)
			(layer "F.CrtYd")
		)
		(fp_rect
			(start -0.4318 0.9525)
			(end 0.4318 -0.9525)
			(stroke
				(width 0)
				(type default)
			)
			(fill no)
			(layer "F.Fab")
		)
		(pad "1" smd custom
			(at 0 -0.4445 180)
			(size 0.1524 0.1524)
			(layers "F.Cu" "F.Mask" "F.Paste")
			(net "P12V")
			(options
				(clearance outline)
				(anchor circle)
			)
			(primitives
				(gr_poly
					(pts
						(arc
							(start 0.3048 -0.2032)
							(mid 0.275042 -0.275042)
							(end 0.2032 -0.3048)
						)
						(arc
							(start -0.2032 -0.3048)
							(mid -0.275042 -0.275042)
							(end -0.3048 -0.2032)
						)
						(arc
							(start -0.3048 0.2032)
							(mid -0.275042 0.275042)
							(end -0.2032 0.3048)
						)
						(arc
							(start 0.2032 0.3048)
							(mid 0.275042 0.275042)
							(end 0.3048 0.2032)
						)
					)
					(width 0)
					(fill yes)
				)
			)
		)
		(pad "2" smd custom
			(at 0 0.4445 180)
			(size 0.1524 0.1524)
			(layers "F.Cu" "F.Mask" "F.Paste")
			(net "SW_HDD5_N")
			(options
				(clearance outline)
				(anchor circle)
			)
			(primitives
				(gr_poly
					(pts
						(arc
							(start 0.3048 -0.2032)
							(mid 0.275042 -0.275042)
							(end 0.2032 -0.3048)
						)
						(arc
							(start -0.2032 -0.3048)
							(mid -0.275042 -0.275042)
							(end -0.3048 -0.2032)
						)
						(arc
							(start -0.3048 0.2032)
							(mid -0.275042 0.275042)
							(end -0.2032 0.3048)
						)
						(arc
							(start 0.2032 0.3048)
							(mid 0.275042 0.275042)
							(end 0.3048 0.2032)
						)
					)
					(width 0)
					(fill yes)
				)
			)
		)
	)
	(footprint ""
		(layer "F.Cu")
		(at 79.191358 -499.412514 90)
		(property "Reference" "R180"
			(at 0 0 90)
			(layer "F.SilkS")
			(hide yes)
			(effects
				(font
					(size 1.27 1.27)
				)
			)
		)
		(property "Value" "4K7R2J-2-GP"
			(at 0.064008 -3.993896 90)
			(unlocked yes)
			(layer "F.Fab")
			(hide yes)
			(effects
				(font
					(size 1.016 1.016)
					(thickness 0.1524)
				)
			)
		)
		(property "Device Type" "R402H16"
			(at 0.064008 -5.517896 90)
			(unlocked yes)
			(layer "F.Fab")
			(hide yes)
			(effects
				(font
					(size 1.016 1.016)
					(thickness 0.1524)
				)
			)
		)
		(duplicate_pad_numbers_are_jumpers no)
		(fp_line
			(start 0.508 -0.9398)
			(end -0.508 -0.9398)
			(stroke
				(width 0.1524)
				(type default)
			)
			(layer "F.SilkS")
		)
		(fp_line
			(start -0.508 -0.9398)
			(end -0.508 0.9398)
			(stroke
				(width 0.1524)
				(type default)
			)
			(layer "F.SilkS")
		)
		(fp_rect
			(start -0.508 0.9398)
			(end 0.508 -0.9398)
			(stroke
				(width 0)
				(type default)
			)
			(fill no)
			(layer "F.CrtYd")
		)
		(fp_rect
			(start -0.508 0.9398)
			(end 0.508 -0.9398)
			(stroke
				(width 0)
				(type default)
			)
			(fill no)
			(layer "F.Fab")
		)
		(pad "1" smd custom
			(at 0 -0.4445 90)
			(size 0.1397 0.1397)
			(layers "F.Cu" "F.Mask" "F.Paste")
			(net "P12V")
			(options
				(clearance outline)
				(anchor circle)
			)
			(primitives
				(gr_poly
					(pts
						(arc
							(start -0.1778 -0.2794)
							(mid -0.249642 -0.249642)
							(end -0.2794 -0.1778)
						)
						(arc
							(start -0.2794 0.1778)
							(mid -0.249642 0.249642)
							(end -0.1778 0.2794)
						)
						(arc
							(start 0.1778 0.2794)
							(mid 0.249642 0.249642)
							(end 0.2794 0.1778)
						)
						(arc
							(start 0.2794 -0.1778)
							(mid 0.249642 -0.249642)
							(end 0.1778 -0.2794)
						)
					)
					(width 0)
					(fill yes)
				)
			)
		)
		(pad "2" smd custom
			(at 0 0.4445 90)
			(size 0.1397 0.1397)
			(layers "F.Cu" "F.Mask" "F.Paste")
			(net "SW_HDD5_R")
			(options
				(clearance outline)
				(anchor circle)
			)
			(primitives
				(gr_poly
					(pts
						(arc
							(start -0.1778 -0.2794)
							(mid -0.249642 -0.249642)
							(end -0.2794 -0.1778)
						)
						(arc
							(start -0.2794 0.1778)
							(mid -0.249642 0.249642)
							(end -0.1778 0.2794)
						)
						(arc
							(start 0.1778 0.2794)
							(mid 0.249642 0.249642)
							(end 0.2794 0.1778)
						)
						(arc
							(start 0.2794 -0.1778)
							(mid 0.249642 -0.249642)
							(end 0.1778 -0.2794)
						)
					)
					(width 0)
					(fill yes)
				)
			)
		)
	)
	(footprint ""
		(layer "F.Cu")
		(at 61.976 -174.2948)
		(property "Reference" "Q62"
			(at 0 0 0)
			(layer "F.SilkS")
			(hide yes)
			(effects
				(font
					(size 1.27 1.27)
				)
			)
		)
		(property "Value" "2N7002DW-7F-GP"
			(at -2.3622 -8.2042 0)
			(unlocked yes)
			(layer "F.Fab")
			(hide yes)
			(effects
				(font
					(size 1.016 1.016)
					(thickness 0.1524)
				)
			)
		)
		(property "Device Type" "SOT-363H44"
			(at -2.3622 -10.1092 0)
			(unlocked yes)
			(layer "F.Fab")
			(hide yes)
			(effects
				(font
					(size 1.016 1.016)
					(thickness 0.1524)
				)
			)
		)
		(duplicate_pad_numbers_are_jumpers no)
		(fp_line
			(start -1.4478 -1.7018)
			(end -1.4478 1.7018)
			(stroke
				(width 0.1524)
				(type default)
			)
			(layer "F.SilkS")
		)
		(fp_line
			(start -1.4478 1.7018)
			(end 1.4478 1.7018)
			(stroke
				(width 0.1524)
				(type default)
			)
			(layer "F.SilkS")
		)
		(fp_line
			(start -1.27 1.524)
			(end -1.27 0.6604)
			(stroke
				(width 0.4826)
				(type default)
			)
			(layer "F.SilkS")
		)
		(fp_line
			(start 1.4478 -1.7018)
			(end -1.4478 -1.7018)
			(stroke
				(width 0.1524)
				(type default)
			)
			(layer "F.SilkS")
		)
		(fp_line
			(start 1.4478 1.7018)
			(end 1.4478 -1.7018)
			(stroke
				(width 0.1524)
				(type default)
			)
			(layer "F.SilkS")
		)
		(fp_poly
			(pts
				(xy -1.524 -1.778) (xy 1.524 -1.778) (xy 1.524 1.778) (xy -1.524 1.778)
			)
			(stroke
				(width 0)
				(type default)
			)
			(fill no)
			(layer "F.CrtYd")
		)
		(fp_poly
			(pts
				(xy -1.524 -1.778) (xy 1.524 -1.778) (xy 1.524 1.778) (xy -1.524 1.778)
			)
			(stroke
				(width 0)
				(type default)
			)
			(fill no)
			(layer "F.Fab")
		)
		(pad "1" smd rect
			(at -0.65024 0.9398)
			(size 0.4064 1.016)
			(layers "F.Cu" "F.Mask" "F.Paste")
			(net "P3V3_HDD8_LED")
		)
		(pad "2" smd rect
			(at 0 0.9398)
			(size 0.4064 1.016)
			(layers "F.Cu" "F.Mask" "F.Paste")
			(net "HDD8_LED_G")
		)
		(pad "3" smd rect
			(at 0.65024 0.9398)
			(size 0.4064 1.016)
			(layers "F.Cu" "F.Mask" "F.Paste")
			(net "P5VB")
		)
		(pad "4" smd rect
			(at 0.65024 -0.9398)
			(size 0.4064 1.016)
			(layers "F.Cu" "F.Mask" "F.Paste")
			(net "P5VB_HDD8_LED")
		)
		(pad "5" smd rect
			(at 0 -0.9398)
			(size 0.4064 1.016)
			(layers "F.Cu" "F.Mask" "F.Paste")
			(net "HDD8_LED_G")
		)
		(pad "6" smd rect
			(at -0.65024 -0.9398)
			(size 0.4064 1.016)
			(layers "F.Cu" "F.Mask" "F.Paste")
			(net "P3V3")
		)
	)
	(footprint ""
		(layer "F.Cu")
		(at 218.646756 -469.039702 -90)
		(property "Reference" "C100"
			(at 0 0 270)
			(layer "F.SilkS")
			(hide yes)
			(effects
				(font
					(size 1.27 1.27)
				)
			)
		)
		(property "Value" "SCD01U50V2KX-1GP"
			(at 1.1811 -2.7051 270)
			(unlocked yes)
			(layer "F.Fab")
			(hide yes)
			(effects
				(font
					(size 1.016 1.016)
					(thickness 0.1524)
				)
			)
		)
		(property "Device Type" "C402H22"
			(at 1.1811 -4.2291 270)
			(unlocked yes)
			(layer "F.Fab")
			(hide yes)
			(effects
				(font
					(size 1.016 1.016)
					(thickness 0.1524)
				)
			)
		)
		(duplicate_pad_numbers_are_jumpers no)
		(fp_rect
			(start -0.4318 0.9525)
			(end 0.4318 -0.9525)
			(stroke
				(width 0)
				(type default)
			)
			(fill no)
			(layer "F.CrtYd")
		)
		(fp_rect
			(start -0.4318 0.9525)
			(end 0.4318 -0.9525)
			(stroke
				(width 0)
				(type default)
			)
			(fill no)
			(layer "F.Fab")
		)
		(pad "1" smd custom
			(at 0 -0.4445 270)
			(size 0.1524 0.1524)
			(layers "F.Cu" "F.Mask" "F.Paste")
			(net "SAS2X28_DRIVE_RX_N_A0")
			(options
				(clearance outline)
				(anchor circle)
			)
			(primitives
				(gr_poly
					(pts
						(arc
							(start 0.3048 -0.2032)
							(mid 0.275042 -0.275042)
							(end 0.2032 -0.3048)
						)
						(arc
							(start -0.2032 -0.3048)
							(mid -0.275042 -0.275042)
							(end -0.3048 -0.2032)
						)
						(arc
							(start -0.3048 0.2032)
							(mid -0.275042 0.275042)
							(end -0.2032 0.3048)
						)
						(arc
							(start 0.2032 0.3048)
							(mid 0.275042 0.275042)
							(end 0.3048 0.2032)
						)
					)
					(width 0)
					(fill yes)
				)
			)
		)
		(pad "2" smd custom
			(at 0 0.4445 270)
			(size 0.1524 0.1524)
			(layers "F.Cu" "F.Mask" "F.Paste")
			(net "SAS2X28_A_HDD0_RX_-")
			(options
				(clearance outline)
				(anchor circle)
			)
			(primitives
				(gr_poly
					(pts
						(arc
							(start 0.3048 -0.2032)
							(mid 0.275042 -0.275042)
							(end 0.2032 -0.3048)
						)
						(arc
							(start -0.2032 -0.3048)
							(mid -0.275042 -0.275042)
							(end -0.3048 -0.2032)
						)
						(arc
							(start -0.3048 0.2032)
							(mid -0.275042 0.275042)
							(end -0.2032 0.3048)
						)
						(arc
							(start 0.2032 0.3048)
							(mid 0.275042 0.275042)
							(end 0.3048 0.2032)
						)
					)
					(width 0)
					(fill yes)
				)
			)
		)
	)
	(footprint ""
		(layer "F.Cu")
		(at 16.255746 -476.6437)
		(property "Reference" "PC39"
			(at 0 0 0)
			(layer "F.SilkS")
			(hide yes)
			(effects
				(font
					(size 1.27 1.27)
				)
			)
		)
		(property "Value" "SC10U16V6KX-2GP"
			(at -0.0762 -5.1308 0)
			(unlocked yes)
			(layer "F.Fab")
			(hide yes)
			(effects
				(font
					(size 1.016 1.016)
					(thickness 0.1524)
				)
			)
		)
		(property "Device Type" "C1206H71"
			(at -0.127 -6.6548 0)
			(unlocked yes)
			(layer "F.Fab")
			(hide yes)
			(effects
				(font
					(size 1.016 1.016)
					(thickness 0.1524)
				)
			)
		)
		(duplicate_pad_numbers_are_jumpers no)
		(fp_line
			(start -1.016 -2.2352)
			(end 1.016 -2.2352)
			(stroke
				(width 0.1524)
				(type default)
			)
			(layer "F.SilkS")
		)
		(fp_line
			(start -1.016 -0.8382)
			(end -1.016 -2.2352)
			(stroke
				(width 0.1524)
				(type default)
			)
			(layer "F.SilkS")
		)
		(fp_line
			(start -1.016 2.2352)
			(end -1.016 0.8382)
			(stroke
				(width 0.1524)
				(type default)
			)
			(layer "F.SilkS")
		)
		(fp_line
			(start 1.016 -2.2352)
			(end 1.016 -0.8382)
			(stroke
				(width 0.1524)
				(type default)
			)
			(layer "F.SilkS")
		)
		(fp_line
			(start 1.016 0.8382)
			(end 1.016 2.2352)
			(stroke
				(width 0.1524)
				(type default)
			)
			(layer "F.SilkS")
		)
		(fp_line
			(start 1.016 2.2352)
			(end -1.016 2.2352)
			(stroke
				(width 0.1524)
				(type default)
			)
			(layer "F.SilkS")
		)
		(fp_rect
			(start -1.0922 2.3114)
			(end 1.0922 -2.3114)
			(stroke
				(width 0)
				(type default)
			)
			(fill no)
			(layer "F.CrtYd")
		)
		(fp_poly
			(pts
				(xy 1.0922 -2.3114) (xy 1.0922 2.3114) (xy -1.0922 2.3114) (xy -1.0922 -2.3114)
			)
			(stroke
				(width 0)
				(type default)
			)
			(fill no)
			(layer "F.Fab")
		)
		(pad "1" smd rect
			(at 0 -1.397)
			(size 1.651 1.27)
			(layers "F.Cu" "F.Mask" "F.Paste")
			(net "P5VC")
		)
		(pad "2" smd rect
			(at 0 1.397)
			(size 1.651 1.27)
			(layers "F.Cu" "F.Mask" "F.Paste")
			(net "GND")
		)
	)
	(footprint ""
		(layer "F.Cu")
		(at 218.142058 -373.201184 -90)
		(property "Reference" "C121"
			(at 0 0 270)
			(layer "F.SilkS")
			(hide yes)
			(effects
				(font
					(size 1.27 1.27)
				)
			)
		)
		(property "Value" "SCD01U50V2KX-1GP"
			(at 1.1811 -2.7051 270)
			(unlocked yes)
			(layer "F.Fab")
			(hide yes)
			(effects
				(font
					(size 1.016 1.016)
					(thickness 0.1524)
				)
			)
		)
		(property "Device Type" "C402H22"
			(at 1.1811 -4.2291 270)
			(unlocked yes)
			(layer "F.Fab")
			(hide yes)
			(effects
				(font
					(size 1.016 1.016)
					(thickness 0.1524)
				)
			)
		)
		(duplicate_pad_numbers_are_jumpers no)
		(fp_rect
			(start -0.4318 0.9525)
			(end 0.4318 -0.9525)
			(stroke
				(width 0)
				(type default)
			)
			(fill no)
			(layer "F.CrtYd")
		)
		(fp_rect
			(start -0.4318 0.9525)
			(end 0.4318 -0.9525)
			(stroke
				(width 0)
				(type default)
			)
			(fill no)
			(layer "F.Fab")
		)
		(pad "1" smd custom
			(at 0 -0.4445 270)
			(size 0.1524 0.1524)
			(layers "F.Cu" "F.Mask" "F.Paste")
			(net "SAS2X28_DRIVE_RX_P_B1")
			(options
				(clearance outline)
				(anchor circle)
			)
			(primitives
				(gr_poly
					(pts
						(arc
							(start 0.3048 -0.2032)
							(mid 0.275042 -0.275042)
							(end 0.2032 -0.3048)
						)
						(arc
							(start -0.2032 -0.3048)
							(mid -0.275042 -0.275042)
							(end -0.3048 -0.2032)
						)
						(arc
							(start -0.3048 0.2032)
							(mid -0.275042 0.275042)
							(end -0.2032 0.3048)
						)
						(arc
							(start 0.2032 0.3048)
							(mid 0.275042 0.275042)
							(end 0.3048 0.2032)
						)
					)
					(width 0)
					(fill yes)
				)
			)
		)
		(pad "2" smd custom
			(at 0 0.4445 270)
			(size 0.1524 0.1524)
			(layers "F.Cu" "F.Mask" "F.Paste")
			(net "SAS2X28_B_HDD1_RX_+")
			(options
				(clearance outline)
				(anchor circle)
			)
			(primitives
				(gr_poly
					(pts
						(arc
							(start 0.3048 -0.2032)
							(mid 0.275042 -0.275042)
							(end 0.2032 -0.3048)
						)
						(arc
							(start -0.2032 -0.3048)
							(mid -0.275042 -0.275042)
							(end -0.3048 -0.2032)
						)
						(arc
							(start -0.3048 0.2032)
							(mid -0.275042 0.275042)
							(end -0.2032 0.3048)
						)
						(arc
							(start 0.2032 0.3048)
							(mid 0.275042 0.275042)
							(end 0.3048 0.2032)
						)
					)
					(width 0)
					(fill yes)
				)
			)
		)
	)
	(footprint ""
		(layer "F.Cu")
		(at 29.844746 -332.3717)
		(property "Reference" "U34"
			(at 0 0 0)
			(layer "F.SilkS")
			(hide yes)
			(effects
				(font
					(size 1.27 1.27)
				)
			)
		)
		(property "Value" "74LVC1G08GW-1-GP"
			(at -2.3368 -8.6868 0)
			(unlocked yes)
			(layer "F.Fab")
			(hide yes)
			(effects
				(font
					(size 1.016 1.016)
					(thickness 0.1524)
				)
			)
		)
		(property "Device Type" "SC70-5H44"
			(at -2.3114 -10.414 0)
			(unlocked yes)
			(layer "F.Fab")
			(hide yes)
			(effects
				(font
					(size 1.016 1.016)
					(thickness 0.1524)
				)
			)
		)
		(duplicate_pad_numbers_are_jumpers no)
		(fp_line
			(start -1.27 -1.7018)
			(end 1.27 -1.7018)
			(stroke
				(width 0.1524)
				(type default)
			)
			(layer "F.SilkS")
		)
		(fp_line
			(start -1.27 1.7018)
			(end -1.27 -1.7018)
			(stroke
				(width 0.1524)
				(type default)
			)
			(layer "F.SilkS")
		)
		(fp_line
			(start 0.6604 -1.8034)
			(end 1.3843 -1.8034)
			(stroke
				(width 0.3302)
				(type default)
			)
			(layer "F.SilkS")
		)
		(fp_line
			(start 1.27 -1.7018)
			(end 1.27 1.7018)
			(stroke
				(width 0.1524)
				(type default)
			)
			(layer "F.SilkS")
		)
		(fp_line
			(start 1.27 1.7018)
			(end -1.27 1.7018)
			(stroke
				(width 0.1524)
				(type default)
			)
			(layer "F.SilkS")
		)
		(fp_line
			(start 1.3843 -1.8034)
			(end 1.3843 -1.1176)
			(stroke
				(width 0.3302)
				(type default)
			)
			(layer "F.SilkS")
		)
		(fp_rect
			(start -1.524 1.9558)
			(end 1.524 -1.9558)
			(stroke
				(width 0)
				(type default)
			)
			(fill no)
			(layer "F.CrtYd")
		)
		(fp_poly
			(pts
				(xy -1.524 -1.9558) (xy 1.524 -1.9558) (xy 1.524 1.9558) (xy -1.524 1.9558)
			)
			(stroke
				(width 0)
				(type default)
			)
			(fill no)
			(layer "F.Fab")
		)
		(pad "1" smd rect
			(at 0.65024 -0.8255)
			(size 0.4064 1.2192)
			(layers "F.Cu" "F.Mask" "F.Paste")
			(net "SAS2X28_B_HDD11_FLT")
		)
		(pad "2" smd rect
			(at 0 -0.8255)
			(size 0.4064 1.2192)
			(layers "F.Cu" "F.Mask" "F.Paste")
			(net "SAS2X28_A_HDD11_FLT")
		)
		(pad "3" smd rect
			(at -0.65024 -0.8255)
			(size 0.4064 1.2192)
			(layers "F.Cu" "F.Mask" "F.Paste")
			(net "GND")
		)
		(pad "4" smd rect
			(at -0.65024 0.8255)
			(size 0.4064 1.2192)
			(layers "F.Cu" "F.Mask" "F.Paste")
			(net "FLT_HDD11_DRIVE")
		)
		(pad "5" smd rect
			(at 0.65024 0.8255)
			(size 0.4064 1.2192)
			(layers "F.Cu" "F.Mask" "F.Paste")
			(net "P3V3")
		)
	)
	(footprint ""
		(layer "F.Cu")
		(at 191.897 -498.094 90)
		(property "Reference" "R108"
			(at 0 0 90)
			(layer "F.SilkS")
			(hide yes)
			(effects
				(font
					(size 1.27 1.27)
				)
			)
		)
		(property "Value" "4K7R2J-2-GP"
			(at 0.064008 -3.993896 90)
			(unlocked yes)
			(layer "F.Fab")
			(hide yes)
			(effects
				(font
					(size 1.016 1.016)
					(thickness 0.1524)
				)
			)
		)
		(property "Device Type" "R402H16"
			(at 0.064008 -5.517896 90)
			(unlocked yes)
			(layer "F.Fab")
			(hide yes)
			(effects
				(font
					(size 1.016 1.016)
					(thickness 0.1524)
				)
			)
		)
		(duplicate_pad_numbers_are_jumpers no)
		(fp_line
			(start 0.508 -0.9398)
			(end -0.508 -0.9398)
			(stroke
				(width 0.1524)
				(type default)
			)
			(layer "F.SilkS")
		)
		(fp_line
			(start -0.508 -0.9398)
			(end -0.508 0.9398)
			(stroke
				(width 0.1524)
				(type default)
			)
			(layer "F.SilkS")
		)
		(fp_rect
			(start -0.508 0.9398)
			(end 0.508 -0.9398)
			(stroke
				(width 0)
				(type default)
			)
			(fill no)
			(layer "F.CrtYd")
		)
		(fp_rect
			(start -0.508 0.9398)
			(end 0.508 -0.9398)
			(stroke
				(width 0)
				(type default)
			)
			(fill no)
			(layer "F.Fab")
		)
		(pad "1" smd custom
			(at 0 -0.4445 90)
			(size 0.1397 0.1397)
			(layers "F.Cu" "F.Mask" "F.Paste")
			(net "P12V")
			(options
				(clearance outline)
				(anchor circle)
			)
			(primitives
				(gr_poly
					(pts
						(arc
							(start -0.1778 -0.2794)
							(mid -0.249642 -0.249642)
							(end -0.2794 -0.1778)
						)
						(arc
							(start -0.2794 0.1778)
							(mid -0.249642 0.249642)
							(end -0.1778 0.2794)
						)
						(arc
							(start 0.1778 0.2794)
							(mid 0.249642 0.249642)
							(end 0.2794 0.1778)
						)
						(arc
							(start 0.2794 -0.1778)
							(mid 0.249642 -0.249642)
							(end 0.1778 -0.2794)
						)
					)
					(width 0)
					(fill yes)
				)
			)
		)
		(pad "2" smd custom
			(at 0 0.4445 90)
			(size 0.1397 0.1397)
			(layers "F.Cu" "F.Mask" "F.Paste")
			(net "SW_HDD0_R")
			(options
				(clearance outline)
				(anchor circle)
			)
			(primitives
				(gr_poly
					(pts
						(arc
							(start -0.1778 -0.2794)
							(mid -0.249642 -0.249642)
							(end -0.2794 -0.1778)
						)
						(arc
							(start -0.2794 0.1778)
							(mid -0.249642 0.249642)
							(end -0.1778 0.2794)
						)
						(arc
							(start 0.1778 0.2794)
							(mid 0.249642 0.249642)
							(end 0.2794 0.1778)
						)
						(arc
							(start 0.2794 -0.1778)
							(mid 0.249642 -0.249642)
							(end 0.1778 -0.2794)
						)
					)
					(width 0)
					(fill yes)
				)
			)
		)
	)
	(footprint ""
		(layer "F.Cu")
		(at 45.212 -106.807 90)
		(property "Reference" "R561"
			(at 0 0 90)
			(layer "F.SilkS")
			(hide yes)
			(effects
				(font
					(size 1.27 1.27)
				)
			)
		)
		(property "Value" "200KR2F-L-GP"
			(at 0.064008 -3.993896 90)
			(unlocked yes)
			(layer "F.Fab")
			(hide yes)
			(effects
				(font
					(size 1.016 1.016)
					(thickness 0.1524)
				)
			)
		)
		(property "Device Type" "R402H16"
			(at 0.064008 -5.517896 90)
			(unlocked yes)
			(layer "F.Fab")
			(hide yes)
			(effects
				(font
					(size 1.016 1.016)
					(thickness 0.1524)
				)
			)
		)
		(duplicate_pad_numbers_are_jumpers no)
		(fp_line
			(start 0.508 -0.9398)
			(end -0.508 -0.9398)
			(stroke
				(width 0.1524)
				(type default)
			)
			(layer "F.SilkS")
		)
		(fp_line
			(start -0.508 -0.9398)
			(end -0.508 0.9398)
			(stroke
				(width 0.1524)
				(type default)
			)
			(layer "F.SilkS")
		)
		(fp_rect
			(start -0.508 0.9398)
			(end 0.508 -0.9398)
			(stroke
				(width 0)
				(type default)
			)
			(fill no)
			(layer "F.CrtYd")
		)
		(fp_rect
			(start -0.508 0.9398)
			(end 0.508 -0.9398)
			(stroke
				(width 0)
				(type default)
			)
			(fill no)
			(layer "F.Fab")
		)
		(pad "1" smd custom
			(at 0 -0.4445 90)
			(size 0.1397 0.1397)
			(layers "F.Cu" "F.Mask" "F.Paste")
			(net "SW_HDD13_R")
			(options
				(clearance outline)
				(anchor circle)
			)
			(primitives
				(gr_poly
					(pts
						(arc
							(start -0.1778 -0.2794)
							(mid -0.249642 -0.249642)
							(end -0.2794 -0.1778)
						)
						(arc
							(start -0.2794 0.1778)
							(mid -0.249642 0.249642)
							(end -0.1778 0.2794)
						)
						(arc
							(start 0.1778 0.2794)
							(mid 0.249642 0.249642)
							(end 0.2794 0.1778)
						)
						(arc
							(start 0.2794 -0.1778)
							(mid 0.249642 -0.249642)
							(end 0.1778 -0.2794)
						)
					)
					(width 0)
					(fill yes)
				)
			)
		)
		(pad "2" smd custom
			(at 0 0.4445 90)
			(size 0.1397 0.1397)
			(layers "F.Cu" "F.Mask" "F.Paste")
			(net "SW_HDD13_N")
			(options
				(clearance outline)
				(anchor circle)
			)
			(primitives
				(gr_poly
					(pts
						(arc
							(start -0.1778 -0.2794)
							(mid -0.249642 -0.249642)
							(end -0.2794 -0.1778)
						)
						(arc
							(start -0.2794 0.1778)
							(mid -0.249642 0.249642)
							(end -0.1778 0.2794)
						)
						(arc
							(start 0.1778 0.2794)
							(mid 0.249642 0.249642)
							(end 0.2794 0.1778)
						)
						(arc
							(start 0.2794 -0.1778)
							(mid 0.249642 -0.249642)
							(end 0.1778 -0.2794)
						)
					)
					(width 0)
					(fill yes)
				)
			)
		)
	)
	(footprint ""
		(layer "F.Cu")
		(at 232.257346 -141.6812 -90)
		(property "Reference" "R491"
			(at 0 0 270)
			(layer "F.SilkS")
			(hide yes)
			(effects
				(font
					(size 1.27 1.27)
				)
			)
		)
		(property "Value" "1KR2F-3-GP"
			(at 0.064008 -3.993896 270)
			(unlocked yes)
			(layer "F.Fab")
			(hide yes)
			(effects
				(font
					(size 1.016 1.016)
					(thickness 0.1524)
				)
			)
		)
		(property "Device Type" "R402H16"
			(at 0.064008 -5.517896 270)
			(unlocked yes)
			(layer "F.Fab")
			(hide yes)
			(effects
				(font
					(size 1.016 1.016)
					(thickness 0.1524)
				)
			)
		)
		(duplicate_pad_numbers_are_jumpers no)
		(fp_line
			(start -0.508 -0.9398)
			(end -0.508 0.9398)
			(stroke
				(width 0.1524)
				(type default)
			)
			(layer "F.SilkS")
		)
		(fp_line
			(start 0.508 -0.9398)
			(end -0.508 -0.9398)
			(stroke
				(width 0.1524)
				(type default)
			)
			(layer "F.SilkS")
		)
		(fp_rect
			(start -0.508 0.9398)
			(end 0.508 -0.9398)
			(stroke
				(width 0)
				(type default)
			)
			(fill no)
			(layer "F.CrtYd")
		)
		(fp_rect
			(start -0.508 0.9398)
			(end 0.508 -0.9398)
			(stroke
				(width 0)
				(type default)
			)
			(fill no)
			(layer "F.Fab")
		)
		(pad "1" smd custom
			(at 0 -0.4445 270)
			(size 0.1397 0.1397)
			(layers "F.Cu" "F.Mask" "F.Paste")
			(net "FLT_HDD3_B")
			(options
				(clearance outline)
				(anchor circle)
			)
			(primitives
				(gr_poly
					(pts
						(arc
							(start -0.1778 -0.2794)
							(mid -0.249642 -0.249642)
							(end -0.2794 -0.1778)
						)
						(arc
							(start -0.2794 0.1778)
							(mid -0.249642 0.249642)
							(end -0.1778 0.2794)
						)
						(arc
							(start 0.1778 0.2794)
							(mid 0.249642 0.249642)
							(end 0.2794 0.1778)
						)
						(arc
							(start 0.2794 -0.1778)
							(mid 0.249642 -0.249642)
							(end 0.1778 -0.2794)
						)
					)
					(width 0)
					(fill yes)
				)
			)
		)
		(pad "2" smd custom
			(at 0 0.4445 270)
			(size 0.1397 0.1397)
			(layers "F.Cu" "F.Mask" "F.Paste")
			(net "FLT_HDD3_DRIVE")
			(options
				(clearance outline)
				(anchor circle)
			)
			(primitives
				(gr_poly
					(pts
						(arc
							(start -0.1778 -0.2794)
							(mid -0.249642 -0.249642)
							(end -0.2794 -0.1778)
						)
						(arc
							(start -0.2794 0.1778)
							(mid -0.249642 0.249642)
							(end -0.1778 0.2794)
						)
						(arc
							(start 0.1778 0.2794)
							(mid 0.249642 0.249642)
							(end 0.2794 0.1778)
						)
						(arc
							(start 0.2794 -0.1778)
							(mid 0.249642 -0.249642)
							(end 0.1778 -0.2794)
						)
					)
					(width 0)
					(fill yes)
				)
			)
		)
	)
	(footprint ""
		(layer "F.Cu")
		(at 42.8244 -107.7722 90)
		(property "Reference" "R421"
			(at 0 0 90)
			(layer "F.SilkS")
			(hide yes)
			(effects
				(font
					(size 1.27 1.27)
				)
			)
		)
		(property "Value" "0R2J-2-GP"
			(at 0.064008 -3.993896 90)
			(unlocked yes)
			(layer "F.Fab")
			(hide yes)
			(effects
				(font
					(size 1.016 1.016)
					(thickness 0.1524)
				)
			)
		)
		(property "Device Type" "R402H16"
			(at 0.064008 -5.517896 90)
			(unlocked yes)
			(layer "F.Fab")
			(hide yes)
			(effects
				(font
					(size 1.016 1.016)
					(thickness 0.1524)
				)
			)
		)
		(duplicate_pad_numbers_are_jumpers no)
		(fp_line
			(start 0.508 -0.9398)
			(end -0.508 -0.9398)
			(stroke
				(width 0.1524)
				(type default)
			)
			(layer "F.SilkS")
		)
		(fp_line
			(start -0.508 -0.9398)
			(end -0.508 0.9398)
			(stroke
				(width 0.1524)
				(type default)
			)
			(layer "F.SilkS")
		)
		(fp_rect
			(start -0.508 0.9398)
			(end 0.508 -0.9398)
			(stroke
				(width 0)
				(type default)
			)
			(fill no)
			(layer "F.CrtYd")
		)
		(fp_rect
			(start -0.508 0.9398)
			(end 0.508 -0.9398)
			(stroke
				(width 0)
				(type default)
			)
			(fill no)
			(layer "F.Fab")
		)
		(pad "1" smd custom
			(at 0 -0.4445 90)
			(size 0.1397 0.1397)
			(layers "F.Cu" "F.Mask" "F.Paste")
			(net "SW_HDD13_G")
			(options
				(clearance outline)
				(anchor circle)
			)
			(primitives
				(gr_poly
					(pts
						(arc
							(start -0.1778 -0.2794)
							(mid -0.249642 -0.249642)
							(end -0.2794 -0.1778)
						)
						(arc
							(start -0.2794 0.1778)
							(mid -0.249642 0.249642)
							(end -0.1778 0.2794)
						)
						(arc
							(start 0.1778 0.2794)
							(mid 0.249642 0.249642)
							(end 0.2794 0.1778)
						)
						(arc
							(start 0.2794 -0.1778)
							(mid 0.249642 -0.249642)
							(end 0.1778 -0.2794)
						)
					)
					(width 0)
					(fill yes)
				)
			)
		)
		(pad "2" smd custom
			(at 0 0.4445 90)
			(size 0.1397 0.1397)
			(layers "F.Cu" "F.Mask" "F.Paste")
			(net "SW_HDD13_R")
			(options
				(clearance outline)
				(anchor circle)
			)
			(primitives
				(gr_poly
					(pts
						(arc
							(start -0.1778 -0.2794)
							(mid -0.249642 -0.249642)
							(end -0.2794 -0.1778)
						)
						(arc
							(start -0.2794 0.1778)
							(mid -0.249642 0.249642)
							(end -0.1778 0.2794)
						)
						(arc
							(start 0.1778 0.2794)
							(mid 0.249642 0.249642)
							(end 0.2794 0.1778)
						)
						(arc
							(start 0.2794 -0.1778)
							(mid 0.249642 -0.249642)
							(end 0.1778 -0.2794)
						)
					)
					(width 0)
					(fill yes)
				)
			)
		)
	)
	(footprint ""
		(layer "F.Cu")
		(at 52.197 -420.497 90)
		(property "Reference" "D25"
			(at 0 0 90)
			(layer "F.SilkS")
			(hide yes)
			(effects
				(font
					(size 1.27 1.27)
				)
			)
		)
		(property "Value" "RB551V30-1-GP"
			(at 0 -6.7818 90)
			(unlocked yes)
			(layer "F.Fab")
			(hide yes)
			(effects
				(font
					(size 1.016 1.016)
					(thickness 0.1524)
				)
			)
		)
		(property "Device Type" "SOD323AKH44"
			(at 0 -8.6868 90)
			(unlocked yes)
			(layer "F.Fab")
			(hide yes)
			(effects
				(font
					(size 1.016 1.016)
					(thickness 0.1524)
				)
			)
		)
		(duplicate_pad_numbers_are_jumpers no)
		(fp_line
			(start 0.889 -1.9304)
			(end 0.889 2.159)
			(stroke
				(width 0.1524)
				(type default)
			)
			(layer "F.SilkS")
		)
		(fp_line
			(start -0.889 -1.9304)
			(end 0.889 -1.9304)
			(stroke
				(width 0.1524)
				(type default)
			)
			(layer "F.SilkS")
		)
		(fp_line
			(start 0.762 2.0574)
			(end -0.762 2.0574)
			(stroke
				(width 0.508)
				(type default)
			)
			(layer "F.SilkS")
		)
		(fp_line
			(start 0.889 2.159)
			(end -0.889 2.159)
			(stroke
				(width 0.1524)
				(type default)
			)
			(layer "F.SilkS")
		)
		(fp_line
			(start -0.889 2.159)
			(end -0.889 -1.9304)
			(stroke
				(width 0.1524)
				(type default)
			)
			(layer "F.SilkS")
		)
		(fp_rect
			(start -1.016 2.3114)
			(end 1.016 -2.0066)
			(stroke
				(width 0)
				(type default)
			)
			(fill no)
			(layer "F.CrtYd")
		)
		(fp_poly
			(pts
				(xy -1.016 -2.0066) (xy 1.016 -2.0066) (xy 1.016 2.3114) (xy -1.016 2.3114)
			)
			(stroke
				(width 0)
				(type default)
			)
			(fill no)
			(layer "F.Fab")
		)
		(pad "A" smd rect
			(at 0 -1.143 90)
			(size 0.5588 1.016)
			(layers "F.Cu" "F.Mask" "F.Paste")
			(net "SW_HDD10_R")
		)
		(pad "K" smd rect
			(at 0 1.143 90)
			(size 0.5588 1.016)
			(layers "F.Cu" "F.Mask" "F.Paste")
			(net "SW_HDD10_N")
		)
	)
	(footprint ""
		(layer "F.Cu")
		(at 54.228746 -25.2857)
		(property "Reference" "PC19"
			(at 0 0 0)
			(layer "F.SilkS")
			(hide yes)
			(effects
				(font
					(size 1.27 1.27)
				)
			)
		)
		(property "Value" "SC680P50V2KX-2GP"
			(at 1.1811 -2.7051 0)
			(unlocked yes)
			(layer "F.Fab")
			(hide yes)
			(effects
				(font
					(size 1.016 1.016)
					(thickness 0.1524)
				)
			)
		)
		(property "Device Type" "C402H22"
			(at 1.1811 -4.2291 0)
			(unlocked yes)
			(layer "F.Fab")
			(hide yes)
			(effects
				(font
					(size 1.016 1.016)
					(thickness 0.1524)
				)
			)
		)
		(duplicate_pad_numbers_are_jumpers no)
		(fp_rect
			(start -0.4318 0.9525)
			(end 0.4318 -0.9525)
			(stroke
				(width 0)
				(type default)
			)
			(fill no)
			(layer "F.CrtYd")
		)
		(fp_rect
			(start -0.4318 0.9525)
			(end 0.4318 -0.9525)
			(stroke
				(width 0)
				(type default)
			)
			(fill no)
			(layer "F.Fab")
		)
		(pad "1" smd custom
			(at 0 -0.4445)
			(size 0.1524 0.1524)
			(layers "F.Cu" "F.Mask" "F.Paste")
			(net "P5VB_LL_NET")
			(options
				(clearance outline)
				(anchor circle)
			)
			(primitives
				(gr_poly
					(pts
						(arc
							(start 0.3048 -0.2032)
							(mid 0.275042 -0.275042)
							(end 0.2032 -0.3048)
						)
						(arc
							(start -0.2032 -0.3048)
							(mid -0.275042 -0.275042)
							(end -0.3048 -0.2032)
						)
						(arc
							(start -0.3048 0.2032)
							(mid -0.275042 0.275042)
							(end -0.2032 0.3048)
						)
						(arc
							(start 0.2032 0.3048)
							(mid 0.275042 0.275042)
							(end 0.3048 0.2032)
						)
					)
					(width 0)
					(fill yes)
				)
			)
		)
		(pad "2" smd custom
			(at 0 0.4445)
			(size 0.1524 0.1524)
			(layers "F.Cu" "F.Mask" "F.Paste")
			(net "P5VB_VFB")
			(options
				(clearance outline)
				(anchor circle)
			)
			(primitives
				(gr_poly
					(pts
						(arc
							(start 0.3048 -0.2032)
							(mid 0.275042 -0.275042)
							(end 0.2032 -0.3048)
						)
						(arc
							(start -0.2032 -0.3048)
							(mid -0.275042 -0.275042)
							(end -0.3048 -0.2032)
						)
						(arc
							(start -0.3048 0.2032)
							(mid -0.275042 0.275042)
							(end -0.2032 0.3048)
						)
						(arc
							(start 0.2032 0.3048)
							(mid 0.275042 0.275042)
							(end 0.3048 0.2032)
						)
					)
					(width 0)
					(fill yes)
				)
			)
		)
	)
	(footprint ""
		(layer "F.Cu")
		(at 206.469742 -76.192634 90)
		(property "Reference" "Q9"
			(at 0 0 90)
			(layer "F.SilkS")
			(hide yes)
			(effects
				(font
					(size 1.27 1.27)
				)
			)
		)
		(property "Value" "AO4406AL-GP"
			(at -3.707384 -1.5367 90)
			(unlocked yes)
			(layer "F.Fab")
			(hide yes)
			(effects
				(font
					(size 1.016 1.016)
					(thickness 0.1524)
				)
			)
		)
		(property "Device Type" "SOIC8H69"
			(at -3.707384 -3.0607 90)
			(unlocked yes)
			(layer "F.Fab")
			(hide yes)
			(effects
				(font
					(size 1.016 1.016)
					(thickness 0.1524)
				)
			)
		)
		(duplicate_pad_numbers_are_jumpers no)
		(fp_line
			(start 2.1336 -1.4224)
			(end -2.7432 -1.4224)
			(stroke
				(width 0.1524)
				(type default)
			)
			(layer "F.SilkS")
		)
		(fp_line
			(start -2.7432 -1.4224)
			(end -2.7432 1.4224)
			(stroke
				(width 0.1524)
				(type default)
			)
			(layer "F.SilkS")
		)
		(fp_line
			(start -2.7178 -0.508)
			(end -2.1844 -0.0508)
			(stroke
				(width 0.1524)
				(type default)
			)
			(layer "F.SilkS")
		)
		(fp_line
			(start -2.1844 -0.0508)
			(end -2.7178 0.508)
			(stroke
				(width 0.1524)
				(type default)
			)
			(layer "F.SilkS")
		)
		(fp_line
			(start 2.1336 1.4224)
			(end 2.1336 -1.4224)
			(stroke
				(width 0.1524)
				(type default)
			)
			(layer "F.SilkS")
		)
		(fp_line
			(start -2.7432 1.4224)
			(end 2.1336 1.4224)
			(stroke
				(width 0.1524)
				(type default)
			)
			(layer "F.SilkS")
		)
		(fp_line
			(start -2.7432 1.4224)
			(end -2.6416 1.4224)
			(stroke
				(width 0.1524)
				(type default)
			)
			(layer "F.SilkS")
		)
		(fp_line
			(start -2.6289 3.4417)
			(end -2.6289 1.4732)
			(stroke
				(width 0.381)
				(type default)
			)
			(layer "F.SilkS")
		)
		(fp_poly
			(pts
				(xy -2.2098 -1.4224) (xy -2.2098 1.4224) (xy 2.2098 1.4224) (xy 2.2098 -1.4224)
			)
			(stroke
				(width 0)
				(type default)
			)
			(fill yes)
			(layer "F.SilkS")
		)
		(fp_rect
			(start -2.450084 2.999994)
			(end 2.450084 -2.999994)
			(stroke
				(width 0)
				(type default)
			)
			(fill no)
			(layer "F.CrtYd")
		)
		(fp_poly
			(pts
				(xy -2.8194 3.6322) (xy -2.8194 -3.6322) (xy 2.8194 -3.6322) (xy 2.8194 1.18364) (xy 2.450084 1.18364)
				(xy 2.450084 -2.999994) (xy -2.450084 -2.999994) (xy -2.450084 2.999994) (xy 2.450084 2.999994)
				(xy 2.450084 1.18618) (xy 2.8194 1.18618) (xy 2.8194 3.6322)
			)
			(stroke
				(width 0)
				(type default)
			)
			(fill no)
			(layer "F.CrtYd")
		)
		(fp_rect
			(start -2.8194 3.6322)
			(end 2.8194 -3.6322)
			(stroke
				(width 0)
				(type default)
			)
			(fill no)
			(layer "F.Fab")
		)
		(pad "1" smd rect
			(at -1.905 2.54 90)
			(size 0.635 1.651)
			(layers "F.Cu" "F.Mask" "F.Paste")
			(net "P5V_HDD4")
		)
		(pad "2" smd rect
			(at -0.635 2.54 90)
			(size 0.635 1.651)
			(layers "F.Cu" "F.Mask" "F.Paste")
			(net "P5V_HDD4")
		)
		(pad "3" smd rect
			(at 0.635 2.54 90)
			(size 0.635 1.651)
			(layers "F.Cu" "F.Mask" "F.Paste")
			(net "P5V_HDD4")
		)
		(pad "4" smd rect
			(at 1.905 2.54 90)
			(size 0.635 1.651)
			(layers "F.Cu" "F.Mask" "F.Paste")
			(net "SW_HDD4_P")
		)
		(pad "5" smd rect
			(at 1.905 -2.54 90)
			(size 0.635 1.651)
			(layers "F.Cu" "F.Mask" "F.Paste")
			(net "P5VA")
		)
		(pad "6" smd rect
			(at 0.635 -2.54 90)
			(size 0.635 1.651)
			(layers "F.Cu" "F.Mask" "F.Paste")
			(net "P5VA")
		)
		(pad "7" smd rect
			(at -0.635 -2.54 90)
			(size 0.635 1.651)
			(layers "F.Cu" "F.Mask" "F.Paste")
			(net "P5VA")
		)
		(pad "8" smd rect
			(at -1.905 -2.54 90)
			(size 0.635 1.651)
			(layers "F.Cu" "F.Mask" "F.Paste")
			(net "P5VA")
		)
	)
	(footprint ""
		(layer "F.Cu")
		(at 68.999608 -376.999754)
		(property "Reference" "H3"
			(at 0 0 0)
			(layer "F.SilkS")
			(hide yes)
			(effects
				(font
					(size 1.27 1.27)
				)
			)
		)
		(property "Value" "HOLE315R140"
			(at 0 -7.5692 0)
			(unlocked yes)
			(layer "F.Fab")
			(hide yes)
			(effects
				(font
					(size 1.016 1.016)
					(thickness 0.1524)
				)
			)
		)
		(property "Device Type" "HOLE315R140"
			(at 0 -9.0932 0)
			(unlocked yes)
			(layer "F.Fab")
			(hide yes)
			(effects
				(font
					(size 1.016 1.016)
					(thickness 0.1524)
				)
			)
		)
		(duplicate_pad_numbers_are_jumpers no)
		(fp_poly
			(pts
				(arc
					(start 4.3053 0)
					(mid -4.3053 0)
					(end 4.3053 0)
				)
			)
			(stroke
				(width 0)
				(type default)
			)
			(fill no)
			(layer "F.CrtYd")
		)
		(fp_poly
			(pts
				(arc
					(start 4.3053 0)
					(mid -4.3053 0)
					(end 4.3053 0)
				)
			)
			(stroke
				(width 0)
				(type default)
			)
			(fill no)
			(layer "F.Fab")
		)
		(pad "1" thru_hole circle
			(at 0.00127 0.00127)
			(size 8.001 8.001)
			(drill 3.556)
			(layers "*.Cu" "*.Mask")
			(remove_unused_layers no)
			(net "GND")
			(clearance -1.7145)
			(thermal_gap 0.3048)
			(padstack
				(mode front_inner_back)
				(layer "Inner"
					(shape circle)
					(size 3.9624 3.9624)
					(clearance 0.3048)
				)
				(layer "B.Cu"
					(shape circle)
					(size 8.001 8.001)
					(clearance -1.7145)
				)
			)
		)
	)
	(footprint ""
		(layer "F.Cu")
		(at 214.8332 -275.1328 -90)
		(property "Reference" "R365"
			(at 0 0 270)
			(layer "F.SilkS")
			(hide yes)
			(effects
				(font
					(size 1.27 1.27)
				)
			)
		)
		(property "Value" "0R2J-2-GP"
			(at 0.064008 -3.993896 270)
			(unlocked yes)
			(layer "F.Fab")
			(hide yes)
			(effects
				(font
					(size 1.016 1.016)
					(thickness 0.1524)
				)
			)
		)
		(property "Device Type" "R402H16"
			(at 0.064008 -5.517896 270)
			(unlocked yes)
			(layer "F.Fab")
			(hide yes)
			(effects
				(font
					(size 1.016 1.016)
					(thickness 0.1524)
				)
			)
		)
		(duplicate_pad_numbers_are_jumpers no)
		(fp_line
			(start -0.508 -0.9398)
			(end -0.508 0.9398)
			(stroke
				(width 0.1524)
				(type default)
			)
			(layer "F.SilkS")
		)
		(fp_line
			(start 0.508 -0.9398)
			(end -0.508 -0.9398)
			(stroke
				(width 0.1524)
				(type default)
			)
			(layer "F.SilkS")
		)
		(fp_rect
			(start -0.508 0.9398)
			(end 0.508 -0.9398)
			(stroke
				(width 0)
				(type default)
			)
			(fill no)
			(layer "F.CrtYd")
		)
		(fp_rect
			(start -0.508 0.9398)
			(end 0.508 -0.9398)
			(stroke
				(width 0)
				(type default)
			)
			(fill no)
			(layer "F.Fab")
		)
		(pad "1" smd custom
			(at 0 -0.4445 270)
			(size 0.1397 0.1397)
			(layers "F.Cu" "F.Mask" "F.Paste")
			(net "HDD_PRSNT_NET2")
			(options
				(clearance outline)
				(anchor circle)
			)
			(primitives
				(gr_poly
					(pts
						(arc
							(start -0.1778 -0.2794)
							(mid -0.249642 -0.249642)
							(end -0.2794 -0.1778)
						)
						(arc
							(start -0.2794 0.1778)
							(mid -0.249642 0.249642)
							(end -0.1778 0.2794)
						)
						(arc
							(start 0.1778 0.2794)
							(mid 0.249642 0.249642)
							(end 0.2794 0.1778)
						)
						(arc
							(start 0.2794 -0.1778)
							(mid 0.249642 -0.249642)
							(end 0.1778 -0.2794)
						)
					)
					(width 0)
					(fill yes)
				)
			)
		)
		(pad "2" smd custom
			(at 0 0.4445 270)
			(size 0.1397 0.1397)
			(layers "F.Cu" "F.Mask" "F.Paste")
			(net "HDD2_LED_B")
			(options
				(clearance outline)
				(anchor circle)
			)
			(primitives
				(gr_poly
					(pts
						(arc
							(start -0.1778 -0.2794)
							(mid -0.249642 -0.249642)
							(end -0.2794 -0.1778)
						)
						(arc
							(start -0.2794 0.1778)
							(mid -0.249642 0.249642)
							(end -0.1778 0.2794)
						)
						(arc
							(start 0.1778 0.2794)
							(mid 0.249642 0.249642)
							(end 0.2794 0.1778)
						)
						(arc
							(start 0.2794 -0.1778)
							(mid 0.249642 -0.249642)
							(end 0.1778 -0.2794)
						)
					)
					(width 0)
					(fill yes)
				)
			)
		)
	)
	(footprint ""
		(layer "F.Cu")
		(at 26.415746 -314.4647)
		(property "Reference" "C291"
			(at 0 0 0)
			(layer "F.SilkS")
			(hide yes)
			(effects
				(font
					(size 1.27 1.27)
				)
			)
		)
		(property "Value" "SC1U25V3KX-1-GP"
			(at 0 -2.8194 0)
			(unlocked yes)
			(layer "F.Fab")
			(hide yes)
			(effects
				(font
					(size 1.016 1.016)
					(thickness 0.1524)
				)
			)
		)
		(property "Device Type" "C603H36"
			(at 0 -4.3434 0)
			(unlocked yes)
			(layer "F.Fab")
			(hide yes)
			(effects
				(font
					(size 1.016 1.016)
					(thickness 0.1524)
				)
			)
		)
		(duplicate_pad_numbers_are_jumpers no)
		(fp_line
			(start 0.508 0)
			(end -0.508 0)
			(stroke
				(width 0.2032)
				(type default)
			)
			(layer "F.SilkS")
		)
		(fp_rect
			(start -0.5842 1.3335)
			(end 0.5842 -1.3335)
			(stroke
				(width 0)
				(type default)
			)
			(fill no)
			(layer "F.CrtYd")
		)
		(fp_rect
			(start -0.5842 1.3335)
			(end 0.5842 -1.3335)
			(stroke
				(width 0)
				(type default)
			)
			(fill no)
			(layer "F.Fab")
		)
		(pad "1" smd custom
			(at 0 -0.762)
			(size 0.2159 0.2159)
			(layers "F.Cu" "F.Mask" "F.Paste")
			(net "P12V_HDD11")
			(options
				(clearance outline)
				(anchor circle)
			)
			(primitives
				(gr_poly
					(pts
						(arc
							(start -0.3302 -0.4318)
							(mid -0.402042 -0.402042)
							(end -0.4318 -0.3302)
						)
						(arc
							(start -0.4318 0.3302)
							(mid -0.402042 0.402042)
							(end -0.3302 0.4318)
						)
						(arc
							(start 0.3302 0.4318)
							(mid 0.402042 0.402042)
							(end 0.4318 0.3302)
						)
						(arc
							(start 0.4318 -0.3302)
							(mid 0.402042 -0.402042)
							(end 0.3302 -0.4318)
						)
					)
					(width 0)
					(fill yes)
				)
			)
		)
		(pad "2" smd custom
			(at 0 0.762)
			(size 0.2159 0.2159)
			(layers "F.Cu" "F.Mask" "F.Paste")
			(net "GND")
			(options
				(clearance outline)
				(anchor circle)
			)
			(primitives
				(gr_poly
					(pts
						(arc
							(start -0.3302 -0.4318)
							(mid -0.402042 -0.402042)
							(end -0.4318 -0.3302)
						)
						(arc
							(start -0.4318 0.3302)
							(mid -0.402042 0.402042)
							(end -0.3302 0.4318)
						)
						(arc
							(start 0.3302 0.4318)
							(mid 0.402042 0.402042)
							(end 0.4318 0.3302)
						)
						(arc
							(start 0.4318 -0.3302)
							(mid 0.402042 -0.402042)
							(end 0.3302 -0.4318)
						)
					)
					(width 0)
					(fill yes)
				)
			)
		)
	)
	(footprint ""
		(layer "F.Cu")
		(at 54.8386 -228.2698 180)
		(property "Reference" "C293"
			(at 0 0 180)
			(layer "F.SilkS")
			(hide yes)
			(effects
				(font
					(size 1.27 1.27)
				)
			)
		)
		(property "Value" "SCD1U10V2KX-5GP"
			(at 1.1811 -2.7051 180)
			(unlocked yes)
			(layer "F.Fab")
			(hide yes)
			(effects
				(font
					(size 1.016 1.016)
					(thickness 0.1524)
				)
			)
		)
		(property "Device Type" "C402H22"
			(at 1.1811 -4.2291 180)
			(unlocked yes)
			(layer "F.Fab")
			(hide yes)
			(effects
				(font
					(size 1.016 1.016)
					(thickness 0.1524)
				)
			)
		)
		(duplicate_pad_numbers_are_jumpers no)
		(fp_rect
			(start -0.4318 0.9525)
			(end 0.4318 -0.9525)
			(stroke
				(width 0)
				(type default)
			)
			(fill no)
			(layer "F.CrtYd")
		)
		(fp_rect
			(start -0.4318 0.9525)
			(end 0.4318 -0.9525)
			(stroke
				(width 0)
				(type default)
			)
			(fill no)
			(layer "F.Fab")
		)
		(pad "1" smd custom
			(at 0 -0.4445 180)
			(size 0.1524 0.1524)
			(layers "F.Cu" "F.Mask" "F.Paste")
			(net "P3V3")
			(options
				(clearance outline)
				(anchor circle)
			)
			(primitives
				(gr_poly
					(pts
						(arc
							(start 0.3048 -0.2032)
							(mid 0.275042 -0.275042)
							(end 0.2032 -0.3048)
						)
						(arc
							(start -0.2032 -0.3048)
							(mid -0.275042 -0.275042)
							(end -0.3048 -0.2032)
						)
						(arc
							(start -0.3048 0.2032)
							(mid -0.275042 0.275042)
							(end -0.2032 0.3048)
						)
						(arc
							(start 0.2032 0.3048)
							(mid 0.275042 0.275042)
							(end 0.3048 0.2032)
						)
					)
					(width 0)
					(fill yes)
				)
			)
		)
		(pad "2" smd custom
			(at 0 0.4445 180)
			(size 0.1524 0.1524)
			(layers "F.Cu" "F.Mask" "F.Paste")
			(net "GND")
			(options
				(clearance outline)
				(anchor circle)
			)
			(primitives
				(gr_poly
					(pts
						(arc
							(start 0.3048 -0.2032)
							(mid 0.275042 -0.275042)
							(end 0.2032 -0.3048)
						)
						(arc
							(start -0.2032 -0.3048)
							(mid -0.275042 -0.275042)
							(end -0.3048 -0.2032)
						)
						(arc
							(start -0.3048 0.2032)
							(mid -0.275042 0.275042)
							(end -0.2032 0.3048)
						)
						(arc
							(start 0.2032 0.3048)
							(mid 0.275042 0.275042)
							(end 0.3048 0.2032)
						)
					)
					(width 0)
					(fill yes)
				)
			)
		)
	)
	(footprint ""
		(layer "F.Cu")
		(at 33.2613 -273.7104 90)
		(property "Reference" "C36"
			(at 0 0 90)
			(layer "F.SilkS")
			(hide yes)
			(effects
				(font
					(size 1.27 1.27)
				)
			)
		)
		(property "Value" "SCD01U50V2KX-1GP"
			(at 1.1811 -2.7051 90)
			(unlocked yes)
			(layer "F.Fab")
			(hide yes)
			(effects
				(font
					(size 1.016 1.016)
					(thickness 0.1524)
				)
			)
		)
		(property "Device Type" "C402H22"
			(at 1.1811 -4.2291 90)
			(unlocked yes)
			(layer "F.Fab")
			(hide yes)
			(effects
				(font
					(size 1.016 1.016)
					(thickness 0.1524)
				)
			)
		)
		(duplicate_pad_numbers_are_jumpers no)
		(fp_rect
			(start -0.4318 0.9525)
			(end 0.4318 -0.9525)
			(stroke
				(width 0)
				(type default)
			)
			(fill no)
			(layer "F.CrtYd")
		)
		(fp_rect
			(start -0.4318 0.9525)
			(end 0.4318 -0.9525)
			(stroke
				(width 0)
				(type default)
			)
			(fill no)
			(layer "F.Fab")
		)
		(pad "1" smd custom
			(at 0 -0.4445 90)
			(size 0.1524 0.1524)
			(layers "F.Cu" "F.Mask" "F.Paste")
			(net "SEB_BA_TX+")
			(options
				(clearance outline)
				(anchor circle)
			)
			(primitives
				(gr_poly
					(pts
						(arc
							(start 0.3048 -0.2032)
							(mid 0.275042 -0.275042)
							(end 0.2032 -0.3048)
						)
						(arc
							(start -0.2032 -0.3048)
							(mid -0.275042 -0.275042)
							(end -0.3048 -0.2032)
						)
						(arc
							(start -0.3048 0.2032)
							(mid -0.275042 0.275042)
							(end -0.2032 0.3048)
						)
						(arc
							(start 0.2032 0.3048)
							(mid 0.275042 0.275042)
							(end 0.3048 0.2032)
						)
					)
					(width 0)
					(fill yes)
				)
			)
		)
		(pad "2" smd custom
			(at 0 0.4445 90)
			(size 0.1524 0.1524)
			(layers "F.Cu" "F.Mask" "F.Paste")
			(net "SEB_BA_RX+")
			(options
				(clearance outline)
				(anchor circle)
			)
			(primitives
				(gr_poly
					(pts
						(arc
							(start 0.3048 -0.2032)
							(mid 0.275042 -0.275042)
							(end 0.2032 -0.3048)
						)
						(arc
							(start -0.2032 -0.3048)
							(mid -0.275042 -0.275042)
							(end -0.3048 -0.2032)
						)
						(arc
							(start -0.3048 0.2032)
							(mid -0.275042 0.275042)
							(end -0.2032 0.3048)
						)
						(arc
							(start 0.2032 0.3048)
							(mid 0.275042 0.275042)
							(end 0.3048 0.2032)
						)
					)
					(width 0)
					(fill yes)
				)
			)
		)
	)
	(footprint ""
		(layer "F.Cu")
		(at 58.7756 -380.8222 90)
		(property "Reference" "R378"
			(at 0 0 90)
			(layer "F.SilkS")
			(hide yes)
			(effects
				(font
					(size 1.27 1.27)
				)
			)
		)
		(property "Value" "0R2J-2-GP"
			(at 0.064008 -3.993896 90)
			(unlocked yes)
			(layer "F.Fab")
			(hide yes)
			(effects
				(font
					(size 1.016 1.016)
					(thickness 0.1524)
				)
			)
		)
		(property "Device Type" "R402H16"
			(at 0.064008 -5.517896 90)
			(unlocked yes)
			(layer "F.Fab")
			(hide yes)
			(effects
				(font
					(size 1.016 1.016)
					(thickness 0.1524)
				)
			)
		)
		(duplicate_pad_numbers_are_jumpers no)
		(fp_line
			(start 0.508 -0.9398)
			(end -0.508 -0.9398)
			(stroke
				(width 0.1524)
				(type default)
			)
			(layer "F.SilkS")
		)
		(fp_line
			(start -0.508 -0.9398)
			(end -0.508 0.9398)
			(stroke
				(width 0.1524)
				(type default)
			)
			(layer "F.SilkS")
		)
		(fp_rect
			(start -0.508 0.9398)
			(end 0.508 -0.9398)
			(stroke
				(width 0)
				(type default)
			)
			(fill no)
			(layer "F.CrtYd")
		)
		(fp_rect
			(start -0.508 0.9398)
			(end 0.508 -0.9398)
			(stroke
				(width 0)
				(type default)
			)
			(fill no)
			(layer "F.Fab")
		)
		(pad "1" smd custom
			(at 0 -0.4445 90)
			(size 0.1397 0.1397)
			(layers "F.Cu" "F.Mask" "F.Paste")
			(net "HDD_PRSNT_NET6")
			(options
				(clearance outline)
				(anchor circle)
			)
			(primitives
				(gr_poly
					(pts
						(arc
							(start -0.1778 -0.2794)
							(mid -0.249642 -0.249642)
							(end -0.2794 -0.1778)
						)
						(arc
							(start -0.2794 0.1778)
							(mid -0.249642 0.249642)
							(end -0.1778 0.2794)
						)
						(arc
							(start 0.1778 0.2794)
							(mid 0.249642 0.249642)
							(end 0.2794 0.1778)
						)
						(arc
							(start 0.2794 -0.1778)
							(mid 0.249642 -0.249642)
							(end 0.1778 -0.2794)
						)
					)
					(width 0)
					(fill yes)
				)
			)
		)
		(pad "2" smd custom
			(at 0 0.4445 90)
			(size 0.1397 0.1397)
			(layers "F.Cu" "F.Mask" "F.Paste")
			(net "HDD6_LED_B")
			(options
				(clearance outline)
				(anchor circle)
			)
			(primitives
				(gr_poly
					(pts
						(arc
							(start -0.1778 -0.2794)
							(mid -0.249642 -0.249642)
							(end -0.2794 -0.1778)
						)
						(arc
							(start -0.2794 0.1778)
							(mid -0.249642 0.249642)
							(end -0.1778 0.2794)
						)
						(arc
							(start 0.1778 0.2794)
							(mid 0.249642 0.249642)
							(end 0.2794 0.1778)
						)
						(arc
							(start 0.2794 -0.1778)
							(mid 0.249642 -0.249642)
							(end 0.1778 -0.2794)
						)
					)
					(width 0)
					(fill yes)
				)
			)
		)
	)
	(footprint ""
		(layer "F.Cu")
		(at 26.288746 -474.9927 90)
		(property "Reference" "PTC6"
			(at 0 0 90)
			(layer "F.SilkS")
			(hide yes)
			(effects
				(font
					(size 1.27 1.27)
				)
			)
		)
		(property "Value" "ST330U10VDM-2GP"
			(at 0 -9.6012 90)
			(unlocked yes)
			(layer "F.Fab")
			(hide yes)
			(effects
				(font
					(size 1.016 1.016)
					(thickness 0.1524)
				)
			)
		)
		(property "Device Type" "CT7343H150"
			(at 0 -11.1252 90)
			(unlocked yes)
			(layer "F.Fab")
			(hide yes)
			(effects
				(font
					(size 1.016 1.016)
					(thickness 0.1524)
				)
			)
		)
		(duplicate_pad_numbers_are_jumpers no)
		(fp_line
			(start 2.286 -4.8768)
			(end -2.286 -4.8768)
			(stroke
				(width 0.1524)
				(type default)
			)
			(layer "F.SilkS")
		)
		(fp_line
			(start -2.286 -4.8768)
			(end -2.286 -2.032)
			(stroke
				(width 0.1524)
				(type default)
			)
			(layer "F.SilkS")
		)
		(fp_line
			(start 2.1082 -4.699)
			(end -2.1082 -4.699)
			(stroke
				(width 0.508)
				(type default)
			)
			(layer "F.SilkS")
		)
		(fp_line
			(start 2.286 -2.032)
			(end 2.286 -4.8768)
			(stroke
				(width 0.1524)
				(type default)
			)
			(layer "F.SilkS")
		)
		(fp_line
			(start 2.286 2.032)
			(end 2.286 4.8768)
			(stroke
				(width 0.1524)
				(type default)
			)
			(layer "F.SilkS")
		)
		(fp_line
			(start 2.286 4.8768)
			(end -2.286 4.8768)
			(stroke
				(width 0.1524)
				(type default)
			)
			(layer "F.SilkS")
		)
		(fp_line
			(start -2.286 4.8768)
			(end -2.286 2.032)
			(stroke
				(width 0.1524)
				(type default)
			)
			(layer "F.SilkS")
		)
		(fp_rect
			(start -2.1463 3.6449)
			(end 2.1463 -3.6449)
			(stroke
				(width 0)
				(type default)
			)
			(fill no)
			(layer "F.CrtYd")
		)
		(fp_poly
			(pts
				(xy -2.54 4.953) (xy -2.54 4.2926) (xy -3.81 4.2926) (xy -3.81 -4.2926) (xy -2.54 -4.2926) (xy -2.54 -4.953)
				(xy 2.54 -4.953) (xy 2.54 -4.2926) (xy 3.81 -4.2926) (xy 3.81 -1.6256) (xy 2.1463 -1.6256) (xy 2.1463 -3.6449)
				(xy -2.1463 -3.6449) (xy -2.1463 3.6449) (xy 2.1463 3.6449) (xy 2.1463 -1.6129) (xy 3.81 -1.6129)
				(xy 3.81 4.2926) (xy 2.54 4.2926) (xy 2.54 4.953)
			)
			(stroke
				(width 0)
				(type default)
			)
			(fill no)
			(layer "F.CrtYd")
		)
		(fp_rect
			(start 2.54 4.2926)
			(end 3.81 -4.2926)
			(stroke
				(width 0)
				(type default)
			)
			(fill no)
			(layer "F.Fab")
		)
		(fp_rect
			(start -3.81 4.2926)
			(end -2.54 -4.2926)
			(stroke
				(width 0)
				(type default)
			)
			(fill no)
			(layer "F.Fab")
		)
		(fp_rect
			(start -2.54 4.953)
			(end 2.54 -4.953)
			(stroke
				(width 0)
				(type default)
			)
			(fill no)
			(layer "F.Fab")
		)
		(pad "1" smd rect
			(at 0 -3.1496 90)
			(size 2.413 2.286)
			(layers "F.Cu" "F.Mask" "F.Paste")
			(net "P5VC")
		)
		(pad "2" smd rect
			(at 0 3.1496 90)
			(size 2.413 2.286)
			(layers "F.Cu" "F.Mask" "F.Paste")
			(net "GND")
		)
		(zone
			(layer "F.Cu")
			(hatch none 0.5)
			(connect_pads
				(clearance 0)
			)
			(min_thickness 0.25)
			(keepout
				(tracks allowed)
				(vias not_allowed)
				(pads allowed)
				(copperpour not_allowed)
				(footprints allowed)
			)
			(placement
				(enabled no)
				(sheetname "")
			)
			(fill
				(thermal_gap 0.5)
				(thermal_bridge_width 0.5)
				(island_removal_mode 0)
			)
			(polygon
				(pts
					(xy 24.599646 -476.504) (xy 21.691346 -476.504) (xy 21.691346 -473.4814) (xy 24.586946 -473.4814)
					(xy 24.917146 -473.4814) (xy 24.917146 -476.504)
				)
			)
		)
		(zone
			(layer "F.Cu")
			(hatch none 0.5)
			(connect_pads
				(clearance 0)
			)
			(min_thickness 0.25)
			(keepout
				(tracks allowed)
				(vias not_allowed)
				(pads allowed)
				(copperpour not_allowed)
				(footprints allowed)
			)
			(placement
				(enabled no)
				(sheetname "")
			)
			(fill
				(thermal_gap 0.5)
				(thermal_bridge_width 0.5)
				(island_removal_mode 0)
			)
			(polygon
				(pts
					(xy 30.886146 -473.4814) (xy 30.886146 -476.504) (xy 27.990546 -476.504) (xy 27.660346 -476.504)
					(xy 27.660346 -473.4814) (xy 27.990546 -473.4814)
				)
			)
		)
	)
	(footprint ""
		(layer "F.Cu")
		(at 21.399246 -464.467702 -90)
		(property "Reference" "R241"
			(at 0 0 270)
			(layer "F.SilkS")
			(hide yes)
			(effects
				(font
					(size 1.27 1.27)
				)
			)
		)
		(property "Value" "402R2F-GP"
			(at 0.064008 -3.993896 270)
			(unlocked yes)
			(layer "F.Fab")
			(hide yes)
			(effects
				(font
					(size 1.016 1.016)
					(thickness 0.1524)
				)
			)
		)
		(property "Device Type" "R402H16"
			(at 0.064008 -5.517896 270)
			(unlocked yes)
			(layer "F.Fab")
			(hide yes)
			(effects
				(font
					(size 1.016 1.016)
					(thickness 0.1524)
				)
			)
		)
		(duplicate_pad_numbers_are_jumpers no)
		(fp_line
			(start -0.508 -0.9398)
			(end -0.508 0.9398)
			(stroke
				(width 0.1524)
				(type default)
			)
			(layer "F.SilkS")
		)
		(fp_line
			(start 0.508 -0.9398)
			(end -0.508 -0.9398)
			(stroke
				(width 0.1524)
				(type default)
			)
			(layer "F.SilkS")
		)
		(fp_rect
			(start -0.508 0.9398)
			(end 0.508 -0.9398)
			(stroke
				(width 0)
				(type default)
			)
			(fill no)
			(layer "F.CrtYd")
		)
		(fp_rect
			(start -0.508 0.9398)
			(end 0.508 -0.9398)
			(stroke
				(width 0)
				(type default)
			)
			(fill no)
			(layer "F.Fab")
		)
		(pad "1" smd custom
			(at 0 -0.4445 270)
			(size 0.1397 0.1397)
			(layers "F.Cu" "F.Mask" "F.Paste")
			(net "P5VC_HDD10_LED")
			(options
				(clearance outline)
				(anchor circle)
			)
			(primitives
				(gr_poly
					(pts
						(arc
							(start -0.1778 -0.2794)
							(mid -0.249642 -0.249642)
							(end -0.2794 -0.1778)
						)
						(arc
							(start -0.2794 0.1778)
							(mid -0.249642 0.249642)
							(end -0.1778 0.2794)
						)
						(arc
							(start 0.1778 0.2794)
							(mid 0.249642 0.249642)
							(end 0.2794 0.1778)
						)
						(arc
							(start 0.2794 -0.1778)
							(mid 0.249642 -0.249642)
							(end 0.1778 -0.2794)
						)
					)
					(width 0)
					(fill yes)
				)
			)
		)
		(pad "2" smd custom
			(at 0 0.4445 270)
			(size 0.1397 0.1397)
			(layers "F.Cu" "F.Mask" "F.Paste")
			(net "DRV_ACT_10")
			(options
				(clearance outline)
				(anchor circle)
			)
			(primitives
				(gr_poly
					(pts
						(arc
							(start -0.1778 -0.2794)
							(mid -0.249642 -0.249642)
							(end -0.2794 -0.1778)
						)
						(arc
							(start -0.2794 0.1778)
							(mid -0.249642 0.249642)
							(end -0.1778 0.2794)
						)
						(arc
							(start 0.1778 0.2794)
							(mid 0.249642 0.249642)
							(end 0.2794 0.1778)
						)
						(arc
							(start 0.2794 -0.1778)
							(mid 0.249642 -0.249642)
							(end 0.1778 -0.2794)
						)
					)
					(width 0)
					(fill yes)
				)
			)
		)
	)
	(footprint ""
		(layer "F.Cu")
		(at 218.490546 -346.1512 -90)
		(property "Reference" "Q35"
			(at 0 0 270)
			(layer "F.SilkS")
			(hide yes)
			(effects
				(font
					(size 1.27 1.27)
				)
			)
		)
		(property "Value" "PMBS3904-1-GP"
			(at 0 -9.0932 270)
			(unlocked yes)
			(layer "F.Fab")
			(hide yes)
			(effects
				(font
					(size 1.016 1.016)
					(thickness 0.1524)
				)
			)
		)
		(property "Device Type" "SOT-23-10H44"
			(at 0 -10.6172 270)
			(unlocked yes)
			(layer "F.Fab")
			(hide yes)
			(effects
				(font
					(size 1.016 1.016)
					(thickness 0.1524)
				)
			)
		)
		(duplicate_pad_numbers_are_jumpers no)
		(fp_line
			(start -1.279144 2.15265)
			(end -0.701294 2.15265)
			(stroke
				(width 0.0127)
				(type default)
			)
			(layer "F.SilkS")
		)
		(fp_line
			(start -0.71628 2.15265)
			(end -1.26492 2.15265)
			(stroke
				(width 0.0127)
				(type default)
			)
			(layer "F.SilkS")
		)
		(fp_line
			(start -1.279398 2.152142)
			(end -0.9906 1.86309)
			(stroke
				(width 0.0127)
				(type default)
			)
			(layer "F.SilkS")
		)
		(fp_line
			(start -0.719074 2.145538)
			(end -1.265936 2.14122)
			(stroke
				(width 0.0127)
				(type default)
			)
			(layer "F.SilkS")
		)
		(fp_line
			(start -1.260856 2.1336)
			(end -0.720344 2.1336)
			(stroke
				(width 0.0127)
				(type default)
			)
			(layer "F.SilkS")
		)
		(fp_line
			(start -1.251458 2.124202)
			(end -0.729996 2.124202)
			(stroke
				(width 0.0127)
				(type default)
			)
			(layer "F.SilkS")
		)
		(fp_line
			(start -1.241806 2.11455)
			(end -0.739394 2.11455)
			(stroke
				(width 0.0127)
				(type default)
			)
			(layer "F.SilkS")
		)
		(fp_line
			(start -1.232408 2.105152)
			(end -0.749046 2.105152)
			(stroke
				(width 0.0127)
				(type default)
			)
			(layer "F.SilkS")
		)
		(fp_line
			(start -1.222756 2.0955)
			(end -0.758444 2.0955)
			(stroke
				(width 0.0127)
				(type default)
			)
			(layer "F.SilkS")
		)
		(fp_line
			(start -1.213358 2.086102)
			(end -0.768096 2.086102)
			(stroke
				(width 0.0127)
				(type default)
			)
			(layer "F.SilkS")
		)
		(fp_line
			(start -1.203706 2.07645)
			(end -0.777494 2.07645)
			(stroke
				(width 0.0127)
				(type default)
			)
			(layer "F.SilkS")
		)
		(fp_line
			(start -1.194308 2.067052)
			(end -0.787146 2.067052)
			(stroke
				(width 0.0127)
				(type default)
			)
			(layer "F.SilkS")
		)
		(fp_line
			(start -1.184656 2.0574)
			(end -0.796544 2.0574)
			(stroke
				(width 0.0127)
				(type default)
			)
			(layer "F.SilkS")
		)
		(fp_line
			(start -1.175258 2.048002)
			(end -0.806196 2.048002)
			(stroke
				(width 0.0127)
				(type default)
			)
			(layer "F.SilkS")
		)
		(fp_line
			(start -1.165606 2.03835)
			(end -0.815594 2.03835)
			(stroke
				(width 0.0127)
				(type default)
			)
			(layer "F.SilkS")
		)
		(fp_line
			(start -1.156208 2.028952)
			(end -0.825246 2.028952)
			(stroke
				(width 0.0127)
				(type default)
			)
			(layer "F.SilkS")
		)
		(fp_line
			(start -1.146556 2.0193)
			(end -0.834644 2.0193)
			(stroke
				(width 0.0127)
				(type default)
			)
			(layer "F.SilkS")
		)
		(fp_line
			(start -1.137158 2.009902)
			(end -0.844296 2.009902)
			(stroke
				(width 0.0127)
				(type default)
			)
			(layer "F.SilkS")
		)
		(fp_line
			(start -1.127506 2.00025)
			(end -0.853694 2.00025)
			(stroke
				(width 0.0127)
				(type default)
			)
			(layer "F.SilkS")
		)
		(fp_line
			(start -1.118108 1.990852)
			(end -0.863346 1.990852)
			(stroke
				(width 0.0127)
				(type default)
			)
			(layer "F.SilkS")
		)
		(fp_line
			(start -1.108456 1.9812)
			(end -0.872744 1.9812)
			(stroke
				(width 0.0127)
				(type default)
			)
			(layer "F.SilkS")
		)
		(fp_line
			(start -1.099058 1.971802)
			(end -0.882396 1.971802)
			(stroke
				(width 0.0127)
				(type default)
			)
			(layer "F.SilkS")
		)
		(fp_line
			(start -1.089406 1.96215)
			(end -0.891794 1.96215)
			(stroke
				(width 0.0127)
				(type default)
			)
			(layer "F.SilkS")
		)
		(fp_line
			(start -1.080008 1.952752)
			(end -0.901446 1.952752)
			(stroke
				(width 0.0127)
				(type default)
			)
			(layer "F.SilkS")
		)
		(fp_line
			(start -1.070356 1.9431)
			(end -0.910844 1.9431)
			(stroke
				(width 0.0127)
				(type default)
			)
			(layer "F.SilkS")
		)
		(fp_line
			(start -1.060958 1.933702)
			(end -0.920496 1.933702)
			(stroke
				(width 0.0127)
				(type default)
			)
			(layer "F.SilkS")
		)
		(fp_line
			(start -1.051306 1.92405)
			(end -0.929894 1.92405)
			(stroke
				(width 0.0127)
				(type default)
			)
			(layer "F.SilkS")
		)
		(fp_line
			(start -1.041908 1.914652)
			(end -0.939546 1.914652)
			(stroke
				(width 0.0127)
				(type default)
			)
			(layer "F.SilkS")
		)
		(fp_line
			(start -1.032256 1.905)
			(end -0.948944 1.905)
			(stroke
				(width 0.0127)
				(type default)
			)
			(layer "F.SilkS")
		)
		(fp_line
			(start -1.022858 1.895602)
			(end -0.958596 1.895602)
			(stroke
				(width 0.0127)
				(type default)
			)
			(layer "F.SilkS")
		)
		(fp_line
			(start -1.013206 1.88595)
			(end -0.967994 1.88595)
			(stroke
				(width 0.0127)
				(type default)
			)
			(layer "F.SilkS")
		)
		(fp_line
			(start -1.7526 1.8796)
			(end -1.7526 0.9906)
			(stroke
				(width 0.3302)
				(type default)
			)
			(layer "F.SilkS")
		)
		(fp_line
			(start -0.635 1.8796)
			(end -1.7526 1.8796)
			(stroke
				(width 0.3302)
				(type default)
			)
			(layer "F.SilkS")
		)
		(fp_line
			(start -1.003808 1.876552)
			(end -0.977646 1.876552)
			(stroke
				(width 0.0127)
				(type default)
			)
			(layer "F.SilkS")
		)
		(fp_line
			(start -0.994156 1.8669)
			(end -0.987044 1.8669)
			(stroke
				(width 0.0127)
				(type default)
			)
			(layer "F.SilkS")
		)
		(fp_line
			(start -0.9906 1.86309)
			(end -0.701294 2.15265)
			(stroke
				(width 0.0127)
				(type default)
			)
			(layer "F.SilkS")
		)
		(fp_line
			(start -1.651 1.778)
			(end 1.651 1.778)
			(stroke
				(width 0.1524)
				(type default)
			)
			(layer "F.SilkS")
		)
		(fp_line
			(start 1.651 1.778)
			(end 1.651 -1.778)
			(stroke
				(width 0.1524)
				(type default)
			)
			(layer "F.SilkS")
		)
		(fp_line
			(start -1.651 -1.778)
			(end -1.651 1.778)
			(stroke
				(width 0.1524)
				(type default)
			)
			(layer "F.SilkS")
		)
		(fp_line
			(start 1.651 -1.778)
			(end -1.651 -1.778)
			(stroke
				(width 0.1524)
				(type default)
			)
			(layer "F.SilkS")
		)
		(fp_poly
			(pts
				(xy -1.285748 2.159) (xy -1.285748 1.8796) (xy -1.778 1.8796) (xy -1.778 -1.8796) (xy 1.778 -1.8796)
				(xy 1.778 1.8796) (xy -0.694944 1.8796) (xy -0.694944 2.159)
			)
			(stroke
				(width 0)
				(type default)
			)
			(fill no)
			(layer "F.CrtYd")
		)
		(fp_poly
			(pts
				(xy -1.285748 2.159) (xy -1.285748 1.8796) (xy -1.778 1.8796) (xy -1.778 -1.8796) (xy 1.778 -1.8796)
				(xy 1.778 1.8796) (xy -0.694944 1.8796) (xy -0.694944 2.159)
			)
			(stroke
				(width 0)
				(type default)
			)
			(fill no)
			(layer "F.Fab")
		)
		(pad "1" smd rect
			(at -0.98425 0.9525 270)
			(size 0.762 1.143)
			(layers "F.Cu" "F.Mask" "F.Paste")
			(net "FLT_HDD1_B")
		)
		(pad "2" smd rect
			(at 0.98425 0.9525 270)
			(size 0.762 1.143)
			(layers "F.Cu" "F.Mask" "F.Paste")
			(net "GND")
		)
		(pad "3" smd rect
			(at 0 -0.9525 270)
			(size 0.762 1.143)
			(layers "F.Cu" "F.Mask" "F.Paste")
			(net "DRIVE_ACT_1")
		)
	)
	(footprint ""
		(layer "F.Cu")
		(at 221.031054 -434.7591 180)
		(property "Reference" "PC41"
			(at 0 0 180)
			(layer "F.SilkS")
			(hide yes)
			(effects
				(font
					(size 1.27 1.27)
				)
			)
		)
		(property "Value" "SCD1U16V2KX-3GP"
			(at 1.1811 -2.7051 180)
			(unlocked yes)
			(layer "F.Fab")
			(hide yes)
			(effects
				(font
					(size 1.016 1.016)
					(thickness 0.1524)
				)
			)
		)
		(property "Device Type" "C402H22"
			(at 1.1811 -4.2291 180)
			(unlocked yes)
			(layer "F.Fab")
			(hide yes)
			(effects
				(font
					(size 1.016 1.016)
					(thickness 0.1524)
				)
			)
		)
		(duplicate_pad_numbers_are_jumpers no)
		(fp_rect
			(start -0.4318 0.9525)
			(end 0.4318 -0.9525)
			(stroke
				(width 0)
				(type default)
			)
			(fill no)
			(layer "F.CrtYd")
		)
		(fp_rect
			(start -0.4318 0.9525)
			(end 0.4318 -0.9525)
			(stroke
				(width 0)
				(type default)
			)
			(fill no)
			(layer "F.Fab")
		)
		(pad "1" smd custom
			(at 0 -0.4445 180)
			(size 0.1524 0.1524)
			(layers "F.Cu" "F.Mask" "F.Paste")
			(net "P3V3_BS_NET")
			(options
				(clearance outline)
				(anchor circle)
			)
			(primitives
				(gr_poly
					(pts
						(arc
							(start 0.3048 -0.2032)
							(mid 0.275042 -0.275042)
							(end 0.2032 -0.3048)
						)
						(arc
							(start -0.2032 -0.3048)
							(mid -0.275042 -0.275042)
							(end -0.3048 -0.2032)
						)
						(arc
							(start -0.3048 0.2032)
							(mid -0.275042 0.275042)
							(end -0.2032 0.3048)
						)
						(arc
							(start 0.2032 0.3048)
							(mid 0.275042 0.275042)
							(end 0.3048 0.2032)
						)
					)
					(width 0)
					(fill yes)
				)
			)
		)
		(pad "2" smd custom
			(at 0 0.4445 180)
			(size 0.1524 0.1524)
			(layers "F.Cu" "F.Mask" "F.Paste")
			(net "P3V3_LX")
			(options
				(clearance outline)
				(anchor circle)
			)
			(primitives
				(gr_poly
					(pts
						(arc
							(start 0.3048 -0.2032)
							(mid 0.275042 -0.275042)
							(end 0.2032 -0.3048)
						)
						(arc
							(start -0.2032 -0.3048)
							(mid -0.275042 -0.275042)
							(end -0.3048 -0.2032)
						)
						(arc
							(start -0.3048 0.2032)
							(mid -0.275042 0.275042)
							(end -0.2032 0.3048)
						)
						(arc
							(start 0.2032 0.3048)
							(mid 0.275042 0.275042)
							(end 0.3048 0.2032)
						)
					)
					(width 0)
					(fill yes)
				)
			)
		)
	)
	(footprint ""
		(layer "F.Cu")
		(at 45.465746 -217.706702)
		(property "Reference" "C305"
			(at 0 0 0)
			(layer "F.SilkS")
			(hide yes)
			(effects
				(font
					(size 1.27 1.27)
				)
			)
		)
		(property "Value" "SC10U25V6KX-1GP"
			(at -0.0762 -5.1308 0)
			(unlocked yes)
			(layer "F.Fab")
			(hide yes)
			(effects
				(font
					(size 1.016 1.016)
					(thickness 0.1524)
				)
			)
		)
		(property "Device Type" "C1206H71"
			(at -0.127 -6.6548 0)
			(unlocked yes)
			(layer "F.Fab")
			(hide yes)
			(effects
				(font
					(size 1.016 1.016)
					(thickness 0.1524)
				)
			)
		)
		(duplicate_pad_numbers_are_jumpers no)
		(fp_line
			(start -1.016 -2.2352)
			(end 1.016 -2.2352)
			(stroke
				(width 0.1524)
				(type default)
			)
			(layer "F.SilkS")
		)
		(fp_line
			(start -1.016 -0.8382)
			(end -1.016 -2.2352)
			(stroke
				(width 0.1524)
				(type default)
			)
			(layer "F.SilkS")
		)
		(fp_line
			(start -1.016 2.2352)
			(end -1.016 0.8382)
			(stroke
				(width 0.1524)
				(type default)
			)
			(layer "F.SilkS")
		)
		(fp_line
			(start 1.016 -2.2352)
			(end 1.016 -0.8382)
			(stroke
				(width 0.1524)
				(type default)
			)
			(layer "F.SilkS")
		)
		(fp_line
			(start 1.016 0.8382)
			(end 1.016 2.2352)
			(stroke
				(width 0.1524)
				(type default)
			)
			(layer "F.SilkS")
		)
		(fp_line
			(start 1.016 2.2352)
			(end -1.016 2.2352)
			(stroke
				(width 0.1524)
				(type default)
			)
			(layer "F.SilkS")
		)
		(fp_rect
			(start -1.0922 2.3114)
			(end 1.0922 -2.3114)
			(stroke
				(width 0)
				(type default)
			)
			(fill no)
			(layer "F.CrtYd")
		)
		(fp_poly
			(pts
				(xy 1.0922 -2.3114) (xy 1.0922 2.3114) (xy -1.0922 2.3114) (xy -1.0922 -2.3114)
			)
			(stroke
				(width 0)
				(type default)
			)
			(fill no)
			(layer "F.Fab")
		)
		(pad "1" smd rect
			(at 0 -1.397)
			(size 1.651 1.27)
			(layers "F.Cu" "F.Mask" "F.Paste")
			(net "P12V_HDD12")
		)
		(pad "2" smd rect
			(at 0 1.397)
			(size 1.651 1.27)
			(layers "F.Cu" "F.Mask" "F.Paste")
			(net "GND")
		)
	)
	(footprint ""
		(layer "F.Cu")
		(at 48.386746 -214.404702)
		(property "Reference" "R278"
			(at 0 0 0)
			(layer "F.SilkS")
			(hide yes)
			(effects
				(font
					(size 1.27 1.27)
				)
			)
		)
		(property "Value" "4K7R2J-2-GP"
			(at 0.064008 -3.993896 0)
			(unlocked yes)
			(layer "F.Fab")
			(hide yes)
			(effects
				(font
					(size 1.016 1.016)
					(thickness 0.1524)
				)
			)
		)
		(property "Device Type" "R402H16"
			(at 0.064008 -5.517896 0)
			(unlocked yes)
			(layer "F.Fab")
			(hide yes)
			(effects
				(font
					(size 1.016 1.016)
					(thickness 0.1524)
				)
			)
		)
		(duplicate_pad_numbers_are_jumpers no)
		(fp_line
			(start -0.508 -0.9398)
			(end -0.508 0.9398)
			(stroke
				(width 0.1524)
				(type default)
			)
			(layer "F.SilkS")
		)
		(fp_line
			(start 0.508 -0.9398)
			(end -0.508 -0.9398)
			(stroke
				(width 0.1524)
				(type default)
			)
			(layer "F.SilkS")
		)
		(fp_rect
			(start -0.508 0.9398)
			(end 0.508 -0.9398)
			(stroke
				(width 0)
				(type default)
			)
			(fill no)
			(layer "F.CrtYd")
		)
		(fp_rect
			(start -0.508 0.9398)
			(end 0.508 -0.9398)
			(stroke
				(width 0)
				(type default)
			)
			(fill no)
			(layer "F.Fab")
		)
		(pad "1" smd custom
			(at 0 -0.4445)
			(size 0.1397 0.1397)
			(layers "F.Cu" "F.Mask" "F.Paste")
			(net "P12V")
			(options
				(clearance outline)
				(anchor circle)
			)
			(primitives
				(gr_poly
					(pts
						(arc
							(start -0.1778 -0.2794)
							(mid -0.249642 -0.249642)
							(end -0.2794 -0.1778)
						)
						(arc
							(start -0.2794 0.1778)
							(mid -0.249642 0.249642)
							(end -0.1778 0.2794)
						)
						(arc
							(start 0.1778 0.2794)
							(mid 0.249642 0.249642)
							(end 0.2794 0.1778)
						)
						(arc
							(start 0.2794 -0.1778)
							(mid 0.249642 -0.249642)
							(end 0.1778 -0.2794)
						)
					)
					(width 0)
					(fill yes)
				)
			)
		)
		(pad "2" smd custom
			(at 0 0.4445)
			(size 0.1397 0.1397)
			(layers "F.Cu" "F.Mask" "F.Paste")
			(net "SW_HDD12_R")
			(options
				(clearance outline)
				(anchor circle)
			)
			(primitives
				(gr_poly
					(pts
						(arc
							(start -0.1778 -0.2794)
							(mid -0.249642 -0.249642)
							(end -0.2794 -0.1778)
						)
						(arc
							(start -0.2794 0.1778)
							(mid -0.249642 0.249642)
							(end -0.1778 0.2794)
						)
						(arc
							(start 0.1778 0.2794)
							(mid 0.249642 0.249642)
							(end 0.2794 0.1778)
						)
						(arc
							(start 0.2794 -0.1778)
							(mid 0.249642 -0.249642)
							(end 0.1778 -0.2794)
						)
					)
					(width 0)
					(fill yes)
				)
			)
		)
	)
	(footprint ""
		(layer "F.Cu")
		(at 228.726746 -21.9837 180)
		(property "Reference" "PR49"
			(at 0 0 180)
			(layer "F.SilkS")
			(hide yes)
			(effects
				(font
					(size 1.27 1.27)
				)
			)
		)
		(property "Value" "10KR2F-2-GP"
			(at 0.064008 -3.993896 180)
			(unlocked yes)
			(layer "F.Fab")
			(hide yes)
			(effects
				(font
					(size 1.016 1.016)
					(thickness 0.1524)
				)
			)
		)
		(property "Device Type" "R402H16"
			(at 0.064008 -5.517896 180)
			(unlocked yes)
			(layer "F.Fab")
			(hide yes)
			(effects
				(font
					(size 1.016 1.016)
					(thickness 0.1524)
				)
			)
		)
		(duplicate_pad_numbers_are_jumpers no)
		(fp_line
			(start 0.508 -0.9398)
			(end -0.508 -0.9398)
			(stroke
				(width 0.1524)
				(type default)
			)
			(layer "F.SilkS")
		)
		(fp_line
			(start -0.508 -0.9398)
			(end -0.508 0.9398)
			(stroke
				(width 0.1524)
				(type default)
			)
			(layer "F.SilkS")
		)
		(fp_rect
			(start -0.508 0.9398)
			(end 0.508 -0.9398)
			(stroke
				(width 0)
				(type default)
			)
			(fill no)
			(layer "F.CrtYd")
		)
		(fp_rect
			(start -0.508 0.9398)
			(end 0.508 -0.9398)
			(stroke
				(width 0)
				(type default)
			)
			(fill no)
			(layer "F.Fab")
		)
		(pad "1" smd custom
			(at 0 -0.4445 180)
			(size 0.1397 0.1397)
			(layers "F.Cu" "F.Mask" "F.Paste")
			(net "P5VA_LL")
			(options
				(clearance outline)
				(anchor circle)
			)
			(primitives
				(gr_poly
					(pts
						(arc
							(start -0.1778 -0.2794)
							(mid -0.249642 -0.249642)
							(end -0.2794 -0.1778)
						)
						(arc
							(start -0.2794 0.1778)
							(mid -0.249642 0.249642)
							(end -0.1778 0.2794)
						)
						(arc
							(start 0.1778 0.2794)
							(mid 0.249642 0.249642)
							(end 0.2794 0.1778)
						)
						(arc
							(start 0.2794 -0.1778)
							(mid 0.249642 -0.249642)
							(end 0.1778 -0.2794)
						)
					)
					(width 0)
					(fill yes)
				)
			)
		)
		(pad "2" smd custom
			(at 0 0.4445 180)
			(size 0.1397 0.1397)
			(layers "F.Cu" "F.Mask" "F.Paste")
			(net "P5VA_LL_NET")
			(options
				(clearance outline)
				(anchor circle)
			)
			(primitives
				(gr_poly
					(pts
						(arc
							(start -0.1778 -0.2794)
							(mid -0.249642 -0.249642)
							(end -0.2794 -0.1778)
						)
						(arc
							(start -0.2794 0.1778)
							(mid -0.249642 0.249642)
							(end -0.1778 0.2794)
						)
						(arc
							(start 0.1778 0.2794)
							(mid 0.249642 0.249642)
							(end 0.2794 0.1778)
						)
						(arc
							(start 0.2794 -0.1778)
							(mid 0.249642 -0.249642)
							(end 0.1778 -0.2794)
						)
					)
					(width 0)
					(fill yes)
				)
			)
		)
	)
	(footprint ""
		(layer "F.Cu")
		(at 32.892746 -340.8807 -90)
		(property "Reference" "R501"
			(at 0 0 270)
			(layer "F.SilkS")
			(hide yes)
			(effects
				(font
					(size 1.27 1.27)
				)
			)
		)
		(property "Value" "1KR2F-3-GP"
			(at 0.064008 -3.993896 270)
			(unlocked yes)
			(layer "F.Fab")
			(hide yes)
			(effects
				(font
					(size 1.016 1.016)
					(thickness 0.1524)
				)
			)
		)
		(property "Device Type" "R402H16"
			(at 0.064008 -5.517896 270)
			(unlocked yes)
			(layer "F.Fab")
			(hide yes)
			(effects
				(font
					(size 1.016 1.016)
					(thickness 0.1524)
				)
			)
		)
		(duplicate_pad_numbers_are_jumpers no)
		(fp_line
			(start -0.508 -0.9398)
			(end -0.508 0.9398)
			(stroke
				(width 0.1524)
				(type default)
			)
			(layer "F.SilkS")
		)
		(fp_line
			(start 0.508 -0.9398)
			(end -0.508 -0.9398)
			(stroke
				(width 0.1524)
				(type default)
			)
			(layer "F.SilkS")
		)
		(fp_rect
			(start -0.508 0.9398)
			(end 0.508 -0.9398)
			(stroke
				(width 0)
				(type default)
			)
			(fill no)
			(layer "F.CrtYd")
		)
		(fp_rect
			(start -0.508 0.9398)
			(end 0.508 -0.9398)
			(stroke
				(width 0)
				(type default)
			)
			(fill no)
			(layer "F.Fab")
		)
		(pad "1" smd custom
			(at 0 -0.4445 270)
			(size 0.1397 0.1397)
			(layers "F.Cu" "F.Mask" "F.Paste")
			(net "FLT_HDD11_B")
			(options
				(clearance outline)
				(anchor circle)
			)
			(primitives
				(gr_poly
					(pts
						(arc
							(start -0.1778 -0.2794)
							(mid -0.249642 -0.249642)
							(end -0.2794 -0.1778)
						)
						(arc
							(start -0.2794 0.1778)
							(mid -0.249642 0.249642)
							(end -0.1778 0.2794)
						)
						(arc
							(start 0.1778 0.2794)
							(mid 0.249642 0.249642)
							(end 0.2794 0.1778)
						)
						(arc
							(start 0.2794 -0.1778)
							(mid 0.249642 -0.249642)
							(end 0.1778 -0.2794)
						)
					)
					(width 0)
					(fill yes)
				)
			)
		)
		(pad "2" smd custom
			(at 0 0.4445 270)
			(size 0.1397 0.1397)
			(layers "F.Cu" "F.Mask" "F.Paste")
			(net "FLT_HDD11_DRIVE")
			(options
				(clearance outline)
				(anchor circle)
			)
			(primitives
				(gr_poly
					(pts
						(arc
							(start -0.1778 -0.2794)
							(mid -0.249642 -0.249642)
							(end -0.2794 -0.1778)
						)
						(arc
							(start -0.2794 0.1778)
							(mid -0.249642 0.249642)
							(end -0.1778 0.2794)
						)
						(arc
							(start 0.1778 0.2794)
							(mid 0.249642 0.249642)
							(end 0.2794 0.1778)
						)
						(arc
							(start 0.2794 -0.1778)
							(mid 0.249642 -0.249642)
							(end 0.1778 -0.2794)
						)
					)
					(width 0)
					(fill yes)
				)
			)
		)
	)
	(footprint ""
		(layer "F.Cu")
		(at 52.323746 -225.6917)
		(property "Reference" "U37"
			(at 0 0 0)
			(layer "F.SilkS")
			(hide yes)
			(effects
				(font
					(size 1.27 1.27)
				)
			)
		)
		(property "Value" "74LVC1G08GW-1-GP"
			(at -2.3368 -8.6868 0)
			(unlocked yes)
			(layer "F.Fab")
			(hide yes)
			(effects
				(font
					(size 1.016 1.016)
					(thickness 0.1524)
				)
			)
		)
		(property "Device Type" "SC70-5H44"
			(at -2.3114 -10.414 0)
			(unlocked yes)
			(layer "F.Fab")
			(hide yes)
			(effects
				(font
					(size 1.016 1.016)
					(thickness 0.1524)
				)
			)
		)
		(duplicate_pad_numbers_are_jumpers no)
		(fp_line
			(start -1.27 -1.7018)
			(end 1.27 -1.7018)
			(stroke
				(width 0.1524)
				(type default)
			)
			(layer "F.SilkS")
		)
		(fp_line
			(start -1.27 1.7018)
			(end -1.27 -1.7018)
			(stroke
				(width 0.1524)
				(type default)
			)
			(layer "F.SilkS")
		)
		(fp_line
			(start 0.6604 -1.8034)
			(end 1.3843 -1.8034)
			(stroke
				(width 0.3302)
				(type default)
			)
			(layer "F.SilkS")
		)
		(fp_line
			(start 1.27 -1.7018)
			(end 1.27 1.7018)
			(stroke
				(width 0.1524)
				(type default)
			)
			(layer "F.SilkS")
		)
		(fp_line
			(start 1.27 1.7018)
			(end -1.27 1.7018)
			(stroke
				(width 0.1524)
				(type default)
			)
			(layer "F.SilkS")
		)
		(fp_line
			(start 1.3843 -1.8034)
			(end 1.3843 -1.1176)
			(stroke
				(width 0.3302)
				(type default)
			)
			(layer "F.SilkS")
		)
		(fp_rect
			(start -1.524 1.9558)
			(end 1.524 -1.9558)
			(stroke
				(width 0)
				(type default)
			)
			(fill no)
			(layer "F.CrtYd")
		)
		(fp_poly
			(pts
				(xy -1.524 -1.9558) (xy 1.524 -1.9558) (xy 1.524 1.9558) (xy -1.524 1.9558)
			)
			(stroke
				(width 0)
				(type default)
			)
			(fill no)
			(layer "F.Fab")
		)
		(pad "1" smd rect
			(at 0.65024 -0.8255)
			(size 0.4064 1.2192)
			(layers "F.Cu" "F.Mask" "F.Paste")
			(net "SAS2X28_B_HDD12_FLT")
		)
		(pad "2" smd rect
			(at 0 -0.8255)
			(size 0.4064 1.2192)
			(layers "F.Cu" "F.Mask" "F.Paste")
			(net "SAS2X28_A_HDD12_FLT")
		)
		(pad "3" smd rect
			(at -0.65024 -0.8255)
			(size 0.4064 1.2192)
			(layers "F.Cu" "F.Mask" "F.Paste")
			(net "GND")
		)
		(pad "4" smd rect
			(at -0.65024 0.8255)
			(size 0.4064 1.2192)
			(layers "F.Cu" "F.Mask" "F.Paste")
			(net "FLT_HDD12_DRIVE")
		)
		(pad "5" smd rect
			(at 0.65024 0.8255)
			(size 0.4064 1.2192)
			(layers "F.Cu" "F.Mask" "F.Paste")
			(net "P3V3")
		)
	)
	(footprint ""
		(layer "F.Cu")
		(at 206.104744 -487.13771 90)
		(property "Reference" "Q2"
			(at 0 0 90)
			(layer "F.SilkS")
			(hide yes)
			(effects
				(font
					(size 1.27 1.27)
				)
			)
		)
		(property "Value" "AO4406AL-GP"
			(at -3.707384 -1.5367 90)
			(unlocked yes)
			(layer "F.Fab")
			(hide yes)
			(effects
				(font
					(size 1.016 1.016)
					(thickness 0.1524)
				)
			)
		)
		(property "Device Type" "SOIC8H69"
			(at -3.707384 -3.0607 90)
			(unlocked yes)
			(layer "F.Fab")
			(hide yes)
			(effects
				(font
					(size 1.016 1.016)
					(thickness 0.1524)
				)
			)
		)
		(duplicate_pad_numbers_are_jumpers no)
		(fp_line
			(start 2.1336 -1.4224)
			(end -2.7432 -1.4224)
			(stroke
				(width 0.1524)
				(type default)
			)
			(layer "F.SilkS")
		)
		(fp_line
			(start -2.7432 -1.4224)
			(end -2.7432 1.4224)
			(stroke
				(width 0.1524)
				(type default)
			)
			(layer "F.SilkS")
		)
		(fp_line
			(start -2.7178 -0.508)
			(end -2.1844 -0.0508)
			(stroke
				(width 0.1524)
				(type default)
			)
			(layer "F.SilkS")
		)
		(fp_line
			(start -2.1844 -0.0508)
			(end -2.7178 0.508)
			(stroke
				(width 0.1524)
				(type default)
			)
			(layer "F.SilkS")
		)
		(fp_line
			(start 2.1336 1.4224)
			(end 2.1336 -1.4224)
			(stroke
				(width 0.1524)
				(type default)
			)
			(layer "F.SilkS")
		)
		(fp_line
			(start -2.7432 1.4224)
			(end 2.1336 1.4224)
			(stroke
				(width 0.1524)
				(type default)
			)
			(layer "F.SilkS")
		)
		(fp_line
			(start -2.7432 1.4224)
			(end -2.6416 1.4224)
			(stroke
				(width 0.1524)
				(type default)
			)
			(layer "F.SilkS")
		)
		(fp_line
			(start -2.6289 3.4417)
			(end -2.6289 1.4732)
			(stroke
				(width 0.381)
				(type default)
			)
			(layer "F.SilkS")
		)
		(fp_poly
			(pts
				(xy -2.2098 -1.4224) (xy -2.2098 1.4224) (xy 2.2098 1.4224) (xy 2.2098 -1.4224)
			)
			(stroke
				(width 0)
				(type default)
			)
			(fill yes)
			(layer "F.SilkS")
		)
		(fp_rect
			(start -2.450084 2.999994)
			(end 2.450084 -2.999994)
			(stroke
				(width 0)
				(type default)
			)
			(fill no)
			(layer "F.CrtYd")
		)
		(fp_poly
			(pts
				(xy -2.8194 3.6322) (xy -2.8194 -3.6322) (xy 2.8194 -3.6322) (xy 2.8194 1.18364) (xy 2.450084 1.18364)
				(xy 2.450084 -2.999994) (xy -2.450084 -2.999994) (xy -2.450084 2.999994) (xy 2.450084 2.999994)
				(xy 2.450084 1.18618) (xy 2.8194 1.18618) (xy 2.8194 3.6322)
			)
			(stroke
				(width 0)
				(type default)
			)
			(fill no)
			(layer "F.CrtYd")
		)
		(fp_rect
			(start -2.8194 3.6322)
			(end 2.8194 -3.6322)
			(stroke
				(width 0)
				(type default)
			)
			(fill no)
			(layer "F.Fab")
		)
		(pad "1" smd rect
			(at -1.905 2.54 90)
			(size 0.635 1.651)
			(layers "F.Cu" "F.Mask" "F.Paste")
			(net "P5V_HDD0")
		)
		(pad "2" smd rect
			(at -0.635 2.54 90)
			(size 0.635 1.651)
			(layers "F.Cu" "F.Mask" "F.Paste")
			(net "P5V_HDD0")
		)
		(pad "3" smd rect
			(at 0.635 2.54 90)
			(size 0.635 1.651)
			(layers "F.Cu" "F.Mask" "F.Paste")
			(net "P5V_HDD0")
		)
		(pad "4" smd rect
			(at 1.905 2.54 90)
			(size 0.635 1.651)
			(layers "F.Cu" "F.Mask" "F.Paste")
			(net "SW_HDD0_P")
		)
		(pad "5" smd rect
			(at 1.905 -2.54 90)
			(size 0.635 1.651)
			(layers "F.Cu" "F.Mask" "F.Paste")
			(net "P5VA")
		)
		(pad "6" smd rect
			(at 0.635 -2.54 90)
			(size 0.635 1.651)
			(layers "F.Cu" "F.Mask" "F.Paste")
			(net "P5VA")
		)
		(pad "7" smd rect
			(at -0.635 -2.54 90)
			(size 0.635 1.651)
			(layers "F.Cu" "F.Mask" "F.Paste")
			(net "P5VA")
		)
		(pad "8" smd rect
			(at -1.905 -2.54 90)
			(size 0.635 1.651)
			(layers "F.Cu" "F.Mask" "F.Paste")
			(net "P5VA")
		)
	)
	(footprint ""
		(layer "F.Cu")
		(at 10.8204 -476.7072)
		(property "Reference" "R608"
			(at 0 0 0)
			(layer "F.SilkS")
			(hide yes)
			(effects
				(font
					(size 1.27 1.27)
				)
			)
		)
		(property "Value" "2R2010J-1-GP"
			(at 0.254 -8.0772 0)
			(unlocked yes)
			(layer "F.Fab")
			(hide yes)
			(effects
				(font
					(size 1.016 1.016)
					(thickness 0.1524)
				)
			)
		)
		(property "Device Type" "R2010H28"
			(at 0.254 -9.6774 0)
			(unlocked yes)
			(layer "F.Fab")
			(hide yes)
			(effects
				(font
					(size 1.016 1.016)
					(thickness 0.1524)
				)
			)
		)
		(duplicate_pad_numbers_are_jumpers no)
		(fp_line
			(start -1.651 -3.302)
			(end -1.651 3.302)
			(stroke
				(width 0.1524)
				(type default)
			)
			(layer "F.SilkS")
		)
		(fp_line
			(start -1.651 3.302)
			(end 1.651 3.302)
			(stroke
				(width 0.1524)
				(type default)
			)
			(layer "F.SilkS")
		)
		(fp_line
			(start 1.651 -3.302)
			(end -1.651 -3.302)
			(stroke
				(width 0.1524)
				(type default)
			)
			(layer "F.SilkS")
		)
		(fp_line
			(start 1.651 3.302)
			(end 1.651 -3.302)
			(stroke
				(width 0.1524)
				(type default)
			)
			(layer "F.SilkS")
		)
		(fp_rect
			(start -1.7272 -3.3782)
			(end 1.7272 3.3782)
			(stroke
				(width 0)
				(type default)
			)
			(fill no)
			(layer "F.CrtYd")
		)
		(fp_poly
			(pts
				(xy 1.7272 3.3782) (xy 1.7272 -3.3782) (xy -1.7272 -3.3782) (xy -1.7272 3.3782)
			)
			(stroke
				(width 0)
				(type default)
			)
			(fill no)
			(layer "F.Fab")
		)
		(pad "1" smd rect
			(at 0 -2.3495)
			(size 2.794 1.143)
			(layers "F.Cu" "F.Mask" "F.Paste")
			(net "GND")
		)
		(pad "2" smd rect
			(at 0 2.3495)
			(size 2.794 1.143)
			(layers "F.Cu" "F.Mask" "F.Paste")
			(net "PCIE_MATED#_A")
		)
	)
	(footprint ""
		(layer "F.Cu")
		(at 42.500042 -376.670062 90)
		(property "Reference" "SKT7"
			(at 0 0 90)
			(layer "F.SilkS")
			(hide yes)
			(effects
				(font
					(size 1.27 1.27)
				)
			)
		)
		(property "Value" "SKT-SATA14P-15P-12-GP"
			(at -22.6187 8.1788 90)
			(unlocked yes)
			(layer "F.Fab")
			(hide yes)
			(effects
				(font
					(size 1.016 1.016)
					(thickness 0.1524)
				)
			)
		)
		(property "Device Type" "87945-1001"
			(at -22.6187 6.6548 90)
			(unlocked yes)
			(layer "F.Fab")
			(hide yes)
			(effects
				(font
					(size 1.016 1.016)
					(thickness 0.1524)
				)
			)
		)
		(duplicate_pad_numbers_are_jumpers no)
		(fp_line
			(start -15.3924 -5.8547)
			(end -16.3576 -5.8547)
			(stroke
				(width 0.3302)
				(type default)
			)
			(layer "F.SilkS")
		)
		(fp_line
			(start 20.4724 -5.7658)
			(end 20.4724 -2.3114)
			(stroke
				(width 0.1524)
				(type default)
			)
			(layer "F.SilkS")
		)
		(fp_line
			(start -20.4724 -5.7658)
			(end 20.4724 -5.7658)
			(stroke
				(width 0.1524)
				(type default)
			)
			(layer "F.SilkS")
		)
		(fp_line
			(start 23.7617 -2.3114)
			(end 23.7617 2.3114)
			(stroke
				(width 0.1524)
				(type default)
			)
			(layer "F.SilkS")
		)
		(fp_line
			(start 20.4724 -2.3114)
			(end 23.7617 -2.3114)
			(stroke
				(width 0.1524)
				(type default)
			)
			(layer "F.SilkS")
		)
		(fp_line
			(start -20.4724 -2.3114)
			(end -20.4724 -5.7658)
			(stroke
				(width 0.1524)
				(type default)
			)
			(layer "F.SilkS")
		)
		(fp_line
			(start -23.7617 -2.3114)
			(end -20.4724 -2.3114)
			(stroke
				(width 0.1524)
				(type default)
			)
			(layer "F.SilkS")
		)
		(fp_line
			(start 23.117556 -0.5461)
			(end 23.117556 0.5461)
			(stroke
				(width 0.3048)
				(type default)
			)
			(layer "F.SilkS")
		)
		(fp_line
			(start -20.882356 -0.5461)
			(end -20.882356 0.5461)
			(stroke
				(width 0.3048)
				(type default)
			)
			(layer "F.SilkS")
		)
		(fp_line
			(start 20.882356 0.5461)
			(end 20.882356 -0.5461)
			(stroke
				(width 0.3048)
				(type default)
			)
			(layer "F.SilkS")
		)
		(fp_line
			(start -23.117556 0.5461)
			(end -23.117556 -0.5461)
			(stroke
				(width 0.3048)
				(type default)
			)
			(layer "F.SilkS")
		)
		(fp_line
			(start 23.7617 2.3114)
			(end 20.4724 2.3114)
			(stroke
				(width 0.1524)
				(type default)
			)
			(layer "F.SilkS")
		)
		(fp_line
			(start 20.4724 2.3114)
			(end 20.4724 9.652)
			(stroke
				(width 0.1524)
				(type default)
			)
			(layer "F.SilkS")
		)
		(fp_line
			(start -20.4724 2.3114)
			(end -23.7617 2.3114)
			(stroke
				(width 0.1524)
				(type default)
			)
			(layer "F.SilkS")
		)
		(fp_line
			(start -23.7617 2.3114)
			(end -23.7617 -2.3114)
			(stroke
				(width 0.1524)
				(type default)
			)
			(layer "F.SilkS")
		)
		(fp_line
			(start 17.8435 7.9502)
			(end -17.8435 7.9502)
			(stroke
				(width 0.1524)
				(type default)
			)
			(layer "F.SilkS")
		)
		(fp_line
			(start -17.8435 7.9502)
			(end -17.8435 9.652)
			(stroke
				(width 0.1524)
				(type default)
			)
			(layer "F.SilkS")
		)
		(fp_line
			(start 20.4724 9.652)
			(end 17.8435 9.652)
			(stroke
				(width 0.1524)
				(type default)
			)
			(layer "F.SilkS")
		)
		(fp_line
			(start 17.8435 9.652)
			(end 17.8435 7.9502)
			(stroke
				(width 0.1524)
				(type default)
			)
			(layer "F.SilkS")
		)
		(fp_line
			(start -17.8435 9.652)
			(end -20.4724 9.652)
			(stroke
				(width 0.1524)
				(type default)
			)
			(layer "F.SilkS")
		)
		(fp_line
			(start -20.4724 9.652)
			(end -20.4724 2.3114)
			(stroke
				(width 0.1524)
				(type default)
			)
			(layer "F.SilkS")
		)
		(fp_arc
			(start 20.882356 -0.5461)
			(mid 21.999956 -1.6637)
			(end 23.117556 -0.5461)
			(stroke
				(width 0.3048)
				(type default)
			)
			(layer "F.SilkS")
		)
		(fp_arc
			(start -23.117556 -0.5461)
			(mid -21.999956 -1.6637)
			(end -20.882356 -0.5461)
			(stroke
				(width 0.3048)
				(type default)
			)
			(layer "F.SilkS")
		)
		(fp_arc
			(start 23.117556 0.5461)
			(mid 21.999956 1.6637)
			(end 20.882356 0.5461)
			(stroke
				(width 0.3048)
				(type default)
			)
			(layer "F.SilkS")
		)
		(fp_arc
			(start -20.882356 0.5461)
			(mid -21.999956 1.6637)
			(end -23.117556 0.5461)
			(stroke
				(width 0.3048)
				(type default)
			)
			(layer "F.SilkS")
		)
		(fp_poly
			(pts
				(xy -15.87119 -5.838698) (xy -15.23619 -6.473698) (xy -16.50619 -6.473698)
			)
			(stroke
				(width 0)
				(type default)
			)
			(fill yes)
			(layer "F.SilkS")
		)
		(fp_poly
			(pts
				(xy -20.2184 -5.5118) (xy 20.2184 -5.5118) (xy 20.2184 -2.0574) (xy 23.5077 -2.0574) (xy 23.5077 2.0574)
				(xy 20.2184 2.0574) (xy 20.2184 9.398) (xy 18.0975 9.398) (xy 18.0975 7.6962) (xy -18.0975 7.6962)
				(xy -18.0975 9.398) (xy -20.2184 9.398) (xy -20.2184 2.0574) (xy -23.5077 2.0574) (xy -23.5077 -2.0574)
				(xy -20.2184 -2.0574)
			)
			(stroke
				(width 0)
				(type default)
			)
			(fill no)
			(layer "F.CrtYd")
		)
		(fp_poly
			(pts
				(xy -20.2184 -5.5118) (xy -20.2184 -6.0198) (xy -20.7264 -6.0198) (xy -20.7264 -2.5654) (xy -24.0157 -2.5654)
				(xy -24.0157 2.5654) (xy -20.7264 2.5654) (xy -20.7264 9.906) (xy -17.5895 9.906) (xy -17.5895 8.2042)
				(xy 17.5895 8.2042) (xy 17.5895 9.906) (xy 20.7264 9.906) (xy 20.7264 2.5654) (xy 24.0157 2.5654)
				(xy 24.0157 -2.5654) (xy 20.7264 -2.5654) (xy 20.7264 -6.0198) (xy -20.21586 -6.0198) (xy -20.21586 -5.5118)
				(xy 20.2184 -5.5118) (xy 20.2184 -2.0574) (xy 23.5077 -2.0574) (xy 23.5077 2.0574) (xy 20.2184 2.0574)
				(xy 20.2184 9.398) (xy 18.0975 9.398) (xy 18.0975 7.6962) (xy -18.0975 7.6962) (xy -18.0975 9.398)
				(xy -20.2184 9.398) (xy -20.2184 2.0574) (xy -23.5077 2.0574) (xy -23.5077 -2.0574) (xy -20.2184 -2.0574)
			)
			(stroke
				(width 0)
				(type default)
			)
			(fill no)
			(layer "F.CrtYd")
		)
		(fp_poly
			(pts
				(xy -20.7264 -6.0198) (xy -20.7264 -2.5654) (xy -24.0157 -2.5654) (xy -24.0157 2.5654) (xy -20.7264 2.5654)
				(xy -20.7264 9.906) (xy -17.5895 9.906) (xy -17.5895 8.2042) (xy 17.5895 8.2042) (xy 17.5895 9.906)
				(xy 20.7264 9.906) (xy 20.7264 2.5654) (xy 24.0157 2.5654) (xy 24.0157 -2.5654) (xy 20.7264 -2.5654)
				(xy 20.7264 -6.0198)
			)
			(stroke
				(width 0)
				(type default)
			)
			(fill no)
			(layer "F.Fab")
		)
		(pad "" np_thru_hole circle
			(at -18.999962 -2.350008 90)
			(size 0.254 0.254)
			(drill 1.8542)
			(layers "*.Cu" "*.Mask")
			(clearance 1.1557)
			(thermal_gap 1.1557)
		)
		(pad "" np_thru_hole circle
			(at 18.999962 -2.350008 90)
			(size 0.254 0.254)
			(drill 1.8542)
			(layers "*.Cu" "*.Mask")
			(clearance 1.1557)
			(thermal_gap 1.1557)
		)
		(pad "H1" thru_hole oval
			(at -21.999956 0 90)
			(size 1.524 2.6162)
			(drill oval 0.8128 1.905)
			(layers "*.Cu" "*.Mask")
			(remove_unused_layers no)
			(net "GND")
			(clearance 0.1524)
			(thermal_gap 0.1524)
		)
		(pad "H2" thru_hole oval
			(at 21.999956 0 90)
			(size 1.524 2.6162)
			(drill oval 0.8128 1.905)
			(layers "*.Cu" "*.Mask")
			(remove_unused_layers no)
			(net "GND")
			(clearance 0.1524)
			(thermal_gap 0.1524)
		)
		(pad "P1" smd rect
			(at -1.89992 -4.249928 90)
			(size 0.6604 2.3876)
			(layers "F.Cu" "F.Mask" "F.Paste")
			(net "Net_15")
		)
		(pad "P2" smd rect
			(at -0.62992 -4.249928 90)
			(size 0.6604 2.3876)
			(layers "F.Cu" "F.Mask" "F.Paste")
			(net "Net_14")
		)
		(pad "P3" smd rect
			(at 0.64008 -4.249928 90)
			(size 0.6604 2.3876)
			(layers "F.Cu" "F.Mask" "F.Paste")
			(net "Net_13")
		)
		(pad "P4" smd rect
			(at 1.91008 -4.249928 90)
			(size 0.6604 2.3876)
			(layers "F.Cu" "F.Mask" "F.Paste")
			(net "GND")
		)
		(pad "P5" smd rect
			(at 3.18008 -4.249928 90)
			(size 0.6604 2.3876)
			(layers "F.Cu" "F.Mask" "F.Paste")
			(net "HDD_PRSNT_NET6")
		)
		(pad "P6" smd rect
			(at 4.45008 -4.249928 90)
			(size 0.6604 2.3876)
			(layers "F.Cu" "F.Mask" "F.Paste")
			(net "GND")
		)
		(pad "P7" smd rect
			(at 5.72008 -4.249928 90)
			(size 0.6604 2.3876)
			(layers "F.Cu" "F.Mask" "F.Paste")
			(net "5V_PRE_6")
		)
		(pad "P8" smd rect
			(at 6.99008 -4.249928 90)
			(size 0.6604 2.3876)
			(layers "F.Cu" "F.Mask" "F.Paste")
			(net "P5V_HDD6")
		)
		(pad "P9" smd rect
			(at 8.26008 -4.249928 90)
			(size 0.6604 2.3876)
			(layers "F.Cu" "F.Mask" "F.Paste")
			(net "P5V_HDD6")
		)
		(pad "P10" smd rect
			(at 9.53008 -4.249928 90)
			(size 0.6604 2.3876)
			(layers "F.Cu" "F.Mask" "F.Paste")
			(net "GND")
		)
		(pad "P11" smd rect
			(at 10.80008 -4.249928 90)
			(size 0.6604 2.3876)
			(layers "F.Cu" "F.Mask" "F.Paste")
			(net "ACT_HDD6")
		)
		(pad "P12" smd rect
			(at 12.07008 -4.249928 90)
			(size 0.6604 2.3876)
			(layers "F.Cu" "F.Mask" "F.Paste")
			(net "GND")
		)
		(pad "P13" smd rect
			(at 13.34008 -4.249928 90)
			(size 0.6604 2.3876)
			(layers "F.Cu" "F.Mask" "F.Paste")
			(net "12V_PRE_6")
		)
		(pad "P14" smd rect
			(at 14.61008 -4.249928 90)
			(size 0.6604 2.3876)
			(layers "F.Cu" "F.Mask" "F.Paste")
			(net "P12V_HDD6")
		)
		(pad "P15" smd rect
			(at 15.88008 -4.249928 90)
			(size 0.6604 2.3876)
			(layers "F.Cu" "F.Mask" "F.Paste")
			(net "P12V_HDD6")
		)
		(pad "S1" smd rect
			(at -15.86992 -4.249928 90)
			(size 0.6604 2.3876)
			(layers "F.Cu" "F.Mask" "F.Paste")
			(net "GND")
		)
		(pad "S2" smd rect
			(at -14.59992 -4.249928 90)
			(size 0.6604 2.3876)
			(layers "F.Cu" "F.Mask" "F.Paste")
			(net "SAS2X28_A_HDD6_TX_+")
		)
		(pad "S3" smd rect
			(at -13.32992 -4.249928 90)
			(size 0.6604 2.3876)
			(layers "F.Cu" "F.Mask" "F.Paste")
			(net "SAS2X28_A_HDD6_TX_-")
		)
		(pad "S4" smd rect
			(at -12.05992 -4.249928 90)
			(size 0.6604 2.3876)
			(layers "F.Cu" "F.Mask" "F.Paste")
			(net "GND")
		)
		(pad "S5" smd rect
			(at -10.78992 -4.249928 90)
			(size 0.6604 2.3876)
			(layers "F.Cu" "F.Mask" "F.Paste")
			(net "SAS2X28_DRIVE_RX_N_A6")
		)
		(pad "S6" smd rect
			(at -9.51992 -4.249928 90)
			(size 0.6604 2.3876)
			(layers "F.Cu" "F.Mask" "F.Paste")
			(net "SAS2X28_DRIVE_RX_P_A6")
		)
		(pad "S7" smd rect
			(at -8.24992 -4.249928 90)
			(size 0.6604 2.3876)
			(layers "F.Cu" "F.Mask" "F.Paste")
			(net "GND")
		)
		(pad "S8" smd rect
			(at -7.480046 -2.100072 90)
			(size 0.508 1.905)
			(layers "F.Cu" "F.Mask" "F.Paste")
			(net "GND")
		)
		(pad "S9" smd rect
			(at -6.679946 -2.100072 90)
			(size 0.508 1.905)
			(layers "F.Cu" "F.Mask" "F.Paste")
			(net "SAS2X28_B_HDD6_TX_+")
		)
		(pad "S10" smd rect
			(at -5.8801 -2.100072 90)
			(size 0.508 1.905)
			(layers "F.Cu" "F.Mask" "F.Paste")
			(net "SAS2X28_B_HDD6_TX_-")
		)
		(pad "S11" smd rect
			(at -5.08 -2.100072 90)
			(size 0.508 1.905)
			(layers "F.Cu" "F.Mask" "F.Paste")
			(net "GND")
		)
		(pad "S12" smd rect
			(at -4.2799 -2.100072 90)
			(size 0.508 1.905)
			(layers "F.Cu" "F.Mask" "F.Paste")
			(net "SAS2X28_DRIVE_RX_N_B6")
		)
		(pad "S13" smd rect
			(at -3.480054 -2.100072 90)
			(size 0.508 1.905)
			(layers "F.Cu" "F.Mask" "F.Paste")
			(net "SAS2X28_DRIVE_RX_P_B6")
		)
		(pad "S14" smd rect
			(at -2.679954 -2.100072 90)
			(size 0.508 1.905)
			(layers "F.Cu" "F.Mask" "F.Paste")
			(net "GND")
		)
		(zone
			(layers "F.Cu" "B.Cu" "In1.Cu" "In2.Cu" "In3.Cu" "In4.Cu" "In5.Cu" "In6.Cu")
			(hatch none 0.5)
			(connect_pads
				(clearance 0)
			)
			(min_thickness 0.25)
			(keepout
				(tracks not_allowed)
				(vias allowed)
				(pads allowed)
				(copperpour not_allowed)
				(footprints allowed)
			)
			(placement
				(enabled no)
				(sheetname "")
			)
			(fill
				(thermal_gap 0.5)
				(thermal_bridge_width 0.5)
				(island_removal_mode 0)
			)
			(polygon
				(pts
					(arc
						(start 41.381934 -395.670024)
						(mid 38.918134 -395.670024)
						(end 41.381934 -395.670024)
					)
				)
			)
		)
		(zone
			(layers "F.Cu" "B.Cu" "In1.Cu" "In2.Cu" "In3.Cu" "In4.Cu" "In5.Cu" "In6.Cu")
			(hatch none 0.5)
			(connect_pads
				(clearance 0)
			)
			(min_thickness 0.25)
			(keepout
				(tracks not_allowed)
				(vias allowed)
				(pads allowed)
				(copperpour not_allowed)
				(footprints allowed)
			)
			(placement
				(enabled no)
				(sheetname "")
			)
			(fill
				(thermal_gap 0.5)
				(thermal_bridge_width 0.5)
				(island_removal_mode 0)
			)
			(polygon
				(pts
					(arc
						(start 41.381934 -357.6701)
						(mid 38.918134 -357.6701)
						(end 41.381934 -357.6701)
					)
				)
			)
		)
	)
	(footprint ""
		(layer "F.Cu")
		(at 20.193254 -155.3083 -90)
		(property "Reference" "R283"
			(at 0 0 270)
			(layer "F.SilkS")
			(hide yes)
			(effects
				(font
					(size 1.27 1.27)
				)
			)
		)
		(property "Value" "402R2F-GP"
			(at 0.064008 -3.993896 270)
			(unlocked yes)
			(layer "F.Fab")
			(hide yes)
			(effects
				(font
					(size 1.016 1.016)
					(thickness 0.1524)
				)
			)
		)
		(property "Device Type" "R402H16"
			(at 0.064008 -5.517896 270)
			(unlocked yes)
			(layer "F.Fab")
			(hide yes)
			(effects
				(font
					(size 1.016 1.016)
					(thickness 0.1524)
				)
			)
		)
		(duplicate_pad_numbers_are_jumpers no)
		(fp_line
			(start -0.508 -0.9398)
			(end -0.508 0.9398)
			(stroke
				(width 0.1524)
				(type default)
			)
			(layer "F.SilkS")
		)
		(fp_line
			(start 0.508 -0.9398)
			(end -0.508 -0.9398)
			(stroke
				(width 0.1524)
				(type default)
			)
			(layer "F.SilkS")
		)
		(fp_rect
			(start -0.508 0.9398)
			(end 0.508 -0.9398)
			(stroke
				(width 0)
				(type default)
			)
			(fill no)
			(layer "F.CrtYd")
		)
		(fp_rect
			(start -0.508 0.9398)
			(end 0.508 -0.9398)
			(stroke
				(width 0)
				(type default)
			)
			(fill no)
			(layer "F.Fab")
		)
		(pad "1" smd custom
			(at 0 -0.4445 270)
			(size 0.1397 0.1397)
			(layers "F.Cu" "F.Mask" "F.Paste")
			(net "P5VC_HDD13_LED")
			(options
				(clearance outline)
				(anchor circle)
			)
			(primitives
				(gr_poly
					(pts
						(arc
							(start -0.1778 -0.2794)
							(mid -0.249642 -0.249642)
							(end -0.2794 -0.1778)
						)
						(arc
							(start -0.2794 0.1778)
							(mid -0.249642 0.249642)
							(end -0.1778 0.2794)
						)
						(arc
							(start 0.1778 0.2794)
							(mid 0.249642 0.249642)
							(end 0.2794 0.1778)
						)
						(arc
							(start 0.2794 -0.1778)
							(mid 0.249642 -0.249642)
							(end 0.1778 -0.2794)
						)
					)
					(width 0)
					(fill yes)
				)
			)
		)
		(pad "2" smd custom
			(at 0 0.4445 270)
			(size 0.1397 0.1397)
			(layers "F.Cu" "F.Mask" "F.Paste")
			(net "DRV_ACT_13")
			(options
				(clearance outline)
				(anchor circle)
			)
			(primitives
				(gr_poly
					(pts
						(arc
							(start -0.1778 -0.2794)
							(mid -0.249642 -0.249642)
							(end -0.2794 -0.1778)
						)
						(arc
							(start -0.2794 0.1778)
							(mid -0.249642 0.249642)
							(end -0.1778 0.2794)
						)
						(arc
							(start 0.1778 0.2794)
							(mid 0.249642 0.249642)
							(end 0.2794 0.1778)
						)
						(arc
							(start 0.2794 -0.1778)
							(mid 0.249642 -0.249642)
							(end 0.1778 -0.2794)
						)
					)
					(width 0)
					(fill yes)
				)
			)
		)
	)
	(footprint ""
		(layer "F.Cu")
		(at 25.298146 -273.6596 90)
		(property "Reference" "R494"
			(at 0 0 90)
			(layer "F.SilkS")
			(hide yes)
			(effects
				(font
					(size 1.27 1.27)
				)
			)
		)
		(property "Value" "4K7R2J-2-GP"
			(at 0.064008 -3.993896 90)
			(unlocked yes)
			(layer "F.Fab")
			(hide yes)
			(effects
				(font
					(size 1.016 1.016)
					(thickness 0.1524)
				)
			)
		)
		(property "Device Type" "R402H16"
			(at 0.064008 -5.517896 90)
			(unlocked yes)
			(layer "F.Fab")
			(hide yes)
			(effects
				(font
					(size 1.016 1.016)
					(thickness 0.1524)
				)
			)
		)
		(duplicate_pad_numbers_are_jumpers no)
		(fp_line
			(start 0.508 -0.9398)
			(end -0.508 -0.9398)
			(stroke
				(width 0.1524)
				(type default)
			)
			(layer "F.SilkS")
		)
		(fp_line
			(start -0.508 -0.9398)
			(end -0.508 0.9398)
			(stroke
				(width 0.1524)
				(type default)
			)
			(layer "F.SilkS")
		)
		(fp_rect
			(start -0.508 0.9398)
			(end 0.508 -0.9398)
			(stroke
				(width 0)
				(type default)
			)
			(fill no)
			(layer "F.CrtYd")
		)
		(fp_rect
			(start -0.508 0.9398)
			(end 0.508 -0.9398)
			(stroke
				(width 0)
				(type default)
			)
			(fill no)
			(layer "F.Fab")
		)
		(pad "1" smd custom
			(at 0 -0.4445 90)
			(size 0.1397 0.1397)
			(layers "F.Cu" "F.Mask" "F.Paste")
			(net "P3V3")
			(options
				(clearance outline)
				(anchor circle)
			)
			(primitives
				(gr_poly
					(pts
						(arc
							(start -0.1778 -0.2794)
							(mid -0.249642 -0.249642)
							(end -0.2794 -0.1778)
						)
						(arc
							(start -0.2794 0.1778)
							(mid -0.249642 0.249642)
							(end -0.1778 0.2794)
						)
						(arc
							(start 0.1778 0.2794)
							(mid 0.249642 0.249642)
							(end 0.2794 0.1778)
						)
						(arc
							(start 0.2794 -0.1778)
							(mid 0.249642 -0.249642)
							(end 0.1778 -0.2794)
						)
					)
					(width 0)
					(fill yes)
				)
			)
		)
		(pad "2" smd custom
			(at 0 0.4445 90)
			(size 0.1397 0.1397)
			(layers "F.Cu" "F.Mask" "F.Paste")
			(net "SAS2X28_A_HDD7_FLT")
			(options
				(clearance outline)
				(anchor circle)
			)
			(primitives
				(gr_poly
					(pts
						(arc
							(start -0.1778 -0.2794)
							(mid -0.249642 -0.249642)
							(end -0.2794 -0.1778)
						)
						(arc
							(start -0.2794 0.1778)
							(mid -0.249642 0.249642)
							(end -0.1778 0.2794)
						)
						(arc
							(start 0.1778 0.2794)
							(mid 0.249642 0.249642)
							(end 0.2794 0.1778)
						)
						(arc
							(start 0.2794 -0.1778)
							(mid 0.249642 -0.249642)
							(end 0.1778 -0.2794)
						)
					)
					(width 0)
					(fill yes)
				)
			)
		)
	)
	(footprint ""
		(layer "F.Cu")
		(at 85.344 -499.618 180)
		(property "Reference" "D20"
			(at 0 0 180)
			(layer "F.SilkS")
			(hide yes)
			(effects
				(font
					(size 1.27 1.27)
				)
			)
		)
		(property "Value" "RB551V30-1-GP"
			(at 0 -6.7818 180)
			(unlocked yes)
			(layer "F.Fab")
			(hide yes)
			(effects
				(font
					(size 1.016 1.016)
					(thickness 0.1524)
				)
			)
		)
		(property "Device Type" "SOD323AKH44"
			(at 0 -8.6868 180)
			(unlocked yes)
			(layer "F.Fab")
			(hide yes)
			(effects
				(font
					(size 1.016 1.016)
					(thickness 0.1524)
				)
			)
		)
		(duplicate_pad_numbers_are_jumpers no)
		(fp_line
			(start 0.889 2.159)
			(end -0.889 2.159)
			(stroke
				(width 0.1524)
				(type default)
			)
			(layer "F.SilkS")
		)
		(fp_line
			(start 0.889 -1.9304)
			(end 0.889 2.159)
			(stroke
				(width 0.1524)
				(type default)
			)
			(layer "F.SilkS")
		)
		(fp_line
			(start 0.762 2.0574)
			(end -0.762 2.0574)
			(stroke
				(width 0.508)
				(type default)
			)
			(layer "F.SilkS")
		)
		(fp_line
			(start -0.889 2.159)
			(end -0.889 -1.9304)
			(stroke
				(width 0.1524)
				(type default)
			)
			(layer "F.SilkS")
		)
		(fp_line
			(start -0.889 -1.9304)
			(end 0.889 -1.9304)
			(stroke
				(width 0.1524)
				(type default)
			)
			(layer "F.SilkS")
		)
		(fp_rect
			(start -1.016 2.3114)
			(end 1.016 -2.0066)
			(stroke
				(width 0)
				(type default)
			)
			(fill no)
			(layer "F.CrtYd")
		)
		(fp_poly
			(pts
				(xy -1.016 -2.0066) (xy 1.016 -2.0066) (xy 1.016 2.3114) (xy -1.016 2.3114)
			)
			(stroke
				(width 0)
				(type default)
			)
			(fill no)
			(layer "F.Fab")
		)
		(pad "A" smd rect
			(at 0 -1.143 180)
			(size 0.5588 1.016)
			(layers "F.Cu" "F.Mask" "F.Paste")
			(net "SW_HDD5_R")
		)
		(pad "K" smd rect
			(at 0 1.143 180)
			(size 0.5588 1.016)
			(layers "F.Cu" "F.Mask" "F.Paste")
			(net "SW_HDD5_N")
		)
	)
	(footprint ""
		(layer "F.Cu")
		(at 26.288746 -480.1997 90)
		(property "Reference" "PTC5"
			(at 0 0 90)
			(layer "F.SilkS")
			(hide yes)
			(effects
				(font
					(size 1.27 1.27)
				)
			)
		)
		(property "Value" "ST330U10VDM-2GP"
			(at 0 -9.6012 90)
			(unlocked yes)
			(layer "F.Fab")
			(hide yes)
			(effects
				(font
					(size 1.016 1.016)
					(thickness 0.1524)
				)
			)
		)
		(property "Device Type" "CT7343H150"
			(at 0 -11.1252 90)
			(unlocked yes)
			(layer "F.Fab")
			(hide yes)
			(effects
				(font
					(size 1.016 1.016)
					(thickness 0.1524)
				)
			)
		)
		(duplicate_pad_numbers_are_jumpers no)
		(fp_line
			(start 2.286 -4.8768)
			(end -2.286 -4.8768)
			(stroke
				(width 0.1524)
				(type default)
			)
			(layer "F.SilkS")
		)
		(fp_line
			(start -2.286 -4.8768)
			(end -2.286 -2.032)
			(stroke
				(width 0.1524)
				(type default)
			)
			(layer "F.SilkS")
		)
		(fp_line
			(start 2.1082 -4.699)
			(end -2.1082 -4.699)
			(stroke
				(width 0.508)
				(type default)
			)
			(layer "F.SilkS")
		)
		(fp_line
			(start 2.286 -2.032)
			(end 2.286 -4.8768)
			(stroke
				(width 0.1524)
				(type default)
			)
			(layer "F.SilkS")
		)
		(fp_line
			(start 2.286 2.032)
			(end 2.286 4.8768)
			(stroke
				(width 0.1524)
				(type default)
			)
			(layer "F.SilkS")
		)
		(fp_line
			(start 2.286 4.8768)
			(end -2.286 4.8768)
			(stroke
				(width 0.1524)
				(type default)
			)
			(layer "F.SilkS")
		)
		(fp_line
			(start -2.286 4.8768)
			(end -2.286 2.032)
			(stroke
				(width 0.1524)
				(type default)
			)
			(layer "F.SilkS")
		)
		(fp_rect
			(start -2.1463 3.6449)
			(end 2.1463 -3.6449)
			(stroke
				(width 0)
				(type default)
			)
			(fill no)
			(layer "F.CrtYd")
		)
		(fp_poly
			(pts
				(xy -2.54 4.953) (xy -2.54 4.2926) (xy -3.81 4.2926) (xy -3.81 -4.2926) (xy -2.54 -4.2926) (xy -2.54 -4.953)
				(xy 2.54 -4.953) (xy 2.54 -4.2926) (xy 3.81 -4.2926) (xy 3.81 -1.6256) (xy 2.1463 -1.6256) (xy 2.1463 -3.6449)
				(xy -2.1463 -3.6449) (xy -2.1463 3.6449) (xy 2.1463 3.6449) (xy 2.1463 -1.6129) (xy 3.81 -1.6129)
				(xy 3.81 4.2926) (xy 2.54 4.2926) (xy 2.54 4.953)
			)
			(stroke
				(width 0)
				(type default)
			)
			(fill no)
			(layer "F.CrtYd")
		)
		(fp_rect
			(start 2.54 4.2926)
			(end 3.81 -4.2926)
			(stroke
				(width 0)
				(type default)
			)
			(fill no)
			(layer "F.Fab")
		)
		(fp_rect
			(start -3.81 4.2926)
			(end -2.54 -4.2926)
			(stroke
				(width 0)
				(type default)
			)
			(fill no)
			(layer "F.Fab")
		)
		(fp_rect
			(start -2.54 4.953)
			(end 2.54 -4.953)
			(stroke
				(width 0)
				(type default)
			)
			(fill no)
			(layer "F.Fab")
		)
		(pad "1" smd rect
			(at 0 -3.1496 90)
			(size 2.413 2.286)
			(layers "F.Cu" "F.Mask" "F.Paste")
			(net "P5VC")
		)
		(pad "2" smd rect
			(at 0 3.1496 90)
			(size 2.413 2.286)
			(layers "F.Cu" "F.Mask" "F.Paste")
			(net "GND")
		)
		(zone
			(layer "F.Cu")
			(hatch none 0.5)
			(connect_pads
				(clearance 0)
			)
			(min_thickness 0.25)
			(keepout
				(tracks allowed)
				(vias not_allowed)
				(pads allowed)
				(copperpour not_allowed)
				(footprints allowed)
			)
			(placement
				(enabled no)
				(sheetname "")
			)
			(fill
				(thermal_gap 0.5)
				(thermal_bridge_width 0.5)
				(island_removal_mode 0)
			)
			(polygon
				(pts
					(xy 24.599646 -481.711) (xy 21.691346 -481.711) (xy 21.691346 -478.6884) (xy 24.586946 -478.6884)
					(xy 24.917146 -478.6884) (xy 24.917146 -481.711)
				)
			)
		)
		(zone
			(layer "F.Cu")
			(hatch none 0.5)
			(connect_pads
				(clearance 0)
			)
			(min_thickness 0.25)
			(keepout
				(tracks allowed)
				(vias not_allowed)
				(pads allowed)
				(copperpour not_allowed)
				(footprints allowed)
			)
			(placement
				(enabled no)
				(sheetname "")
			)
			(fill
				(thermal_gap 0.5)
				(thermal_bridge_width 0.5)
				(island_removal_mode 0)
			)
			(polygon
				(pts
					(xy 30.886146 -478.6884) (xy 30.886146 -481.711) (xy 27.990546 -481.711) (xy 27.660346 -481.711)
					(xy 27.660346 -478.6884) (xy 27.990546 -478.6884)
				)
			)
		)
	)
	(footprint ""
		(layer "F.Cu")
		(at 195.58 -191.262 180)
		(property "Reference" "C382"
			(at 0 0 180)
			(layer "F.SilkS")
			(hide yes)
			(effects
				(font
					(size 1.27 1.27)
				)
			)
		)
		(property "Value" "SCD033U25V2KX-GP"
			(at 1.1811 -2.7051 180)
			(unlocked yes)
			(layer "F.Fab")
			(hide yes)
			(effects
				(font
					(size 1.016 1.016)
					(thickness 0.1524)
				)
			)
		)
		(property "Device Type" "C402H22"
			(at 1.1811 -4.2291 180)
			(unlocked yes)
			(layer "F.Fab")
			(hide yes)
			(effects
				(font
					(size 1.016 1.016)
					(thickness 0.1524)
				)
			)
		)
		(duplicate_pad_numbers_are_jumpers no)
		(fp_rect
			(start -0.4318 0.9525)
			(end 0.4318 -0.9525)
			(stroke
				(width 0)
				(type default)
			)
			(fill no)
			(layer "F.CrtYd")
		)
		(fp_rect
			(start -0.4318 0.9525)
			(end 0.4318 -0.9525)
			(stroke
				(width 0)
				(type default)
			)
			(fill no)
			(layer "F.Fab")
		)
		(pad "1" smd custom
			(at 0 -0.4445 180)
			(size 0.1524 0.1524)
			(layers "F.Cu" "F.Mask" "F.Paste")
			(net "SW_HDD3_N")
			(options
				(clearance outline)
				(anchor circle)
			)
			(primitives
				(gr_poly
					(pts
						(arc
							(start 0.3048 -0.2032)
							(mid 0.275042 -0.275042)
							(end 0.2032 -0.3048)
						)
						(arc
							(start -0.2032 -0.3048)
							(mid -0.275042 -0.275042)
							(end -0.3048 -0.2032)
						)
						(arc
							(start -0.3048 0.2032)
							(mid -0.275042 0.275042)
							(end -0.2032 0.3048)
						)
						(arc
							(start 0.2032 0.3048)
							(mid 0.275042 0.275042)
							(end 0.3048 0.2032)
						)
					)
					(width 0)
					(fill yes)
				)
			)
		)
		(pad "2" smd custom
			(at 0 0.4445 180)
			(size 0.1524 0.1524)
			(layers "F.Cu" "F.Mask" "F.Paste")
			(net "P12V")
			(options
				(clearance outline)
				(anchor circle)
			)
			(primitives
				(gr_poly
					(pts
						(arc
							(start 0.3048 -0.2032)
							(mid 0.275042 -0.275042)
							(end 0.2032 -0.3048)
						)
						(arc
							(start -0.2032 -0.3048)
							(mid -0.275042 -0.275042)
							(end -0.3048 -0.2032)
						)
						(arc
							(start -0.3048 0.2032)
							(mid -0.275042 0.275042)
							(end -0.2032 0.3048)
						)
						(arc
							(start 0.2032 0.3048)
							(mid 0.275042 0.275042)
							(end 0.3048 0.2032)
						)
					)
					(width 0)
					(fill yes)
				)
			)
		)
	)
	(footprint ""
		(layer "F.Cu")
		(at 34.543746 -108.486702 90)
		(property "Reference" "R473"
			(at 0 0 90)
			(layer "F.SilkS")
			(hide yes)
			(effects
				(font
					(size 1.27 1.27)
				)
			)
		)
		(property "Value" "4K7R2J-2-GP"
			(at 0.064008 -3.993896 90)
			(unlocked yes)
			(layer "F.Fab")
			(hide yes)
			(effects
				(font
					(size 1.016 1.016)
					(thickness 0.1524)
				)
			)
		)
		(property "Device Type" "R402H16"
			(at 0.064008 -5.517896 90)
			(unlocked yes)
			(layer "F.Fab")
			(hide yes)
			(effects
				(font
					(size 1.016 1.016)
					(thickness 0.1524)
				)
			)
		)
		(duplicate_pad_numbers_are_jumpers no)
		(fp_line
			(start 0.508 -0.9398)
			(end -0.508 -0.9398)
			(stroke
				(width 0.1524)
				(type default)
			)
			(layer "F.SilkS")
		)
		(fp_line
			(start -0.508 -0.9398)
			(end -0.508 0.9398)
			(stroke
				(width 0.1524)
				(type default)
			)
			(layer "F.SilkS")
		)
		(fp_rect
			(start -0.508 0.9398)
			(end 0.508 -0.9398)
			(stroke
				(width 0)
				(type default)
			)
			(fill no)
			(layer "F.CrtYd")
		)
		(fp_rect
			(start -0.508 0.9398)
			(end 0.508 -0.9398)
			(stroke
				(width 0)
				(type default)
			)
			(fill no)
			(layer "F.Fab")
		)
		(pad "1" smd custom
			(at 0 -0.4445 90)
			(size 0.1397 0.1397)
			(layers "F.Cu" "F.Mask" "F.Paste")
			(net "P3V3")
			(options
				(clearance outline)
				(anchor circle)
			)
			(primitives
				(gr_poly
					(pts
						(arc
							(start -0.1778 -0.2794)
							(mid -0.249642 -0.249642)
							(end -0.2794 -0.1778)
						)
						(arc
							(start -0.2794 0.1778)
							(mid -0.249642 0.249642)
							(end -0.1778 0.2794)
						)
						(arc
							(start 0.1778 0.2794)
							(mid 0.249642 0.249642)
							(end 0.2794 0.1778)
						)
						(arc
							(start 0.2794 -0.1778)
							(mid 0.249642 -0.249642)
							(end 0.1778 -0.2794)
						)
					)
					(width 0)
					(fill yes)
				)
			)
		)
		(pad "2" smd custom
			(at 0 0.4445 90)
			(size 0.1397 0.1397)
			(layers "F.Cu" "F.Mask" "F.Paste")
			(net "SAS_EXP_B_PWR13")
			(options
				(clearance outline)
				(anchor circle)
			)
			(primitives
				(gr_poly
					(pts
						(arc
							(start -0.1778 -0.2794)
							(mid -0.249642 -0.249642)
							(end -0.2794 -0.1778)
						)
						(arc
							(start -0.2794 0.1778)
							(mid -0.249642 0.249642)
							(end -0.1778 0.2794)
						)
						(arc
							(start 0.1778 0.2794)
							(mid 0.249642 0.249642)
							(end 0.2794 0.1778)
						)
						(arc
							(start 0.2794 -0.1778)
							(mid 0.249642 -0.249642)
							(end 0.1778 -0.2794)
						)
					)
					(width 0)
					(fill yes)
				)
			)
		)
	)
	(footprint ""
		(layer "F.Cu")
		(at 193.669412 -86.213696 -90)
		(property "Reference" "Q10"
			(at 0 0 270)
			(layer "F.SilkS")
			(hide yes)
			(effects
				(font
					(size 1.27 1.27)
				)
			)
		)
		(property "Value" "2N7002DW-7F-GP"
			(at -2.3622 -8.2042 270)
			(unlocked yes)
			(layer "F.Fab")
			(hide yes)
			(effects
				(font
					(size 1.016 1.016)
					(thickness 0.1524)
				)
			)
		)
		(property "Device Type" "SOT-363H44"
			(at -2.3622 -10.1092 270)
			(unlocked yes)
			(layer "F.Fab")
			(hide yes)
			(effects
				(font
					(size 1.016 1.016)
					(thickness 0.1524)
				)
			)
		)
		(duplicate_pad_numbers_are_jumpers no)
		(fp_line
			(start -1.4478 1.7018)
			(end 1.4478 1.7018)
			(stroke
				(width 0.1524)
				(type default)
			)
			(layer "F.SilkS")
		)
		(fp_line
			(start 1.4478 1.7018)
			(end 1.4478 -1.7018)
			(stroke
				(width 0.1524)
				(type default)
			)
			(layer "F.SilkS")
		)
		(fp_line
			(start -1.27 1.524)
			(end -1.27 0.6604)
			(stroke
				(width 0.4826)
				(type default)
			)
			(layer "F.SilkS")
		)
		(fp_line
			(start -1.4478 -1.7018)
			(end -1.4478 1.7018)
			(stroke
				(width 0.1524)
				(type default)
			)
			(layer "F.SilkS")
		)
		(fp_line
			(start 1.4478 -1.7018)
			(end -1.4478 -1.7018)
			(stroke
				(width 0.1524)
				(type default)
			)
			(layer "F.SilkS")
		)
		(fp_poly
			(pts
				(xy -1.524 -1.778) (xy 1.524 -1.778) (xy 1.524 1.778) (xy -1.524 1.778)
			)
			(stroke
				(width 0)
				(type default)
			)
			(fill no)
			(layer "F.CrtYd")
		)
		(fp_poly
			(pts
				(xy -1.524 -1.778) (xy 1.524 -1.778) (xy 1.524 1.778) (xy -1.524 1.778)
			)
			(stroke
				(width 0)
				(type default)
			)
			(fill no)
			(layer "F.Fab")
		)
		(pad "1" smd rect
			(at -0.65024 0.9398 270)
			(size 0.4064 1.016)
			(layers "F.Cu" "F.Mask" "F.Paste")
			(net "GND")
		)
		(pad "2" smd rect
			(at 0 0.9398 270)
			(size 0.4064 1.016)
			(layers "F.Cu" "F.Mask" "F.Paste")
			(net "SW_PWR_R_HDD4")
		)
		(pad "3" smd rect
			(at 0.65024 0.9398 270)
			(size 0.4064 1.016)
			(layers "F.Cu" "F.Mask" "F.Paste")
			(net "SW_HDD4_P")
		)
		(pad "4" smd rect
			(at 0.65024 -0.9398 270)
			(size 0.4064 1.016)
			(layers "F.Cu" "F.Mask" "F.Paste")
			(net "GND")
		)
		(pad "5" smd rect
			(at 0 -0.9398 270)
			(size 0.4064 1.016)
			(layers "F.Cu" "F.Mask" "F.Paste")
			(net "SW_HDD4_G")
		)
		(pad "6" smd rect
			(at -0.65024 -0.9398 270)
			(size 0.4064 1.016)
			(layers "F.Cu" "F.Mask" "F.Paste")
			(net "SW_HDD4_R")
		)
	)
	(footprint ""
		(layer "F.Cu")
		(at 7.746746 -403.95144 180)
		(property "Reference" "R358"
			(at 0 0 180)
			(layer "F.SilkS")
			(hide yes)
			(effects
				(font
					(size 1.27 1.27)
				)
			)
		)
		(property "Value" "100R2J-2-GP"
			(at 0.064008 -3.993896 180)
			(unlocked yes)
			(layer "F.Fab")
			(hide yes)
			(effects
				(font
					(size 1.016 1.016)
					(thickness 0.1524)
				)
			)
		)
		(property "Device Type" "R402H14"
			(at 0.064008 -5.517896 180)
			(unlocked yes)
			(layer "F.Fab")
			(hide yes)
			(effects
				(font
					(size 1.016 1.016)
					(thickness 0.1524)
				)
			)
		)
		(duplicate_pad_numbers_are_jumpers no)
		(fp_line
			(start 0.508 -0.9398)
			(end -0.508 -0.9398)
			(stroke
				(width 0.1524)
				(type default)
			)
			(layer "F.SilkS")
		)
		(fp_line
			(start -0.508 -0.9398)
			(end -0.508 0.9398)
			(stroke
				(width 0.1524)
				(type default)
			)
			(layer "F.SilkS")
		)
		(fp_rect
			(start -0.508 0.9398)
			(end 0.508 -0.9398)
			(stroke
				(width 0)
				(type default)
			)
			(fill no)
			(layer "F.CrtYd")
		)
		(fp_rect
			(start -0.508 0.9398)
			(end 0.508 -0.9398)
			(stroke
				(width 0)
				(type default)
			)
			(fill no)
			(layer "F.Fab")
		)
		(pad "1" smd custom
			(at 0 -0.4445 180)
			(size 0.1397 0.1397)
			(layers "F.Cu" "F.Mask" "F.Paste")
			(net "TEMP_SENSOR_A_ADDR0&ID")
			(options
				(clearance outline)
				(anchor circle)
			)
			(primitives
				(gr_poly
					(pts
						(arc
							(start -0.1778 -0.2794)
							(mid -0.249642 -0.249642)
							(end -0.2794 -0.1778)
						)
						(arc
							(start -0.2794 0.1778)
							(mid -0.249642 0.249642)
							(end -0.1778 0.2794)
						)
						(arc
							(start 0.1778 0.2794)
							(mid 0.249642 0.249642)
							(end 0.2794 0.1778)
						)
						(arc
							(start 0.2794 -0.1778)
							(mid 0.249642 -0.249642)
							(end 0.1778 -0.2794)
						)
					)
					(width 0)
					(fill yes)
				)
			)
		)
		(pad "2" smd custom
			(at 0 0.4445 180)
			(size 0.1397 0.1397)
			(layers "F.Cu" "F.Mask" "F.Paste")
			(net "GND")
			(options
				(clearance outline)
				(anchor circle)
			)
			(primitives
				(gr_poly
					(pts
						(arc
							(start -0.1778 -0.2794)
							(mid -0.249642 -0.249642)
							(end -0.2794 -0.1778)
						)
						(arc
							(start -0.2794 0.1778)
							(mid -0.249642 0.249642)
							(end -0.1778 0.2794)
						)
						(arc
							(start 0.1778 0.2794)
							(mid 0.249642 0.249642)
							(end 0.2794 0.1778)
						)
						(arc
							(start 0.2794 -0.1778)
							(mid 0.249642 -0.249642)
							(end 0.1778 -0.2794)
						)
					)
					(width 0)
					(fill yes)
				)
			)
		)
	)
	(footprint ""
		(layer "F.Cu")
		(at 190.960756 -492.179102 -90)
		(property "Reference" "R107"
			(at 0 0 270)
			(layer "F.SilkS")
			(hide yes)
			(effects
				(font
					(size 1.27 1.27)
				)
			)
		)
		(property "Value" "1KR2F-3-GP"
			(at 0.064008 -3.993896 270)
			(unlocked yes)
			(layer "F.Fab")
			(hide yes)
			(effects
				(font
					(size 1.016 1.016)
					(thickness 0.1524)
				)
			)
		)
		(property "Device Type" "R402H16"
			(at 0.064008 -5.517896 270)
			(unlocked yes)
			(layer "F.Fab")
			(hide yes)
			(effects
				(font
					(size 1.016 1.016)
					(thickness 0.1524)
				)
			)
		)
		(duplicate_pad_numbers_are_jumpers no)
		(fp_line
			(start -0.508 -0.9398)
			(end -0.508 0.9398)
			(stroke
				(width 0.1524)
				(type default)
			)
			(layer "F.SilkS")
		)
		(fp_line
			(start 0.508 -0.9398)
			(end -0.508 -0.9398)
			(stroke
				(width 0.1524)
				(type default)
			)
			(layer "F.SilkS")
		)
		(fp_rect
			(start -0.508 0.9398)
			(end 0.508 -0.9398)
			(stroke
				(width 0)
				(type default)
			)
			(fill no)
			(layer "F.CrtYd")
		)
		(fp_rect
			(start -0.508 0.9398)
			(end 0.508 -0.9398)
			(stroke
				(width 0)
				(type default)
			)
			(fill no)
			(layer "F.Fab")
		)
		(pad "1" smd custom
			(at 0 -0.4445 270)
			(size 0.1397 0.1397)
			(layers "F.Cu" "F.Mask" "F.Paste")
			(net "P3V3")
			(options
				(clearance outline)
				(anchor circle)
			)
			(primitives
				(gr_poly
					(pts
						(arc
							(start -0.1778 -0.2794)
							(mid -0.249642 -0.249642)
							(end -0.2794 -0.1778)
						)
						(arc
							(start -0.2794 0.1778)
							(mid -0.249642 0.249642)
							(end -0.1778 0.2794)
						)
						(arc
							(start 0.1778 0.2794)
							(mid 0.249642 0.249642)
							(end 0.2794 0.1778)
						)
						(arc
							(start 0.2794 -0.1778)
							(mid 0.249642 -0.249642)
							(end 0.1778 -0.2794)
						)
					)
					(width 0)
					(fill yes)
				)
			)
		)
		(pad "2" smd custom
			(at 0 0.4445 270)
			(size 0.1397 0.1397)
			(layers "F.Cu" "F.Mask" "F.Paste")
			(net "SW_PWR_HDD0")
			(options
				(clearance outline)
				(anchor circle)
			)
			(primitives
				(gr_poly
					(pts
						(arc
							(start -0.1778 -0.2794)
							(mid -0.249642 -0.249642)
							(end -0.2794 -0.1778)
						)
						(arc
							(start -0.2794 0.1778)
							(mid -0.249642 0.249642)
							(end -0.1778 0.2794)
						)
						(arc
							(start 0.1778 0.2794)
							(mid 0.249642 0.249642)
							(end 0.2794 0.1778)
						)
						(arc
							(start 0.2794 -0.1778)
							(mid 0.249642 -0.249642)
							(end 0.1778 -0.2794)
						)
					)
					(width 0)
					(fill yes)
				)
			)
		)
	)
	(footprint ""
		(layer "F.Cu")
		(at 242.569746 -11.6967 90)
		(property "Reference" "PC5"
			(at 0 0 90)
			(layer "F.SilkS")
			(hide yes)
			(effects
				(font
					(size 1.27 1.27)
				)
			)
		)
		(property "Value" "SC22U25V5MX-GP"
			(at -0.0762 -6.1214 90)
			(unlocked yes)
			(layer "F.Fab")
			(hide yes)
			(effects
				(font
					(size 1.016 1.016)
					(thickness 0.1524)
				)
			)
		)
		(property "Device Type" "C805H58"
			(at -0.0762 -8.1534 90)
			(unlocked yes)
			(layer "F.Fab")
			(hide yes)
			(effects
				(font
					(size 1.016 1.016)
					(thickness 0.1524)
				)
			)
		)
		(duplicate_pad_numbers_are_jumpers no)
		(fp_line
			(start 0.635 0)
			(end -0.635 0)
			(stroke
				(width 0.508)
				(type default)
			)
			(layer "F.SilkS")
		)
		(fp_rect
			(start -0.9652 1.778)
			(end 0.9652 -1.778)
			(stroke
				(width 0)
				(type default)
			)
			(fill no)
			(layer "F.CrtYd")
		)
		(fp_poly
			(pts
				(xy -0.9652 -1.778) (xy 0.9652 -1.778) (xy 0.9652 1.778) (xy -0.9652 1.778)
			)
			(stroke
				(width 0)
				(type default)
			)
			(fill no)
			(layer "F.Fab")
		)
		(pad "1" smd rect
			(at 0 -0.9652 90)
			(size 1.397 1.143)
			(layers "F.Cu" "F.Mask" "F.Paste")
			(net "P5VA_12VIN")
		)
		(pad "2" smd rect
			(at 0 0.9652 90)
			(size 1.397 1.143)
			(layers "F.Cu" "F.Mask" "F.Paste")
			(net "GND")
		)
	)
	(footprint ""
		(layer "F.Cu")
		(at 57.531 -375.9454 90)
		(property "Reference" "R377"
			(at 0 0 90)
			(layer "F.SilkS")
			(hide yes)
			(effects
				(font
					(size 1.27 1.27)
				)
			)
		)
		(property "Value" "10KR2F-2-GP"
			(at 0.064008 -3.993896 90)
			(unlocked yes)
			(layer "F.Fab")
			(hide yes)
			(effects
				(font
					(size 1.016 1.016)
					(thickness 0.1524)
				)
			)
		)
		(property "Device Type" "R402H16"
			(at 0.064008 -5.517896 90)
			(unlocked yes)
			(layer "F.Fab")
			(hide yes)
			(effects
				(font
					(size 1.016 1.016)
					(thickness 0.1524)
				)
			)
		)
		(duplicate_pad_numbers_are_jumpers no)
		(fp_line
			(start 0.508 -0.9398)
			(end -0.508 -0.9398)
			(stroke
				(width 0.1524)
				(type default)
			)
			(layer "F.SilkS")
		)
		(fp_line
			(start -0.508 -0.9398)
			(end -0.508 0.9398)
			(stroke
				(width 0.1524)
				(type default)
			)
			(layer "F.SilkS")
		)
		(fp_rect
			(start -0.508 0.9398)
			(end 0.508 -0.9398)
			(stroke
				(width 0)
				(type default)
			)
			(fill no)
			(layer "F.CrtYd")
		)
		(fp_rect
			(start -0.508 0.9398)
			(end 0.508 -0.9398)
			(stroke
				(width 0)
				(type default)
			)
			(fill no)
			(layer "F.Fab")
		)
		(pad "1" smd custom
			(at 0 -0.4445 90)
			(size 0.1397 0.1397)
			(layers "F.Cu" "F.Mask" "F.Paste")
			(net "P12V")
			(options
				(clearance outline)
				(anchor circle)
			)
			(primitives
				(gr_poly
					(pts
						(arc
							(start -0.1778 -0.2794)
							(mid -0.249642 -0.249642)
							(end -0.2794 -0.1778)
						)
						(arc
							(start -0.2794 0.1778)
							(mid -0.249642 0.249642)
							(end -0.1778 0.2794)
						)
						(arc
							(start 0.1778 0.2794)
							(mid 0.249642 0.249642)
							(end 0.2794 0.1778)
						)
						(arc
							(start 0.2794 -0.1778)
							(mid 0.249642 -0.249642)
							(end 0.1778 -0.2794)
						)
					)
					(width 0)
					(fill yes)
				)
			)
		)
		(pad "2" smd custom
			(at 0 0.4445 90)
			(size 0.1397 0.1397)
			(layers "F.Cu" "F.Mask" "F.Paste")
			(net "HDD6_LED_G")
			(options
				(clearance outline)
				(anchor circle)
			)
			(primitives
				(gr_poly
					(pts
						(arc
							(start -0.1778 -0.2794)
							(mid -0.249642 -0.249642)
							(end -0.2794 -0.1778)
						)
						(arc
							(start -0.2794 0.1778)
							(mid -0.249642 0.249642)
							(end -0.1778 0.2794)
						)
						(arc
							(start 0.1778 0.2794)
							(mid 0.249642 0.249642)
							(end 0.2794 0.1778)
						)
						(arc
							(start 0.2794 -0.1778)
							(mid 0.249642 -0.249642)
							(end 0.1778 -0.2794)
						)
					)
					(width 0)
					(fill yes)
				)
			)
		)
	)
	(footprint ""
		(layer "F.Cu")
		(at 95.7834 -10.7442 -90)
		(property "Reference" "R480"
			(at 0 0 270)
			(layer "F.SilkS")
			(hide yes)
			(effects
				(font
					(size 1.27 1.27)
				)
			)
		)
		(property "Value" "0R2J-2-GP"
			(at 0.064008 -3.993896 270)
			(unlocked yes)
			(layer "F.Fab")
			(hide yes)
			(effects
				(font
					(size 1.016 1.016)
					(thickness 0.1524)
				)
			)
		)
		(property "Device Type" "R402H16"
			(at 0.064008 -5.517896 270)
			(unlocked yes)
			(layer "F.Fab")
			(hide yes)
			(effects
				(font
					(size 1.016 1.016)
					(thickness 0.1524)
				)
			)
		)
		(duplicate_pad_numbers_are_jumpers no)
		(fp_line
			(start -0.508 -0.9398)
			(end -0.508 0.9398)
			(stroke
				(width 0.1524)
				(type default)
			)
			(layer "F.SilkS")
		)
		(fp_line
			(start 0.508 -0.9398)
			(end -0.508 -0.9398)
			(stroke
				(width 0.1524)
				(type default)
			)
			(layer "F.SilkS")
		)
		(fp_rect
			(start -0.508 0.9398)
			(end 0.508 -0.9398)
			(stroke
				(width 0)
				(type default)
			)
			(fill no)
			(layer "F.CrtYd")
		)
		(fp_rect
			(start -0.508 0.9398)
			(end 0.508 -0.9398)
			(stroke
				(width 0)
				(type default)
			)
			(fill no)
			(layer "F.Fab")
		)
		(pad "1" smd custom
			(at 0 -0.4445 270)
			(size 0.1397 0.1397)
			(layers "F.Cu" "F.Mask" "F.Paste")
			(net "SW_HDD14_G")
			(options
				(clearance outline)
				(anchor circle)
			)
			(primitives
				(gr_poly
					(pts
						(arc
							(start -0.1778 -0.2794)
							(mid -0.249642 -0.249642)
							(end -0.2794 -0.1778)
						)
						(arc
							(start -0.2794 0.1778)
							(mid -0.249642 0.249642)
							(end -0.1778 0.2794)
						)
						(arc
							(start 0.1778 0.2794)
							(mid 0.249642 0.249642)
							(end 0.2794 0.1778)
						)
						(arc
							(start 0.2794 -0.1778)
							(mid 0.249642 -0.249642)
							(end 0.1778 -0.2794)
						)
					)
					(width 0)
					(fill yes)
				)
			)
		)
		(pad "2" smd custom
			(at 0 0.4445 270)
			(size 0.1397 0.1397)
			(layers "F.Cu" "F.Mask" "F.Paste")
			(net "SW_HDD14_R")
			(options
				(clearance outline)
				(anchor circle)
			)
			(primitives
				(gr_poly
					(pts
						(arc
							(start -0.1778 -0.2794)
							(mid -0.249642 -0.249642)
							(end -0.2794 -0.1778)
						)
						(arc
							(start -0.2794 0.1778)
							(mid -0.249642 0.249642)
							(end -0.1778 0.2794)
						)
						(arc
							(start 0.1778 0.2794)
							(mid 0.249642 0.249642)
							(end 0.2794 0.1778)
						)
						(arc
							(start 0.2794 -0.1778)
							(mid 0.249642 -0.249642)
							(end 0.1778 -0.2794)
						)
					)
					(width 0)
					(fill yes)
				)
			)
		)
	)
	(footprint ""
		(layer "F.Cu")
		(at 14.096746 -482.9937 -90)
		(property "Reference" "PC34"
			(at 0 0 270)
			(layer "F.SilkS")
			(hide yes)
			(effects
				(font
					(size 1.27 1.27)
				)
			)
		)
		(property "Value" "SCD1U25V2KX-GP"
			(at 1.1811 -2.7051 270)
			(unlocked yes)
			(layer "F.Fab")
			(hide yes)
			(effects
				(font
					(size 1.016 1.016)
					(thickness 0.1524)
				)
			)
		)
		(property "Device Type" "C402H22"
			(at 1.1811 -4.2291 270)
			(unlocked yes)
			(layer "F.Fab")
			(hide yes)
			(effects
				(font
					(size 1.016 1.016)
					(thickness 0.1524)
				)
			)
		)
		(duplicate_pad_numbers_are_jumpers no)
		(fp_rect
			(start -0.4318 0.9525)
			(end 0.4318 -0.9525)
			(stroke
				(width 0)
				(type default)
			)
			(fill no)
			(layer "F.CrtYd")
		)
		(fp_rect
			(start -0.4318 0.9525)
			(end 0.4318 -0.9525)
			(stroke
				(width 0)
				(type default)
			)
			(fill no)
			(layer "F.Fab")
		)
		(pad "1" smd custom
			(at 0 -0.4445 270)
			(size 0.1524 0.1524)
			(layers "F.Cu" "F.Mask" "F.Paste")
			(net "P5VC")
			(options
				(clearance outline)
				(anchor circle)
			)
			(primitives
				(gr_poly
					(pts
						(arc
							(start 0.3048 -0.2032)
							(mid 0.275042 -0.275042)
							(end 0.2032 -0.3048)
						)
						(arc
							(start -0.2032 -0.3048)
							(mid -0.275042 -0.275042)
							(end -0.3048 -0.2032)
						)
						(arc
							(start -0.3048 0.2032)
							(mid -0.275042 0.275042)
							(end -0.2032 0.3048)
						)
						(arc
							(start 0.2032 0.3048)
							(mid 0.275042 0.275042)
							(end 0.3048 0.2032)
						)
					)
					(width 0)
					(fill yes)
				)
			)
		)
		(pad "2" smd custom
			(at 0 0.4445 270)
			(size 0.1524 0.1524)
			(layers "F.Cu" "F.Mask" "F.Paste")
			(net "P5VC_LL_NET")
			(options
				(clearance outline)
				(anchor circle)
			)
			(primitives
				(gr_poly
					(pts
						(arc
							(start 0.3048 -0.2032)
							(mid 0.275042 -0.275042)
							(end 0.2032 -0.3048)
						)
						(arc
							(start -0.2032 -0.3048)
							(mid -0.275042 -0.275042)
							(end -0.3048 -0.2032)
						)
						(arc
							(start -0.3048 0.2032)
							(mid -0.275042 0.275042)
							(end -0.2032 0.3048)
						)
						(arc
							(start 0.2032 0.3048)
							(mid 0.275042 0.275042)
							(end 0.3048 0.2032)
						)
					)
					(width 0)
					(fill yes)
				)
			)
		)
	)
	(footprint ""
		(layer "F.Cu")
		(at 85.781134 -494.641886 -90)
		(property "Reference" "R444"
			(at 0 0 270)
			(layer "F.SilkS")
			(hide yes)
			(effects
				(font
					(size 1.27 1.27)
				)
			)
		)
		(property "Value" "4K7R2J-2-GP"
			(at 0.064008 -3.993896 270)
			(unlocked yes)
			(layer "F.Fab")
			(hide yes)
			(effects
				(font
					(size 1.016 1.016)
					(thickness 0.1524)
				)
			)
		)
		(property "Device Type" "R402H16"
			(at 0.064008 -5.517896 270)
			(unlocked yes)
			(layer "F.Fab")
			(hide yes)
			(effects
				(font
					(size 1.016 1.016)
					(thickness 0.1524)
				)
			)
		)
		(duplicate_pad_numbers_are_jumpers no)
		(fp_line
			(start -0.508 -0.9398)
			(end -0.508 0.9398)
			(stroke
				(width 0.1524)
				(type default)
			)
			(layer "F.SilkS")
		)
		(fp_line
			(start 0.508 -0.9398)
			(end -0.508 -0.9398)
			(stroke
				(width 0.1524)
				(type default)
			)
			(layer "F.SilkS")
		)
		(fp_rect
			(start -0.508 0.9398)
			(end 0.508 -0.9398)
			(stroke
				(width 0)
				(type default)
			)
			(fill no)
			(layer "F.CrtYd")
		)
		(fp_rect
			(start -0.508 0.9398)
			(end 0.508 -0.9398)
			(stroke
				(width 0)
				(type default)
			)
			(fill no)
			(layer "F.Fab")
		)
		(pad "1" smd custom
			(at 0 -0.4445 270)
			(size 0.1397 0.1397)
			(layers "F.Cu" "F.Mask" "F.Paste")
			(net "P3V3")
			(options
				(clearance outline)
				(anchor circle)
			)
			(primitives
				(gr_poly
					(pts
						(arc
							(start -0.1778 -0.2794)
							(mid -0.249642 -0.249642)
							(end -0.2794 -0.1778)
						)
						(arc
							(start -0.2794 0.1778)
							(mid -0.249642 0.249642)
							(end -0.1778 0.2794)
						)
						(arc
							(start 0.1778 0.2794)
							(mid 0.249642 0.249642)
							(end 0.2794 0.1778)
						)
						(arc
							(start 0.2794 -0.1778)
							(mid 0.249642 -0.249642)
							(end 0.1778 -0.2794)
						)
					)
					(width 0)
					(fill yes)
				)
			)
		)
		(pad "2" smd custom
			(at 0 0.4445 270)
			(size 0.1397 0.1397)
			(layers "F.Cu" "F.Mask" "F.Paste")
			(net "SAS_EXP_A_PWR5")
			(options
				(clearance outline)
				(anchor circle)
			)
			(primitives
				(gr_poly
					(pts
						(arc
							(start -0.1778 -0.2794)
							(mid -0.249642 -0.249642)
							(end -0.2794 -0.1778)
						)
						(arc
							(start -0.2794 0.1778)
							(mid -0.249642 0.249642)
							(end -0.1778 0.2794)
						)
						(arc
							(start 0.1778 0.2794)
							(mid 0.249642 0.249642)
							(end 0.2794 0.1778)
						)
						(arc
							(start 0.2794 -0.1778)
							(mid 0.249642 -0.249642)
							(end 0.1778 -0.2794)
						)
					)
					(width 0)
					(fill yes)
				)
			)
		)
	)
	(footprint ""
		(layer "F.Cu")
		(at 225.9838 -433.4256)
		(property "Reference" "PR55"
			(at 0 0 0)
			(layer "F.SilkS")
			(hide yes)
			(effects
				(font
					(size 1.27 1.27)
				)
			)
		)
		(property "Value" "100KR2F-L1-GP"
			(at 0.064008 -3.993896 0)
			(unlocked yes)
			(layer "F.Fab")
			(hide yes)
			(effects
				(font
					(size 1.016 1.016)
					(thickness 0.1524)
				)
			)
		)
		(property "Device Type" "R402H16"
			(at 0.064008 -5.517896 0)
			(unlocked yes)
			(layer "F.Fab")
			(hide yes)
			(effects
				(font
					(size 1.016 1.016)
					(thickness 0.1524)
				)
			)
		)
		(duplicate_pad_numbers_are_jumpers no)
		(fp_line
			(start -0.508 -0.9398)
			(end -0.508 0.9398)
			(stroke
				(width 0.1524)
				(type default)
			)
			(layer "F.SilkS")
		)
		(fp_line
			(start 0.508 -0.9398)
			(end -0.508 -0.9398)
			(stroke
				(width 0.1524)
				(type default)
			)
			(layer "F.SilkS")
		)
		(fp_rect
			(start -0.508 0.9398)
			(end 0.508 -0.9398)
			(stroke
				(width 0)
				(type default)
			)
			(fill no)
			(layer "F.CrtYd")
		)
		(fp_rect
			(start -0.508 0.9398)
			(end 0.508 -0.9398)
			(stroke
				(width 0)
				(type default)
			)
			(fill no)
			(layer "F.Fab")
		)
		(pad "1" smd custom
			(at 0 -0.4445)
			(size 0.1397 0.1397)
			(layers "F.Cu" "F.Mask" "F.Paste")
			(net "P3V3_FB_R")
			(options
				(clearance outline)
				(anchor circle)
			)
			(primitives
				(gr_poly
					(pts
						(arc
							(start -0.1778 -0.2794)
							(mid -0.249642 -0.249642)
							(end -0.2794 -0.1778)
						)
						(arc
							(start -0.2794 0.1778)
							(mid -0.249642 0.249642)
							(end -0.1778 0.2794)
						)
						(arc
							(start 0.1778 0.2794)
							(mid 0.249642 0.249642)
							(end 0.2794 0.1778)
						)
						(arc
							(start 0.2794 -0.1778)
							(mid 0.249642 -0.249642)
							(end 0.1778 -0.2794)
						)
					)
					(width 0)
					(fill yes)
				)
			)
		)
		(pad "2" smd custom
			(at 0 0.4445)
			(size 0.1397 0.1397)
			(layers "F.Cu" "F.Mask" "F.Paste")
			(net "P3V3_FB")
			(options
				(clearance outline)
				(anchor circle)
			)
			(primitives
				(gr_poly
					(pts
						(arc
							(start -0.1778 -0.2794)
							(mid -0.249642 -0.249642)
							(end -0.2794 -0.1778)
						)
						(arc
							(start -0.2794 0.1778)
							(mid -0.249642 0.249642)
							(end -0.1778 0.2794)
						)
						(arc
							(start 0.1778 0.2794)
							(mid 0.249642 0.249642)
							(end 0.2794 0.1778)
						)
						(arc
							(start 0.2794 -0.1778)
							(mid 0.249642 -0.249642)
							(end 0.1778 -0.2794)
						)
					)
					(width 0)
					(fill yes)
				)
			)
		)
	)
	(footprint ""
		(layer "F.Cu")
		(at 13.715746 -481.8507 -90)
		(property "Reference" "PR37"
			(at 0 0 270)
			(layer "F.SilkS")
			(hide yes)
			(effects
				(font
					(size 1.27 1.27)
				)
			)
		)
		(property "Value" "10R2F-L-GP"
			(at 0.064008 -3.993896 270)
			(unlocked yes)
			(layer "F.Fab")
			(hide yes)
			(effects
				(font
					(size 1.016 1.016)
					(thickness 0.1524)
				)
			)
		)
		(property "Device Type" "R402H14"
			(at 0.064008 -5.517896 270)
			(unlocked yes)
			(layer "F.Fab")
			(hide yes)
			(effects
				(font
					(size 1.016 1.016)
					(thickness 0.1524)
				)
			)
		)
		(duplicate_pad_numbers_are_jumpers no)
		(fp_line
			(start -0.508 -0.9398)
			(end -0.508 0.9398)
			(stroke
				(width 0.1524)
				(type default)
			)
			(layer "F.SilkS")
		)
		(fp_line
			(start 0.508 -0.9398)
			(end -0.508 -0.9398)
			(stroke
				(width 0.1524)
				(type default)
			)
			(layer "F.SilkS")
		)
		(fp_rect
			(start -0.508 0.9398)
			(end 0.508 -0.9398)
			(stroke
				(width 0)
				(type default)
			)
			(fill no)
			(layer "F.CrtYd")
		)
		(fp_rect
			(start -0.508 0.9398)
			(end 0.508 -0.9398)
			(stroke
				(width 0)
				(type default)
			)
			(fill no)
			(layer "F.Fab")
		)
		(pad "1" smd custom
			(at 0 -0.4445 270)
			(size 0.1397 0.1397)
			(layers "F.Cu" "F.Mask" "F.Paste")
			(net "P5VC")
			(options
				(clearance outline)
				(anchor circle)
			)
			(primitives
				(gr_poly
					(pts
						(arc
							(start -0.1778 -0.2794)
							(mid -0.249642 -0.249642)
							(end -0.2794 -0.1778)
						)
						(arc
							(start -0.2794 0.1778)
							(mid -0.249642 0.249642)
							(end -0.1778 0.2794)
						)
						(arc
							(start 0.1778 0.2794)
							(mid 0.249642 0.249642)
							(end 0.2794 0.1778)
						)
						(arc
							(start 0.2794 -0.1778)
							(mid 0.249642 -0.249642)
							(end 0.1778 -0.2794)
						)
					)
					(width 0)
					(fill yes)
				)
			)
		)
		(pad "2" smd custom
			(at 0 0.4445 270)
			(size 0.1397 0.1397)
			(layers "F.Cu" "F.Mask" "F.Paste")
			(net "P5VC_VFB_NET")
			(options
				(clearance outline)
				(anchor circle)
			)
			(primitives
				(gr_poly
					(pts
						(arc
							(start -0.1778 -0.2794)
							(mid -0.249642 -0.249642)
							(end -0.2794 -0.1778)
						)
						(arc
							(start -0.2794 0.1778)
							(mid -0.249642 0.249642)
							(end -0.1778 0.2794)
						)
						(arc
							(start 0.1778 0.2794)
							(mid 0.249642 0.249642)
							(end 0.2794 0.1778)
						)
						(arc
							(start 0.2794 -0.1778)
							(mid 0.249642 -0.249642)
							(end 0.1778 -0.2794)
						)
					)
					(width 0)
					(fill yes)
				)
			)
		)
	)
	(footprint ""
		(layer "F.Cu")
		(at 84.200492 -85.626956 -90)
		(property "Reference" "R458"
			(at 0 0 270)
			(layer "F.SilkS")
			(hide yes)
			(effects
				(font
					(size 1.27 1.27)
				)
			)
		)
		(property "Value" "4K7R2J-2-GP"
			(at 0.064008 -3.993896 270)
			(unlocked yes)
			(layer "F.Fab")
			(hide yes)
			(effects
				(font
					(size 1.016 1.016)
					(thickness 0.1524)
				)
			)
		)
		(property "Device Type" "R402H16"
			(at 0.064008 -5.517896 270)
			(unlocked yes)
			(layer "F.Fab")
			(hide yes)
			(effects
				(font
					(size 1.016 1.016)
					(thickness 0.1524)
				)
			)
		)
		(duplicate_pad_numbers_are_jumpers no)
		(fp_line
			(start -0.508 -0.9398)
			(end -0.508 0.9398)
			(stroke
				(width 0.1524)
				(type default)
			)
			(layer "F.SilkS")
		)
		(fp_line
			(start 0.508 -0.9398)
			(end -0.508 -0.9398)
			(stroke
				(width 0.1524)
				(type default)
			)
			(layer "F.SilkS")
		)
		(fp_rect
			(start -0.508 0.9398)
			(end 0.508 -0.9398)
			(stroke
				(width 0)
				(type default)
			)
			(fill no)
			(layer "F.CrtYd")
		)
		(fp_rect
			(start -0.508 0.9398)
			(end 0.508 -0.9398)
			(stroke
				(width 0)
				(type default)
			)
			(fill no)
			(layer "F.Fab")
		)
		(pad "1" smd custom
			(at 0 -0.4445 270)
			(size 0.1397 0.1397)
			(layers "F.Cu" "F.Mask" "F.Paste")
			(net "P3V3")
			(options
				(clearance outline)
				(anchor circle)
			)
			(primitives
				(gr_poly
					(pts
						(arc
							(start -0.1778 -0.2794)
							(mid -0.249642 -0.249642)
							(end -0.2794 -0.1778)
						)
						(arc
							(start -0.2794 0.1778)
							(mid -0.249642 0.249642)
							(end -0.1778 0.2794)
						)
						(arc
							(start 0.1778 0.2794)
							(mid 0.249642 0.249642)
							(end 0.2794 0.1778)
						)
						(arc
							(start 0.2794 -0.1778)
							(mid 0.249642 -0.249642)
							(end 0.1778 -0.2794)
						)
					)
					(width 0)
					(fill yes)
				)
			)
		)
		(pad "2" smd custom
			(at 0 0.4445 270)
			(size 0.1397 0.1397)
			(layers "F.Cu" "F.Mask" "F.Paste")
			(net "SAS_EXP_A_PWR9")
			(options
				(clearance outline)
				(anchor circle)
			)
			(primitives
				(gr_poly
					(pts
						(arc
							(start -0.1778 -0.2794)
							(mid -0.249642 -0.249642)
							(end -0.2794 -0.1778)
						)
						(arc
							(start -0.2794 0.1778)
							(mid -0.249642 0.249642)
							(end -0.1778 0.2794)
						)
						(arc
							(start 0.1778 0.2794)
							(mid 0.249642 0.249642)
							(end 0.2794 0.1778)
						)
						(arc
							(start 0.2794 -0.1778)
							(mid 0.249642 -0.249642)
							(end 0.1778 -0.2794)
						)
					)
					(width 0)
					(fill yes)
				)
			)
		)
	)
	(footprint ""
		(layer "F.Cu")
		(at 230.335582 -245.463568 90)
		(property "Reference" "R132"
			(at 0 0 90)
			(layer "F.SilkS")
			(hide yes)
			(effects
				(font
					(size 1.27 1.27)
				)
			)
		)
		(property "Value" "0R2J-2-GP"
			(at 0.064008 -3.993896 90)
			(unlocked yes)
			(layer "F.Fab")
			(hide yes)
			(effects
				(font
					(size 1.016 1.016)
					(thickness 0.1524)
				)
			)
		)
		(property "Device Type" "R402H16"
			(at 0.064008 -5.517896 90)
			(unlocked yes)
			(layer "F.Fab")
			(hide yes)
			(effects
				(font
					(size 1.016 1.016)
					(thickness 0.1524)
				)
			)
		)
		(duplicate_pad_numbers_are_jumpers no)
		(fp_line
			(start 0.508 -0.9398)
			(end -0.508 -0.9398)
			(stroke
				(width 0.1524)
				(type default)
			)
			(layer "F.SilkS")
		)
		(fp_line
			(start -0.508 -0.9398)
			(end -0.508 0.9398)
			(stroke
				(width 0.1524)
				(type default)
			)
			(layer "F.SilkS")
		)
		(fp_rect
			(start -0.508 0.9398)
			(end 0.508 -0.9398)
			(stroke
				(width 0)
				(type default)
			)
			(fill no)
			(layer "F.CrtYd")
		)
		(fp_rect
			(start -0.508 0.9398)
			(end 0.508 -0.9398)
			(stroke
				(width 0)
				(type default)
			)
			(fill no)
			(layer "F.Fab")
		)
		(pad "1" smd custom
			(at 0 -0.4445 90)
			(size 0.1397 0.1397)
			(layers "F.Cu" "F.Mask" "F.Paste")
			(net "FLT_NET_HDD2")
			(options
				(clearance outline)
				(anchor circle)
			)
			(primitives
				(gr_poly
					(pts
						(arc
							(start -0.1778 -0.2794)
							(mid -0.249642 -0.249642)
							(end -0.2794 -0.1778)
						)
						(arc
							(start -0.2794 0.1778)
							(mid -0.249642 0.249642)
							(end -0.1778 0.2794)
						)
						(arc
							(start 0.1778 0.2794)
							(mid 0.249642 0.249642)
							(end 0.2794 0.1778)
						)
						(arc
							(start 0.2794 -0.1778)
							(mid 0.249642 -0.249642)
							(end 0.1778 -0.2794)
						)
					)
					(width 0)
					(fill yes)
				)
			)
		)
		(pad "2" smd custom
			(at 0 0.4445 90)
			(size 0.1397 0.1397)
			(layers "F.Cu" "F.Mask" "F.Paste")
			(net "FLT_HDD2_DRIVE")
			(options
				(clearance outline)
				(anchor circle)
			)
			(primitives
				(gr_poly
					(pts
						(arc
							(start -0.1778 -0.2794)
							(mid -0.249642 -0.249642)
							(end -0.2794 -0.1778)
						)
						(arc
							(start -0.2794 0.1778)
							(mid -0.249642 0.249642)
							(end -0.1778 0.2794)
						)
						(arc
							(start 0.1778 0.2794)
							(mid 0.249642 0.249642)
							(end 0.2794 0.1778)
						)
						(arc
							(start 0.2794 -0.1778)
							(mid 0.249642 -0.249642)
							(end 0.1778 -0.2794)
						)
					)
					(width 0)
					(fill yes)
				)
			)
		)
	)
	(footprint ""
		(layer "F.Cu")
		(at 202.945746 -85.3567 -90)
		(property "Reference" "R438"
			(at 0 0 270)
			(layer "F.SilkS")
			(hide yes)
			(effects
				(font
					(size 1.27 1.27)
				)
			)
		)
		(property "Value" "4K7R2J-2-GP"
			(at 0.064008 -3.993896 270)
			(unlocked yes)
			(layer "F.Fab")
			(hide yes)
			(effects
				(font
					(size 1.016 1.016)
					(thickness 0.1524)
				)
			)
		)
		(property "Device Type" "R402H16"
			(at 0.064008 -5.517896 270)
			(unlocked yes)
			(layer "F.Fab")
			(hide yes)
			(effects
				(font
					(size 1.016 1.016)
					(thickness 0.1524)
				)
			)
		)
		(duplicate_pad_numbers_are_jumpers no)
		(fp_line
			(start -0.508 -0.9398)
			(end -0.508 0.9398)
			(stroke
				(width 0.1524)
				(type default)
			)
			(layer "F.SilkS")
		)
		(fp_line
			(start 0.508 -0.9398)
			(end -0.508 -0.9398)
			(stroke
				(width 0.1524)
				(type default)
			)
			(layer "F.SilkS")
		)
		(fp_rect
			(start -0.508 0.9398)
			(end 0.508 -0.9398)
			(stroke
				(width 0)
				(type default)
			)
			(fill no)
			(layer "F.CrtYd")
		)
		(fp_rect
			(start -0.508 0.9398)
			(end 0.508 -0.9398)
			(stroke
				(width 0)
				(type default)
			)
			(fill no)
			(layer "F.Fab")
		)
		(pad "1" smd custom
			(at 0 -0.4445 270)
			(size 0.1397 0.1397)
			(layers "F.Cu" "F.Mask" "F.Paste")
			(net "P3V3")
			(options
				(clearance outline)
				(anchor circle)
			)
			(primitives
				(gr_poly
					(pts
						(arc
							(start -0.1778 -0.2794)
							(mid -0.249642 -0.249642)
							(end -0.2794 -0.1778)
						)
						(arc
							(start -0.2794 0.1778)
							(mid -0.249642 0.249642)
							(end -0.1778 0.2794)
						)
						(arc
							(start 0.1778 0.2794)
							(mid 0.249642 0.249642)
							(end 0.2794 0.1778)
						)
						(arc
							(start 0.2794 -0.1778)
							(mid 0.249642 -0.249642)
							(end 0.1778 -0.2794)
						)
					)
					(width 0)
					(fill yes)
				)
			)
		)
		(pad "2" smd custom
			(at 0 0.4445 270)
			(size 0.1397 0.1397)
			(layers "F.Cu" "F.Mask" "F.Paste")
			(net "SAS2X28_A_HDD4_FLT")
			(options
				(clearance outline)
				(anchor circle)
			)
			(primitives
				(gr_poly
					(pts
						(arc
							(start -0.1778 -0.2794)
							(mid -0.249642 -0.249642)
							(end -0.2794 -0.1778)
						)
						(arc
							(start -0.2794 0.1778)
							(mid -0.249642 0.249642)
							(end -0.1778 0.2794)
						)
						(arc
							(start 0.1778 0.2794)
							(mid 0.249642 0.249642)
							(end 0.2794 0.1778)
						)
						(arc
							(start 0.2794 -0.1778)
							(mid 0.249642 -0.249642)
							(end 0.1778 -0.2794)
						)
					)
					(width 0)
					(fill yes)
				)
			)
		)
	)
	(footprint ""
		(layer "F.Cu")
		(at 5.84962 -489.442252)
		(property "Reference" "PR48"
			(at 0 0 0)
			(layer "F.SilkS")
			(hide yes)
			(effects
				(font
					(size 1.27 1.27)
				)
			)
		)
		(property "Value" "0R2J-2-GP"
			(at 0.064008 -3.993896 0)
			(unlocked yes)
			(layer "F.Fab")
			(hide yes)
			(effects
				(font
					(size 1.016 1.016)
					(thickness 0.1524)
				)
			)
		)
		(property "Device Type" "R402H16"
			(at 0.064008 -5.517896 0)
			(unlocked yes)
			(layer "F.Fab")
			(hide yes)
			(effects
				(font
					(size 1.016 1.016)
					(thickness 0.1524)
				)
			)
		)
		(duplicate_pad_numbers_are_jumpers no)
		(fp_line
			(start -0.508 -0.9398)
			(end -0.508 0.9398)
			(stroke
				(width 0.1524)
				(type default)
			)
			(layer "F.SilkS")
		)
		(fp_line
			(start 0.508 -0.9398)
			(end -0.508 -0.9398)
			(stroke
				(width 0.1524)
				(type default)
			)
			(layer "F.SilkS")
		)
		(fp_rect
			(start -0.508 0.9398)
			(end 0.508 -0.9398)
			(stroke
				(width 0)
				(type default)
			)
			(fill no)
			(layer "F.CrtYd")
		)
		(fp_rect
			(start -0.508 0.9398)
			(end 0.508 -0.9398)
			(stroke
				(width 0)
				(type default)
			)
			(fill no)
			(layer "F.Fab")
		)
		(pad "1" smd custom
			(at 0 -0.4445)
			(size 0.1397 0.1397)
			(layers "F.Cu" "F.Mask" "F.Paste")
			(net "P5VC_ROVP")
			(options
				(clearance outline)
				(anchor circle)
			)
			(primitives
				(gr_poly
					(pts
						(arc
							(start -0.1778 -0.2794)
							(mid -0.249642 -0.249642)
							(end -0.2794 -0.1778)
						)
						(arc
							(start -0.2794 0.1778)
							(mid -0.249642 0.249642)
							(end -0.1778 0.2794)
						)
						(arc
							(start 0.1778 0.2794)
							(mid 0.249642 0.249642)
							(end 0.2794 0.1778)
						)
						(arc
							(start 0.2794 -0.1778)
							(mid 0.249642 -0.249642)
							(end 0.1778 -0.2794)
						)
					)
					(width 0)
					(fill yes)
				)
			)
		)
		(pad "2" smd custom
			(at 0 0.4445)
			(size 0.1397 0.1397)
			(layers "F.Cu" "F.Mask" "F.Paste")
			(net "P5VC_AGND")
			(options
				(clearance outline)
				(anchor circle)
			)
			(primitives
				(gr_poly
					(pts
						(arc
							(start -0.1778 -0.2794)
							(mid -0.249642 -0.249642)
							(end -0.2794 -0.1778)
						)
						(arc
							(start -0.2794 0.1778)
							(mid -0.249642 0.249642)
							(end -0.1778 0.2794)
						)
						(arc
							(start 0.1778 0.2794)
							(mid 0.249642 0.249642)
							(end 0.2794 0.1778)
						)
						(arc
							(start 0.2794 -0.1778)
							(mid 0.249642 -0.249642)
							(end 0.1778 -0.2794)
						)
					)
					(width 0)
					(fill yes)
				)
			)
		)
	)
	(footprint ""
		(layer "F.Cu")
		(at 46.017688 -23.005288 -90)
		(property "Reference" "PR31"
			(at 0 0 270)
			(layer "F.SilkS")
			(hide yes)
			(effects
				(font
					(size 1.27 1.27)
				)
			)
		)
		(property "Value" "76K8R2F-GP"
			(at 0.064008 -3.993896 270)
			(unlocked yes)
			(layer "F.Fab")
			(hide yes)
			(effects
				(font
					(size 1.016 1.016)
					(thickness 0.1524)
				)
			)
		)
		(property "Device Type" "R402H16"
			(at 0.064008 -5.517896 270)
			(unlocked yes)
			(layer "F.Fab")
			(hide yes)
			(effects
				(font
					(size 1.016 1.016)
					(thickness 0.1524)
				)
			)
		)
		(duplicate_pad_numbers_are_jumpers no)
		(fp_line
			(start -0.508 -0.9398)
			(end -0.508 0.9398)
			(stroke
				(width 0.1524)
				(type default)
			)
			(layer "F.SilkS")
		)
		(fp_line
			(start 0.508 -0.9398)
			(end -0.508 -0.9398)
			(stroke
				(width 0.1524)
				(type default)
			)
			(layer "F.SilkS")
		)
		(fp_rect
			(start -0.508 0.9398)
			(end 0.508 -0.9398)
			(stroke
				(width 0)
				(type default)
			)
			(fill no)
			(layer "F.CrtYd")
		)
		(fp_rect
			(start -0.508 0.9398)
			(end 0.508 -0.9398)
			(stroke
				(width 0)
				(type default)
			)
			(fill no)
			(layer "F.Fab")
		)
		(pad "1" smd custom
			(at 0 -0.4445 270)
			(size 0.1397 0.1397)
			(layers "F.Cu" "F.Mask" "F.Paste")
			(net "P5VB_ROVP")
			(options
				(clearance outline)
				(anchor circle)
			)
			(primitives
				(gr_poly
					(pts
						(arc
							(start -0.1778 -0.2794)
							(mid -0.249642 -0.249642)
							(end -0.2794 -0.1778)
						)
						(arc
							(start -0.2794 0.1778)
							(mid -0.249642 0.249642)
							(end -0.1778 0.2794)
						)
						(arc
							(start 0.1778 0.2794)
							(mid 0.249642 0.249642)
							(end 0.2794 0.1778)
						)
						(arc
							(start 0.2794 -0.1778)
							(mid 0.249642 -0.249642)
							(end 0.1778 -0.2794)
						)
					)
					(width 0)
					(fill yes)
				)
			)
		)
		(pad "2" smd custom
			(at 0 0.4445 270)
			(size 0.1397 0.1397)
			(layers "F.Cu" "F.Mask" "F.Paste")
			(net "P5VB")
			(options
				(clearance outline)
				(anchor circle)
			)
			(primitives
				(gr_poly
					(pts
						(arc
							(start -0.1778 -0.2794)
							(mid -0.249642 -0.249642)
							(end -0.2794 -0.1778)
						)
						(arc
							(start -0.2794 0.1778)
							(mid -0.249642 0.249642)
							(end -0.1778 0.2794)
						)
						(arc
							(start 0.1778 0.2794)
							(mid 0.249642 0.249642)
							(end 0.2794 0.1778)
						)
						(arc
							(start 0.2794 -0.1778)
							(mid 0.249642 -0.249642)
							(end 0.1778 -0.2794)
						)
					)
					(width 0)
					(fill yes)
				)
			)
		)
	)
	(footprint ""
		(layer "F.Cu")
		(at 196.088 -393.065 180)
		(property "Reference" "R409"
			(at 0 0 180)
			(layer "F.SilkS")
			(hide yes)
			(effects
				(font
					(size 1.27 1.27)
				)
			)
		)
		(property "Value" "0R2J-2-GP"
			(at 0.064008 -3.993896 180)
			(unlocked yes)
			(layer "F.Fab")
			(hide yes)
			(effects
				(font
					(size 1.016 1.016)
					(thickness 0.1524)
				)
			)
		)
		(property "Device Type" "R402H16"
			(at 0.064008 -5.517896 180)
			(unlocked yes)
			(layer "F.Fab")
			(hide yes)
			(effects
				(font
					(size 1.016 1.016)
					(thickness 0.1524)
				)
			)
		)
		(duplicate_pad_numbers_are_jumpers no)
		(fp_line
			(start 0.508 -0.9398)
			(end -0.508 -0.9398)
			(stroke
				(width 0.1524)
				(type default)
			)
			(layer "F.SilkS")
		)
		(fp_line
			(start -0.508 -0.9398)
			(end -0.508 0.9398)
			(stroke
				(width 0.1524)
				(type default)
			)
			(layer "F.SilkS")
		)
		(fp_rect
			(start -0.508 0.9398)
			(end 0.508 -0.9398)
			(stroke
				(width 0)
				(type default)
			)
			(fill no)
			(layer "F.CrtYd")
		)
		(fp_rect
			(start -0.508 0.9398)
			(end 0.508 -0.9398)
			(stroke
				(width 0)
				(type default)
			)
			(fill no)
			(layer "F.Fab")
		)
		(pad "1" smd custom
			(at 0 -0.4445 180)
			(size 0.1397 0.1397)
			(layers "F.Cu" "F.Mask" "F.Paste")
			(net "SW_HDD1_G")
			(options
				(clearance outline)
				(anchor circle)
			)
			(primitives
				(gr_poly
					(pts
						(arc
							(start -0.1778 -0.2794)
							(mid -0.249642 -0.249642)
							(end -0.2794 -0.1778)
						)
						(arc
							(start -0.2794 0.1778)
							(mid -0.249642 0.249642)
							(end -0.1778 0.2794)
						)
						(arc
							(start 0.1778 0.2794)
							(mid 0.249642 0.249642)
							(end 0.2794 0.1778)
						)
						(arc
							(start 0.2794 -0.1778)
							(mid 0.249642 -0.249642)
							(end 0.1778 -0.2794)
						)
					)
					(width 0)
					(fill yes)
				)
			)
		)
		(pad "2" smd custom
			(at 0 0.4445 180)
			(size 0.1397 0.1397)
			(layers "F.Cu" "F.Mask" "F.Paste")
			(net "SW_HDD1_R")
			(options
				(clearance outline)
				(anchor circle)
			)
			(primitives
				(gr_poly
					(pts
						(arc
							(start -0.1778 -0.2794)
							(mid -0.249642 -0.249642)
							(end -0.2794 -0.1778)
						)
						(arc
							(start -0.2794 0.1778)
							(mid -0.249642 0.249642)
							(end -0.1778 0.2794)
						)
						(arc
							(start 0.1778 0.2794)
							(mid 0.249642 0.249642)
							(end 0.2794 0.1778)
						)
						(arc
							(start 0.2794 -0.1778)
							(mid 0.249642 -0.249642)
							(end 0.1778 -0.2794)
						)
					)
					(width 0)
					(fill yes)
				)
			)
		)
	)
	(footprint ""
		(layer "F.Cu")
		(at 20.574 -257.302 90)
		(property "Reference" "R271"
			(at 0 0 90)
			(layer "F.SilkS")
			(hide yes)
			(effects
				(font
					(size 1.27 1.27)
				)
			)
		)
		(property "Value" "330R2F-GP"
			(at 0.064008 -3.993896 90)
			(unlocked yes)
			(layer "F.Fab")
			(hide yes)
			(effects
				(font
					(size 1.016 1.016)
					(thickness 0.1524)
				)
			)
		)
		(property "Device Type" "R402H16"
			(at 0.064008 -5.517896 90)
			(unlocked yes)
			(layer "F.Fab")
			(hide yes)
			(effects
				(font
					(size 1.016 1.016)
					(thickness 0.1524)
				)
			)
		)
		(duplicate_pad_numbers_are_jumpers no)
		(fp_line
			(start 0.508 -0.9398)
			(end -0.508 -0.9398)
			(stroke
				(width 0.1524)
				(type default)
			)
			(layer "F.SilkS")
		)
		(fp_line
			(start -0.508 -0.9398)
			(end -0.508 0.9398)
			(stroke
				(width 0.1524)
				(type default)
			)
			(layer "F.SilkS")
		)
		(fp_rect
			(start -0.508 0.9398)
			(end 0.508 -0.9398)
			(stroke
				(width 0)
				(type default)
			)
			(fill no)
			(layer "F.CrtYd")
		)
		(fp_rect
			(start -0.508 0.9398)
			(end 0.508 -0.9398)
			(stroke
				(width 0)
				(type default)
			)
			(fill no)
			(layer "F.Fab")
		)
		(pad "1" smd custom
			(at 0 -0.4445 90)
			(size 0.1397 0.1397)
			(layers "F.Cu" "F.Mask" "F.Paste")
			(net "P3V3_HDD12_LED")
			(options
				(clearance outline)
				(anchor circle)
			)
			(primitives
				(gr_poly
					(pts
						(arc
							(start -0.1778 -0.2794)
							(mid -0.249642 -0.249642)
							(end -0.2794 -0.1778)
						)
						(arc
							(start -0.2794 0.1778)
							(mid -0.249642 0.249642)
							(end -0.1778 0.2794)
						)
						(arc
							(start 0.1778 0.2794)
							(mid 0.249642 0.249642)
							(end 0.2794 0.1778)
						)
						(arc
							(start 0.2794 -0.1778)
							(mid 0.249642 -0.249642)
							(end 0.1778 -0.2794)
						)
					)
					(width 0)
					(fill yes)
				)
			)
		)
		(pad "2" smd custom
			(at 0 0.4445 90)
			(size 0.1397 0.1397)
			(layers "F.Cu" "F.Mask" "F.Paste")
			(net "FLT_HDD12")
			(options
				(clearance outline)
				(anchor circle)
			)
			(primitives
				(gr_poly
					(pts
						(arc
							(start -0.1778 -0.2794)
							(mid -0.249642 -0.249642)
							(end -0.2794 -0.1778)
						)
						(arc
							(start -0.2794 0.1778)
							(mid -0.249642 0.249642)
							(end -0.1778 0.2794)
						)
						(arc
							(start 0.1778 0.2794)
							(mid 0.249642 0.249642)
							(end 0.2794 0.1778)
						)
						(arc
							(start 0.2794 -0.1778)
							(mid 0.249642 -0.249642)
							(end 0.1778 -0.2794)
						)
					)
					(width 0)
					(fill yes)
				)
			)
		)
	)
	(footprint ""
		(layer "F.Cu")
		(at 35.6616 -339.2932 -90)
		(property "Reference" "R399"
			(at 0 0 270)
			(layer "F.SilkS")
			(hide yes)
			(effects
				(font
					(size 1.27 1.27)
				)
			)
		)
		(property "Value" "10KR2F-2-GP"
			(at 0.064008 -3.993896 270)
			(unlocked yes)
			(layer "F.Fab")
			(hide yes)
			(effects
				(font
					(size 1.016 1.016)
					(thickness 0.1524)
				)
			)
		)
		(property "Device Type" "R402H16"
			(at 0.064008 -5.517896 270)
			(unlocked yes)
			(layer "F.Fab")
			(hide yes)
			(effects
				(font
					(size 1.016 1.016)
					(thickness 0.1524)
				)
			)
		)
		(duplicate_pad_numbers_are_jumpers no)
		(fp_line
			(start -0.508 -0.9398)
			(end -0.508 0.9398)
			(stroke
				(width 0.1524)
				(type default)
			)
			(layer "F.SilkS")
		)
		(fp_line
			(start 0.508 -0.9398)
			(end -0.508 -0.9398)
			(stroke
				(width 0.1524)
				(type default)
			)
			(layer "F.SilkS")
		)
		(fp_rect
			(start -0.508 0.9398)
			(end 0.508 -0.9398)
			(stroke
				(width 0)
				(type default)
			)
			(fill no)
			(layer "F.CrtYd")
		)
		(fp_rect
			(start -0.508 0.9398)
			(end 0.508 -0.9398)
			(stroke
				(width 0)
				(type default)
			)
			(fill no)
			(layer "F.Fab")
		)
		(pad "1" smd custom
			(at 0 -0.4445 270)
			(size 0.1397 0.1397)
			(layers "F.Cu" "F.Mask" "F.Paste")
			(net "P12V")
			(options
				(clearance outline)
				(anchor circle)
			)
			(primitives
				(gr_poly
					(pts
						(arc
							(start -0.1778 -0.2794)
							(mid -0.249642 -0.249642)
							(end -0.2794 -0.1778)
						)
						(arc
							(start -0.2794 0.1778)
							(mid -0.249642 0.249642)
							(end -0.1778 0.2794)
						)
						(arc
							(start 0.1778 0.2794)
							(mid 0.249642 0.249642)
							(end 0.2794 0.1778)
						)
						(arc
							(start 0.2794 -0.1778)
							(mid 0.249642 -0.249642)
							(end 0.1778 -0.2794)
						)
					)
					(width 0)
					(fill yes)
				)
			)
		)
		(pad "2" smd custom
			(at 0 0.4445 270)
			(size 0.1397 0.1397)
			(layers "F.Cu" "F.Mask" "F.Paste")
			(net "HDD11_LED_G")
			(options
				(clearance outline)
				(anchor circle)
			)
			(primitives
				(gr_poly
					(pts
						(arc
							(start -0.1778 -0.2794)
							(mid -0.249642 -0.249642)
							(end -0.2794 -0.1778)
						)
						(arc
							(start -0.2794 0.1778)
							(mid -0.249642 0.249642)
							(end -0.1778 0.2794)
						)
						(arc
							(start 0.1778 0.2794)
							(mid 0.249642 0.249642)
							(end 0.2794 0.1778)
						)
						(arc
							(start 0.2794 -0.1778)
							(mid 0.249642 -0.249642)
							(end 0.1778 -0.2794)
						)
					)
					(width 0)
					(fill yes)
				)
			)
		)
	)
	(footprint ""
		(layer "F.Cu")
		(at 230.364284 -142.972028 90)
		(property "Reference" "R146"
			(at 0 0 90)
			(layer "F.SilkS")
			(hide yes)
			(effects
				(font
					(size 1.27 1.27)
				)
			)
		)
		(property "Value" "0R2J-2-GP"
			(at 0.064008 -3.993896 90)
			(unlocked yes)
			(layer "F.Fab")
			(hide yes)
			(effects
				(font
					(size 1.016 1.016)
					(thickness 0.1524)
				)
			)
		)
		(property "Device Type" "R402H16"
			(at 0.064008 -5.517896 90)
			(unlocked yes)
			(layer "F.Fab")
			(hide yes)
			(effects
				(font
					(size 1.016 1.016)
					(thickness 0.1524)
				)
			)
		)
		(duplicate_pad_numbers_are_jumpers no)
		(fp_line
			(start 0.508 -0.9398)
			(end -0.508 -0.9398)
			(stroke
				(width 0.1524)
				(type default)
			)
			(layer "F.SilkS")
		)
		(fp_line
			(start -0.508 -0.9398)
			(end -0.508 0.9398)
			(stroke
				(width 0.1524)
				(type default)
			)
			(layer "F.SilkS")
		)
		(fp_rect
			(start -0.508 0.9398)
			(end 0.508 -0.9398)
			(stroke
				(width 0)
				(type default)
			)
			(fill no)
			(layer "F.CrtYd")
		)
		(fp_rect
			(start -0.508 0.9398)
			(end 0.508 -0.9398)
			(stroke
				(width 0)
				(type default)
			)
			(fill no)
			(layer "F.Fab")
		)
		(pad "1" smd custom
			(at 0 -0.4445 90)
			(size 0.1397 0.1397)
			(layers "F.Cu" "F.Mask" "F.Paste")
			(net "FLT_NET_HDD3")
			(options
				(clearance outline)
				(anchor circle)
			)
			(primitives
				(gr_poly
					(pts
						(arc
							(start -0.1778 -0.2794)
							(mid -0.249642 -0.249642)
							(end -0.2794 -0.1778)
						)
						(arc
							(start -0.2794 0.1778)
							(mid -0.249642 0.249642)
							(end -0.1778 0.2794)
						)
						(arc
							(start 0.1778 0.2794)
							(mid 0.249642 0.249642)
							(end 0.2794 0.1778)
						)
						(arc
							(start 0.2794 -0.1778)
							(mid 0.249642 -0.249642)
							(end 0.1778 -0.2794)
						)
					)
					(width 0)
					(fill yes)
				)
			)
		)
		(pad "2" smd custom
			(at 0 0.4445 90)
			(size 0.1397 0.1397)
			(layers "F.Cu" "F.Mask" "F.Paste")
			(net "FLT_HDD3_DRIVE")
			(options
				(clearance outline)
				(anchor circle)
			)
			(primitives
				(gr_poly
					(pts
						(arc
							(start -0.1778 -0.2794)
							(mid -0.249642 -0.249642)
							(end -0.2794 -0.1778)
						)
						(arc
							(start -0.2794 0.1778)
							(mid -0.249642 0.249642)
							(end -0.1778 0.2794)
						)
						(arc
							(start 0.1778 0.2794)
							(mid 0.249642 0.249642)
							(end 0.2794 0.1778)
						)
						(arc
							(start 0.2794 -0.1778)
							(mid 0.249642 -0.249642)
							(end 0.1778 -0.2794)
						)
					)
					(width 0)
					(fill yes)
				)
			)
		)
	)
	(footprint ""
		(layer "F.Cu")
		(at 202.564746 -186.9567 -90)
		(property "Reference" "R434"
			(at 0 0 270)
			(layer "F.SilkS")
			(hide yes)
			(effects
				(font
					(size 1.27 1.27)
				)
			)
		)
		(property "Value" "4K7R2J-2-GP"
			(at 0.064008 -3.993896 270)
			(unlocked yes)
			(layer "F.Fab")
			(hide yes)
			(effects
				(font
					(size 1.016 1.016)
					(thickness 0.1524)
				)
			)
		)
		(property "Device Type" "R402H16"
			(at 0.064008 -5.517896 270)
			(unlocked yes)
			(layer "F.Fab")
			(hide yes)
			(effects
				(font
					(size 1.016 1.016)
					(thickness 0.1524)
				)
			)
		)
		(duplicate_pad_numbers_are_jumpers no)
		(fp_line
			(start -0.508 -0.9398)
			(end -0.508 0.9398)
			(stroke
				(width 0.1524)
				(type default)
			)
			(layer "F.SilkS")
		)
		(fp_line
			(start 0.508 -0.9398)
			(end -0.508 -0.9398)
			(stroke
				(width 0.1524)
				(type default)
			)
			(layer "F.SilkS")
		)
		(fp_rect
			(start -0.508 0.9398)
			(end 0.508 -0.9398)
			(stroke
				(width 0)
				(type default)
			)
			(fill no)
			(layer "F.CrtYd")
		)
		(fp_rect
			(start -0.508 0.9398)
			(end 0.508 -0.9398)
			(stroke
				(width 0)
				(type default)
			)
			(fill no)
			(layer "F.Fab")
		)
		(pad "1" smd custom
			(at 0 -0.4445 270)
			(size 0.1397 0.1397)
			(layers "F.Cu" "F.Mask" "F.Paste")
			(net "P3V3")
			(options
				(clearance outline)
				(anchor circle)
			)
			(primitives
				(gr_poly
					(pts
						(arc
							(start -0.1778 -0.2794)
							(mid -0.249642 -0.249642)
							(end -0.2794 -0.1778)
						)
						(arc
							(start -0.2794 0.1778)
							(mid -0.249642 0.249642)
							(end -0.1778 0.2794)
						)
						(arc
							(start 0.1778 0.2794)
							(mid 0.249642 0.249642)
							(end 0.2794 0.1778)
						)
						(arc
							(start 0.2794 -0.1778)
							(mid 0.249642 -0.249642)
							(end 0.1778 -0.2794)
						)
					)
					(width 0)
					(fill yes)
				)
			)
		)
		(pad "2" smd custom
			(at 0 0.4445 270)
			(size 0.1397 0.1397)
			(layers "F.Cu" "F.Mask" "F.Paste")
			(net "SAS2X28_A_HDD3_FLT")
			(options
				(clearance outline)
				(anchor circle)
			)
			(primitives
				(gr_poly
					(pts
						(arc
							(start -0.1778 -0.2794)
							(mid -0.249642 -0.249642)
							(end -0.2794 -0.1778)
						)
						(arc
							(start -0.2794 0.1778)
							(mid -0.249642 0.249642)
							(end -0.1778 0.2794)
						)
						(arc
							(start 0.1778 0.2794)
							(mid 0.249642 0.249642)
							(end 0.2794 0.1778)
						)
						(arc
							(start 0.2794 -0.1778)
							(mid 0.249642 -0.249642)
							(end 0.1778 -0.2794)
						)
					)
					(width 0)
					(fill yes)
				)
			)
		)
	)
	(footprint ""
		(layer "F.Cu")
		(at 176.669446 -463.711036 90)
		(property "Reference" "R382"
			(at 0 0 90)
			(layer "F.SilkS")
			(hide yes)
			(effects
				(font
					(size 1.27 1.27)
				)
			)
		)
		(property "Value" "0R2J-2-GP"
			(at 0.064008 -3.993896 90)
			(unlocked yes)
			(layer "F.Fab")
			(hide yes)
			(effects
				(font
					(size 1.016 1.016)
					(thickness 0.1524)
				)
			)
		)
		(property "Device Type" "R402H16"
			(at 0.064008 -5.517896 90)
			(unlocked yes)
			(layer "F.Fab")
			(hide yes)
			(effects
				(font
					(size 1.016 1.016)
					(thickness 0.1524)
				)
			)
		)
		(duplicate_pad_numbers_are_jumpers no)
		(fp_line
			(start 0.508 -0.9398)
			(end -0.508 -0.9398)
			(stroke
				(width 0.1524)
				(type default)
			)
			(layer "F.SilkS")
		)
		(fp_line
			(start -0.508 -0.9398)
			(end -0.508 0.9398)
			(stroke
				(width 0.1524)
				(type default)
			)
			(layer "F.SilkS")
		)
		(fp_rect
			(start -0.508 0.9398)
			(end 0.508 -0.9398)
			(stroke
				(width 0)
				(type default)
			)
			(fill no)
			(layer "F.CrtYd")
		)
		(fp_rect
			(start -0.508 0.9398)
			(end 0.508 -0.9398)
			(stroke
				(width 0)
				(type default)
			)
			(fill no)
			(layer "F.Fab")
		)
		(pad "1" smd custom
			(at 0 -0.4445 90)
			(size 0.1397 0.1397)
			(layers "F.Cu" "F.Mask" "F.Paste")
			(net "VOL_SEN_SDA")
			(options
				(clearance outline)
				(anchor circle)
			)
			(primitives
				(gr_poly
					(pts
						(arc
							(start -0.1778 -0.2794)
							(mid -0.249642 -0.249642)
							(end -0.2794 -0.1778)
						)
						(arc
							(start -0.2794 0.1778)
							(mid -0.249642 0.249642)
							(end -0.1778 0.2794)
						)
						(arc
							(start 0.1778 0.2794)
							(mid 0.249642 0.249642)
							(end 0.2794 0.1778)
						)
						(arc
							(start 0.2794 -0.1778)
							(mid 0.249642 -0.249642)
							(end 0.1778 -0.2794)
						)
					)
					(width 0)
					(fill yes)
				)
			)
		)
		(pad "2" smd custom
			(at 0 0.4445 90)
			(size 0.1397 0.1397)
			(layers "F.Cu" "F.Mask" "F.Paste")
			(net "I2C_B_SDA")
			(options
				(clearance outline)
				(anchor circle)
			)
			(primitives
				(gr_poly
					(pts
						(arc
							(start -0.1778 -0.2794)
							(mid -0.249642 -0.249642)
							(end -0.2794 -0.1778)
						)
						(arc
							(start -0.2794 0.1778)
							(mid -0.249642 0.249642)
							(end -0.1778 0.2794)
						)
						(arc
							(start 0.1778 0.2794)
							(mid 0.249642 0.249642)
							(end 0.2794 0.1778)
						)
						(arc
							(start 0.2794 -0.1778)
							(mid 0.249642 -0.249642)
							(end 0.1778 -0.2794)
						)
					)
					(width 0)
					(fill yes)
				)
			)
		)
	)
	(footprint ""
		(layer "F.Cu")
		(at 29.845 -417.449)
		(property "Reference" "C274"
			(at 0 0 0)
			(layer "F.SilkS")
			(hide yes)
			(effects
				(font
					(size 1.27 1.27)
				)
			)
		)
		(property "Value" "SC10U25V6KX-1GP"
			(at -0.0762 -5.1308 0)
			(unlocked yes)
			(layer "F.Fab")
			(hide yes)
			(effects
				(font
					(size 1.016 1.016)
					(thickness 0.1524)
				)
			)
		)
		(property "Device Type" "C1206H71"
			(at -0.127 -6.6548 0)
			(unlocked yes)
			(layer "F.Fab")
			(hide yes)
			(effects
				(font
					(size 1.016 1.016)
					(thickness 0.1524)
				)
			)
		)
		(duplicate_pad_numbers_are_jumpers no)
		(fp_line
			(start -1.016 -2.2352)
			(end 1.016 -2.2352)
			(stroke
				(width 0.1524)
				(type default)
			)
			(layer "F.SilkS")
		)
		(fp_line
			(start -1.016 -0.8382)
			(end -1.016 -2.2352)
			(stroke
				(width 0.1524)
				(type default)
			)
			(layer "F.SilkS")
		)
		(fp_line
			(start -1.016 2.2352)
			(end -1.016 0.8382)
			(stroke
				(width 0.1524)
				(type default)
			)
			(layer "F.SilkS")
		)
		(fp_line
			(start 1.016 -2.2352)
			(end 1.016 -0.8382)
			(stroke
				(width 0.1524)
				(type default)
			)
			(layer "F.SilkS")
		)
		(fp_line
			(start 1.016 0.8382)
			(end 1.016 2.2352)
			(stroke
				(width 0.1524)
				(type default)
			)
			(layer "F.SilkS")
		)
		(fp_line
			(start 1.016 2.2352)
			(end -1.016 2.2352)
			(stroke
				(width 0.1524)
				(type default)
			)
			(layer "F.SilkS")
		)
		(fp_rect
			(start -1.0922 2.3114)
			(end 1.0922 -2.3114)
			(stroke
				(width 0)
				(type default)
			)
			(fill no)
			(layer "F.CrtYd")
		)
		(fp_poly
			(pts
				(xy 1.0922 -2.3114) (xy 1.0922 2.3114) (xy -1.0922 2.3114) (xy -1.0922 -2.3114)
			)
			(stroke
				(width 0)
				(type default)
			)
			(fill no)
			(layer "F.Fab")
		)
		(pad "1" smd rect
			(at 0 -1.397)
			(size 1.651 1.27)
			(layers "F.Cu" "F.Mask" "F.Paste")
			(net "P12V_HDD10")
		)
		(pad "2" smd rect
			(at 0 1.397)
			(size 1.651 1.27)
			(layers "F.Cu" "F.Mask" "F.Paste")
			(net "GND")
		)
	)
	(footprint ""
		(layer "F.Cu")
		(at 25.991312 -338.696808 90)
		(property "Reference" "C281"
			(at 0 0 90)
			(layer "F.SilkS")
			(hide yes)
			(effects
				(font
					(size 1.27 1.27)
				)
			)
		)
		(property "Value" "SCD01U50V2KX-1GP"
			(at 1.1811 -2.7051 90)
			(unlocked yes)
			(layer "F.Fab")
			(hide yes)
			(effects
				(font
					(size 1.016 1.016)
					(thickness 0.1524)
				)
			)
		)
		(property "Device Type" "C402H22"
			(at 1.1811 -4.2291 90)
			(unlocked yes)
			(layer "F.Fab")
			(hide yes)
			(effects
				(font
					(size 1.016 1.016)
					(thickness 0.1524)
				)
			)
		)
		(duplicate_pad_numbers_are_jumpers no)
		(fp_rect
			(start -0.4318 0.9525)
			(end 0.4318 -0.9525)
			(stroke
				(width 0)
				(type default)
			)
			(fill no)
			(layer "F.CrtYd")
		)
		(fp_rect
			(start -0.4318 0.9525)
			(end 0.4318 -0.9525)
			(stroke
				(width 0)
				(type default)
			)
			(fill no)
			(layer "F.Fab")
		)
		(pad "1" smd custom
			(at 0 -0.4445 90)
			(size 0.1524 0.1524)
			(layers "F.Cu" "F.Mask" "F.Paste")
			(net "SAS2X28_DRIVE_RX_P_B11")
			(options
				(clearance outline)
				(anchor circle)
			)
			(primitives
				(gr_poly
					(pts
						(arc
							(start 0.3048 -0.2032)
							(mid 0.275042 -0.275042)
							(end 0.2032 -0.3048)
						)
						(arc
							(start -0.2032 -0.3048)
							(mid -0.275042 -0.275042)
							(end -0.3048 -0.2032)
						)
						(arc
							(start -0.3048 0.2032)
							(mid -0.275042 0.275042)
							(end -0.2032 0.3048)
						)
						(arc
							(start 0.2032 0.3048)
							(mid 0.275042 0.275042)
							(end 0.3048 0.2032)
						)
					)
					(width 0)
					(fill yes)
				)
			)
		)
		(pad "2" smd custom
			(at 0 0.4445 90)
			(size 0.1524 0.1524)
			(layers "F.Cu" "F.Mask" "F.Paste")
			(net "SAS2X28_B_HDD11_RX_+")
			(options
				(clearance outline)
				(anchor circle)
			)
			(primitives
				(gr_poly
					(pts
						(arc
							(start 0.3048 -0.2032)
							(mid 0.275042 -0.275042)
							(end 0.2032 -0.3048)
						)
						(arc
							(start -0.2032 -0.3048)
							(mid -0.275042 -0.275042)
							(end -0.3048 -0.2032)
						)
						(arc
							(start -0.3048 0.2032)
							(mid -0.275042 0.275042)
							(end -0.2032 0.3048)
						)
						(arc
							(start 0.2032 0.3048)
							(mid 0.275042 0.275042)
							(end 0.3048 0.2032)
						)
					)
					(width 0)
					(fill yes)
				)
			)
		)
	)
	(footprint ""
		(layer "F.Cu")
		(at 27.177746 -32.9057 90)
		(property "Reference" "C328"
			(at 0 0 90)
			(layer "F.SilkS")
			(hide yes)
			(effects
				(font
					(size 1.27 1.27)
				)
			)
		)
		(property "Value" "SCD01U50V2KX-1GP"
			(at 1.1811 -2.7051 90)
			(unlocked yes)
			(layer "F.Fab")
			(hide yes)
			(effects
				(font
					(size 1.016 1.016)
					(thickness 0.1524)
				)
			)
		)
		(property "Device Type" "C402H22"
			(at 1.1811 -4.2291 90)
			(unlocked yes)
			(layer "F.Fab")
			(hide yes)
			(effects
				(font
					(size 1.016 1.016)
					(thickness 0.1524)
				)
			)
		)
		(duplicate_pad_numbers_are_jumpers no)
		(fp_rect
			(start -0.4318 0.9525)
			(end 0.4318 -0.9525)
			(stroke
				(width 0)
				(type default)
			)
			(fill no)
			(layer "F.CrtYd")
		)
		(fp_rect
			(start -0.4318 0.9525)
			(end 0.4318 -0.9525)
			(stroke
				(width 0)
				(type default)
			)
			(fill no)
			(layer "F.Fab")
		)
		(pad "1" smd custom
			(at 0 -0.4445 90)
			(size 0.1524 0.1524)
			(layers "F.Cu" "F.Mask" "F.Paste")
			(net "SAS2X28_DRIVE_RX_N_B14")
			(options
				(clearance outline)
				(anchor circle)
			)
			(primitives
				(gr_poly
					(pts
						(arc
							(start 0.3048 -0.2032)
							(mid 0.275042 -0.275042)
							(end 0.2032 -0.3048)
						)
						(arc
							(start -0.2032 -0.3048)
							(mid -0.275042 -0.275042)
							(end -0.3048 -0.2032)
						)
						(arc
							(start -0.3048 0.2032)
							(mid -0.275042 0.275042)
							(end -0.2032 0.3048)
						)
						(arc
							(start 0.2032 0.3048)
							(mid 0.275042 0.275042)
							(end 0.3048 0.2032)
						)
					)
					(width 0)
					(fill yes)
				)
			)
		)
		(pad "2" smd custom
			(at 0 0.4445 90)
			(size 0.1524 0.1524)
			(layers "F.Cu" "F.Mask" "F.Paste")
			(net "SAS2X28_B_HDD14_RX_-")
			(options
				(clearance outline)
				(anchor circle)
			)
			(primitives
				(gr_poly
					(pts
						(arc
							(start 0.3048 -0.2032)
							(mid 0.275042 -0.275042)
							(end 0.2032 -0.3048)
						)
						(arc
							(start -0.2032 -0.3048)
							(mid -0.275042 -0.275042)
							(end -0.3048 -0.2032)
						)
						(arc
							(start -0.3048 0.2032)
							(mid -0.275042 0.275042)
							(end -0.2032 0.3048)
						)
						(arc
							(start 0.2032 0.3048)
							(mid 0.275042 0.275042)
							(end 0.3048 0.2032)
						)
					)
					(width 0)
					(fill yes)
				)
			)
		)
	)
	(footprint ""
		(layer "F.Cu")
		(at 202.564746 -287.7947 -90)
		(property "Reference" "R430"
			(at 0 0 270)
			(layer "F.SilkS")
			(hide yes)
			(effects
				(font
					(size 1.27 1.27)
				)
			)
		)
		(property "Value" "4K7R2J-2-GP"
			(at 0.064008 -3.993896 270)
			(unlocked yes)
			(layer "F.Fab")
			(hide yes)
			(effects
				(font
					(size 1.016 1.016)
					(thickness 0.1524)
				)
			)
		)
		(property "Device Type" "R402H16"
			(at 0.064008 -5.517896 270)
			(unlocked yes)
			(layer "F.Fab")
			(hide yes)
			(effects
				(font
					(size 1.016 1.016)
					(thickness 0.1524)
				)
			)
		)
		(duplicate_pad_numbers_are_jumpers no)
		(fp_line
			(start -0.508 -0.9398)
			(end -0.508 0.9398)
			(stroke
				(width 0.1524)
				(type default)
			)
			(layer "F.SilkS")
		)
		(fp_line
			(start 0.508 -0.9398)
			(end -0.508 -0.9398)
			(stroke
				(width 0.1524)
				(type default)
			)
			(layer "F.SilkS")
		)
		(fp_rect
			(start -0.508 0.9398)
			(end 0.508 -0.9398)
			(stroke
				(width 0)
				(type default)
			)
			(fill no)
			(layer "F.CrtYd")
		)
		(fp_rect
			(start -0.508 0.9398)
			(end 0.508 -0.9398)
			(stroke
				(width 0)
				(type default)
			)
			(fill no)
			(layer "F.Fab")
		)
		(pad "1" smd custom
			(at 0 -0.4445 270)
			(size 0.1397 0.1397)
			(layers "F.Cu" "F.Mask" "F.Paste")
			(net "P3V3")
			(options
				(clearance outline)
				(anchor circle)
			)
			(primitives
				(gr_poly
					(pts
						(arc
							(start -0.1778 -0.2794)
							(mid -0.249642 -0.249642)
							(end -0.2794 -0.1778)
						)
						(arc
							(start -0.2794 0.1778)
							(mid -0.249642 0.249642)
							(end -0.1778 0.2794)
						)
						(arc
							(start 0.1778 0.2794)
							(mid 0.249642 0.249642)
							(end 0.2794 0.1778)
						)
						(arc
							(start 0.2794 -0.1778)
							(mid 0.249642 -0.249642)
							(end 0.1778 -0.2794)
						)
					)
					(width 0)
					(fill yes)
				)
			)
		)
		(pad "2" smd custom
			(at 0 0.4445 270)
			(size 0.1397 0.1397)
			(layers "F.Cu" "F.Mask" "F.Paste")
			(net "SAS2X28_B_HDD2_FLT")
			(options
				(clearance outline)
				(anchor circle)
			)
			(primitives
				(gr_poly
					(pts
						(arc
							(start -0.1778 -0.2794)
							(mid -0.249642 -0.249642)
							(end -0.2794 -0.1778)
						)
						(arc
							(start -0.2794 0.1778)
							(mid -0.249642 0.249642)
							(end -0.1778 0.2794)
						)
						(arc
							(start 0.1778 0.2794)
							(mid 0.249642 0.249642)
							(end 0.2794 0.1778)
						)
						(arc
							(start 0.2794 -0.1778)
							(mid 0.249642 -0.249642)
							(end 0.1778 -0.2794)
						)
					)
					(width 0)
					(fill yes)
				)
			)
		)
	)
	(footprint ""
		(layer "F.Cu")
		(at 71.754746 -396.5067)
		(property "Reference" "R447"
			(at 0 0 0)
			(layer "F.SilkS")
			(hide yes)
			(effects
				(font
					(size 1.27 1.27)
				)
			)
		)
		(property "Value" "4K7R2J-2-GP"
			(at 0.064008 -3.993896 0)
			(unlocked yes)
			(layer "F.Fab")
			(hide yes)
			(effects
				(font
					(size 1.016 1.016)
					(thickness 0.1524)
				)
			)
		)
		(property "Device Type" "R402H16"
			(at 0.064008 -5.517896 0)
			(unlocked yes)
			(layer "F.Fab")
			(hide yes)
			(effects
				(font
					(size 1.016 1.016)
					(thickness 0.1524)
				)
			)
		)
		(duplicate_pad_numbers_are_jumpers no)
		(fp_line
			(start -0.508 -0.9398)
			(end -0.508 0.9398)
			(stroke
				(width 0.1524)
				(type default)
			)
			(layer "F.SilkS")
		)
		(fp_line
			(start 0.508 -0.9398)
			(end -0.508 -0.9398)
			(stroke
				(width 0.1524)
				(type default)
			)
			(layer "F.SilkS")
		)
		(fp_rect
			(start -0.508 0.9398)
			(end 0.508 -0.9398)
			(stroke
				(width 0)
				(type default)
			)
			(fill no)
			(layer "F.CrtYd")
		)
		(fp_rect
			(start -0.508 0.9398)
			(end 0.508 -0.9398)
			(stroke
				(width 0)
				(type default)
			)
			(fill no)
			(layer "F.Fab")
		)
		(pad "1" smd custom
			(at 0 -0.4445)
			(size 0.1397 0.1397)
			(layers "F.Cu" "F.Mask" "F.Paste")
			(net "P3V3")
			(options
				(clearance outline)
				(anchor circle)
			)
			(primitives
				(gr_poly
					(pts
						(arc
							(start -0.1778 -0.2794)
							(mid -0.249642 -0.249642)
							(end -0.2794 -0.1778)
						)
						(arc
							(start -0.2794 0.1778)
							(mid -0.249642 0.249642)
							(end -0.1778 0.2794)
						)
						(arc
							(start 0.1778 0.2794)
							(mid 0.249642 0.249642)
							(end 0.2794 0.1778)
						)
						(arc
							(start 0.2794 -0.1778)
							(mid 0.249642 -0.249642)
							(end 0.1778 -0.2794)
						)
					)
					(width 0)
					(fill yes)
				)
			)
		)
		(pad "2" smd custom
			(at 0 0.4445)
			(size 0.1397 0.1397)
			(layers "F.Cu" "F.Mask" "F.Paste")
			(net "SAS2X28_B_HDD6_FLT")
			(options
				(clearance outline)
				(anchor circle)
			)
			(primitives
				(gr_poly
					(pts
						(arc
							(start -0.1778 -0.2794)
							(mid -0.249642 -0.249642)
							(end -0.2794 -0.1778)
						)
						(arc
							(start -0.2794 0.1778)
							(mid -0.249642 0.249642)
							(end -0.1778 0.2794)
						)
						(arc
							(start 0.1778 0.2794)
							(mid 0.249642 0.249642)
							(end 0.2794 0.1778)
						)
						(arc
							(start 0.2794 -0.1778)
							(mid 0.249642 -0.249642)
							(end 0.1778 -0.2794)
						)
					)
					(width 0)
					(fill yes)
				)
			)
		)
	)
	(gr_poly
		(pts
			(xy 14.986 -495.427) (xy 14.986 -494.0427) (xy 14.09065 -493.14735) (xy 8.896096 -493.14735) (xy 8.000746 -494.0427)
			(xy 8.000746 -495.6937) (xy 8.254746 -495.9477) (xy 14.4653 -495.9477)
		)
		(stroke
			(width 0)
			(type solid)
		)
		(fill yes)
		(layer "F.Cu")
		(net "GND")
	)
	(gr_poly
		(pts
			(xy 35.432746 -502.793254) (xy 35.432746 -497.4717) (xy 35.178746 -497.2177) (xy 29.717746 -497.2177)
			(xy 29.463746 -497.4717) (xy 29.463746 -502.792746) (xy 29.972 -503.301) (xy 34.925 -503.301)
		)
		(stroke
			(width 0)
			(type solid)
		)
		(fill yes)
		(layer "F.Cu")
		(net "P12V")
	)
	(gr_poly
		(pts
			(xy 53.847746 -11.5697) (xy 53.847746 -5.2197) (xy 53.339746 -4.7117) (xy 47.624746 -4.7117) (xy 46.735746 -5.6007)
			(xy 46.735746 -9.4107) (xy 49.656746 -12.3317) (xy 53.085746 -12.3317)
		)
		(stroke
			(width 0)
			(type solid)
		)
		(fill yes)
		(layer "F.Cu")
		(net "P12V")
	)
	(gr_poly
		(pts
			(xy 234.314746 -12.3317) (xy 234.314746 -4.4577) (xy 233.679746 -3.8227) (xy 228.726746 -3.8227)
			(xy 228.091746 -4.4577) (xy 228.091746 -9.4107) (xy 231.393746 -12.7127) (xy 233.933746 -12.7127)
		)
		(stroke
			(width 0)
			(type solid)
		)
		(fill yes)
		(layer "F.Cu")
		(net "P12V")
	)
	(gr_poly
		(pts
			(xy 55.096918 -21.179282) (xy 55.096918 -15.464282) (xy 55.118 -15.464282) (xy 55.118 -14.224) (xy 54.1782 -13.2842)
			(xy 52.0954 -13.2842) (xy 51.8668 -13.5128) (xy 51.8668 -15.464282) (xy 51.92649 -15.464282) (xy 51.92649 -21.19249)
			(xy 52.149756 -21.415756) (xy 52.74818 -21.415756) (xy 52.79517 -21.463) (xy 54.8132 -21.463)
		)
		(stroke
			(width 0)
			(type solid)
		)
		(fill yes)
		(layer "F.Cu")
		(net "GND")
	)
	(gr_poly
		(pts
			(xy 242.442746 -22.9997) (xy 242.442746 -8.6487) (xy 241.553746 -7.7597) (xy 235.457746 -7.7597)
			(xy 234.949746 -8.2677) (xy 234.949746 -16.7767) (xy 235.711746 -17.5387) (xy 237.108746 -17.5387)
			(xy 237.743746 -18.1737) (xy 237.743746 -18.643092) (xy 237.8075 -18.643092) (xy 237.8075 -21.772372)
			(xy 239.152176 -21.772372) (xy 239.152176 -21.797772) (xy 240.531142 -21.797772) (xy 240.59007 -21.8567)
			(xy 240.664746 -21.8567) (xy 240.994946 -22.1869) (xy 241.426746 -22.1869) (xy 241.680746 -22.1869)
			(xy 241.680746 -22.4409) (xy 241.426746 -22.4409) (xy 241.426746 -22.1869) (xy 240.994946 -22.1869)
			(xy 241.299746 -22.4917) (xy 241.299746 -22.566376) (xy 241.7318 -22.99843) (xy 241.7318 -23.1267)
			(xy 242.315746 -23.1267)
		)
		(stroke
			(width 0)
			(type solid)
		)
		(fill yes)
		(layer "F.Cu")
		(net "P5VA_12VIN")
	)
	(gr_poly
		(pts
			(xy 46.804326 -30.108906) (xy 46.836946 -30.098181) (xy 46.904617 -30.086568) (xy 46.938946 -30.085792)
			(xy 47.294546 -30.085792) (xy 47.328877 -30.086546) (xy 47.39655 -30.098165) (xy 47.429166 -30.108906)
			(xy 47.437294 -30.1117) (xy 47.497746 -30.1117) (xy 47.624746 -29.9847) (xy 47.624746 -27.4447) (xy 45.973746 -25.7937)
			(xy 45.973746 -25.504648) (xy 45.970952 -25.49652) (xy 45.960287 -25.463892) (xy 45.948798 -25.39622)
			(xy 45.948092 -25.3619) (xy 45.948092 -25.005792) (xy 45.846746 -24.9047) (xy 44.322746 -24.9047)
			(xy 43.433746 -24.0157) (xy 43.433746 -19.5707) (xy 42.798746 -18.9357) (xy 27.558746 -18.9357) (xy 27.304746 -19.1897)
			(xy 27.304746 -25.3365) (xy 45.211746 -25.3365) (xy 45.465746 -25.3365) (xy 45.465746 -25.5905) (xy 45.211746 -25.5905)
			(xy 45.211746 -25.3365) (xy 27.304746 -25.3365) (xy 27.304746 -29.0957) (xy 27.609546 -29.4005) (xy 46.710346 -29.4005)
			(xy 46.964346 -29.4005) (xy 46.964346 -29.6545) (xy 46.710346 -29.6545) (xy 46.710346 -29.4005) (xy 27.609546 -29.4005)
			(xy 28.320746 -30.1117) (xy 46.796198 -30.1117)
		)
		(stroke
			(width 0)
			(type solid)
		)
		(fill yes)
		(layer "F.Cu")
		(net "P5VB")
	)
	(gr_poly
		(pts
			(xy 60.705746 -19.8247) (xy 60.705746 -18.9357) (xy 60.4393 -18.669508) (xy 60.032392 -18.669508)
			(xy 60.032392 -18.262092) (xy 59.943746 -18.1737) (xy 59.943746 -7.7597) (xy 59.562746 -7.3787) (xy 54.863746 -7.3787)
			(xy 54.482746 -7.7597) (xy 54.482746 -12.9667) (xy 55.625746 -14.1097) (xy 55.625746 -18.3007) (xy 55.752746 -18.4277)
			(xy 57.276746 -18.4277) (xy 57.338976 -18.490184) (xy 58.331354 -18.490184) (xy 58.63717 -18.795746)
			(xy 58.655712 -18.79727) (xy 58.690053 -18.800455) (xy 58.757704 -18.813876) (xy 58.823306 -18.835162)
			(xy 58.885949 -18.864019) (xy 58.920038 -18.8849) (xy 59.562746 -18.8849) (xy 59.816746 -18.8849)
			(xy 59.816746 -19.1389) (xy 59.562746 -19.1389) (xy 59.562746 -18.8849) (xy 58.920038 -18.8849) (xy 58.944761 -18.900044)
			(xy 58.998927 -18.942739) (xy 59.047694 -18.99151) (xy 59.090384 -19.045679) (xy 59.126405 -19.104495)
			(xy 59.155256 -19.16714) (xy 59.176537 -19.232744) (xy 59.189952 -19.300396) (xy 59.193176 -19.334734)
			(xy 59.1947 -19.353276) (xy 59.3598 -19.51863) (xy 59.3598 -19.749008) (xy 59.562746 -19.9517) (xy 60.578746 -19.9517)
		)
		(stroke
			(width 0)
			(type solid)
		)
		(fill yes)
		(layer "F.Cu")
		(net "P5VB_12VIN")
	)
	(gr_poly
		(pts
			(xy 28.574746 -500.0117) (xy 28.574746 -497.5987) (xy 28.193746 -497.2177) (xy 24.002746 -497.2177)
			(xy 23.240746 -496.4557) (xy 11.2268 -496.4557) (xy 11.2268 -497.015008) (xy 11.683746 -497.4717)
			(xy 11.683746 -498.106446) (xy 11.7348 -498.1575) (xy 11.7348 -498.64645) (xy 11.746887 -498.669127)
			(xy 11.76589 -498.716872) (xy 11.778733 -498.766629) (xy 11.785212 -498.817606) (xy 11.7856 -498.8433)
			(xy 11.7856 -498.8687) (xy 12.140946 -498.8687) (xy 12.394946 -498.8687) (xy 13.004546 -498.8687)
			(xy 13.258546 -498.8687) (xy 13.258546 -499.1227) (xy 13.004546 -499.1227) (xy 13.004546 -498.8687)
			(xy 12.394946 -498.8687) (xy 12.394946 -499.1227) (xy 12.140946 -499.1227) (xy 12.140946 -498.8687)
			(xy 11.7856 -498.8687) (xy 11.7856 -499.2497) (xy 11.785454 -499.266411) (xy 11.782782 -499.299726)
			(xy 11.780266 -499.316248) (xy 11.775948 -499.341902) (xy 12.547092 -500.112792) (xy 13.029946 -500.112792)
			(xy 13.060357 -500.113355) (xy 13.120501 -500.122407) (xy 13.178625 -500.140316) (xy 13.233434 -500.166684)
			(xy 13.283703 -500.200922) (xy 13.328312 -500.242265) (xy 13.3477 -500.2657) (xy 24.637746 -500.2657)
			(xy 25.272746 -500.9007) (xy 27.685746 -500.9007)
		)
		(stroke
			(width 0)
			(type solid)
		)
		(fill yes)
		(layer "F.Cu")
		(net "P5VC_12VIN")
	)
	(gr_poly
		(pts
			(xy 229.176326 -32.902906) (xy 229.208946 -32.892181) (xy 229.276617 -32.880568) (xy 229.310946 -32.879792)
			(xy 229.666546 -32.879792) (xy 229.700877 -32.880546) (xy 229.76855 -32.892165) (xy 229.801166 -32.902906)
			(xy 229.809294 -32.9057) (xy 229.869746 -32.9057) (xy 229.996746 -32.7787) (xy 229.996746 -32.156654)
			(xy 229.973368 -32.137219) (xy 229.932087 -32.092591) (xy 229.897906 -32.042318) (xy 229.871585 -31.98752)
			(xy 229.85371 -31.929414) (xy 229.84468 -31.869296) (xy 229.844092 -31.8389) (xy 229.844092 -31.4325)
			(xy 229.84414 -31.420791) (xy 229.845411 -31.397409) (xy 229.846632 -31.385764) (xy 229.849426 -31.36138)
			(xy 229.742746 -31.2547) (xy 228.726746 -31.2547) (xy 227.678996 -30.20695) (xy 227.678996 -23.48738)
			(xy 227.652457 -23.471069) (xy 227.602668 -23.433629) (xy 227.557142 -23.391106) (xy 227.516395 -23.343985)
			(xy 227.480889 -23.292798) (xy 227.465636 -23.265638) (xy 227.462334 -23.259288) (xy 224.408746 -20.2057)
			(xy 212.597746 -20.2057) (xy 212.216746 -20.5867) (xy 212.216746 -32.0167) (xy 212.394546 -32.1945)
			(xy 229.082346 -32.1945) (xy 229.107746 -32.0675) (xy 229.107746 -31.8135) (xy 229.361746 -31.8135)
			(xy 229.361746 -32.0675) (xy 229.336346 -32.1945) (xy 229.336346 -32.4485) (xy 229.082346 -32.4485)
			(xy 229.082346 -32.1945) (xy 212.394546 -32.1945) (xy 213.105746 -32.9057) (xy 229.168198 -32.9057)
		)
		(stroke
			(width 0)
			(type solid)
		)
		(fill yes)
		(layer "F.Cu")
		(net "P5VA")
	)
	(gr_poly
		(pts
			(xy 232.525316 -21.772372) (xy 233.764328 -21.772372) (xy 233.806746 -21.7297) (xy 233.806746 -15.6337)
			(xy 227.456746 -9.2837) (xy 213.232746 -9.2837) (xy 212.343746 -10.1727) (xy 212.343746 -19.3167)
			(xy 212.661246 -19.6342) (xy 225.234246 -19.6342) (xy 226.694746 -21.0947) (xy 229.310946 -21.0947)
			(xy 229.564946 -21.0947) (xy 229.920546 -21.0947) (xy 230.453946 -21.0947) (xy 230.809546 -21.0947)
			(xy 231.063546 -21.0947) (xy 231.063546 -21.3487) (xy 230.809546 -21.3487) (xy 230.809546 -21.0947)
			(xy 230.453946 -21.0947) (xy 230.453946 -21.3487) (xy 229.920546 -21.3487) (xy 229.920546 -21.0947)
			(xy 229.564946 -21.0947) (xy 229.564946 -21.3487) (xy 229.310946 -21.3487) (xy 229.310946 -21.0947)
			(xy 226.694746 -21.0947) (xy 226.745546 -21.1455) (xy 228.320346 -21.1455) (xy 228.574346 -21.1455)
			(xy 228.879146 -21.1455) (xy 229.133146 -21.1455) (xy 229.133146 -21.3995) (xy 228.879146 -21.3995)
			(xy 228.879146 -21.1455) (xy 228.574346 -21.1455) (xy 228.574346 -21.3995) (xy 228.320346 -21.3995)
			(xy 228.320346 -21.1455) (xy 226.745546 -21.1455) (xy 227.393246 -21.7932) (xy 231.465628 -21.7932)
			(xy 231.499544 -21.777668) (xy 231.570109 -21.753465) (xy 231.642949 -21.737358) (xy 231.71714 -21.72955)
			(xy 231.791737 -21.730142) (xy 231.865795 -21.739125) (xy 231.938371 -21.756385) (xy 232.008543 -21.781703)
			(xy 232.042208 -21.797772) (xy 232.525316 -21.797772)
		)
		(stroke
			(width 0)
			(type solid)
		)
		(fill yes)
		(layer "F.Cu")
		(net "P5VA_LL")
	)
	(gr_poly
		(pts
			(xy 34.924746 -495.4397) (xy 34.924746 -485.2797) (xy 33.400746 -483.7557) (xy 30.225746 -483.7557)
			(xy 28.1813 -481.711508) (xy 27.990292 -481.711508) (xy 27.990292 -481.519992) (xy 27.177746 -480.7077)
			(xy 27.177746 -474.1037) (xy 26.542746 -473.4687) (xy 20.446746 -473.4687) (xy 20.192746 -473.7227)
			(xy 20.192746 -476.1357) (xy 19.430746 -476.8977) (xy 14.223746 -476.8977) (xy 13.969746 -477.1517)
			(xy 13.969746 -481.4443) (xy 14.299946 -481.4443) (xy 14.553946 -481.4443) (xy 14.553946 -481.6983)
			(xy 14.299946 -481.6983) (xy 14.299946 -481.4443) (xy 13.969746 -481.4443) (xy 13.969746 -482.0031)
			(xy 14.299946 -482.0031) (xy 14.553946 -482.0031) (xy 14.553946 -482.2571) (xy 14.299946 -482.2571)
			(xy 14.299946 -482.0031) (xy 13.969746 -482.0031) (xy 13.969746 -482.402642) (xy 14.000734 -482.415596)
			(xy 14.027989 -482.427668) (xy 14.078935 -482.458618) (xy 14.124818 -482.496671) (xy 14.164658 -482.541011)
			(xy 14.17851 -482.5619) (xy 14.731746 -482.5619) (xy 14.985746 -482.5619) (xy 14.985746 -482.8159)
			(xy 14.731746 -482.8159) (xy 14.731746 -482.5619) (xy 14.17851 -482.5619) (xy 14.197601 -482.590691)
			(xy 14.222942 -482.644646) (xy 14.240139 -482.701721) (xy 14.248823 -482.760695) (xy 14.2494 -482.7905)
			(xy 14.2494 -483.1969) (xy 14.2494 -483.20706) (xy 14.249486 -483.2206) (xy 14.255949 -483.246885)
			(xy 14.269098 -483.270545) (xy 14.288007 -483.289914) (xy 14.311343 -483.303627) (xy 14.337466 -483.310721)
			(xy 14.351 -483.3112) (xy 14.668246 -483.3112) (xy 14.979396 -483.62235) (xy 18.67535 -483.62235)
			(xy 19.558 -484.505) (xy 21.844 -484.505) (xy 23.876 -486.537) (xy 23.869396 -486.543604) (xy 23.869396 -494.671604)
			(xy 25.526746 -496.3287) (xy 34.035746 -496.3287)
		)
		(stroke
			(width 0)
			(type solid)
		)
		(fill yes)
		(layer "F.Cu")
		(net "P5VC")
	)
	(gr_poly
		(pts
			(xy 44.137326 -18.424906) (xy 44.169946 -18.414181) (xy 44.237617 -18.402568) (xy 44.271946 -18.401792)
			(xy 44.627546 -18.401792) (xy 44.661877 -18.402546) (xy 44.72955 -18.414165) (xy 44.762166 -18.424906)
			(xy 44.770294 -18.4277) (xy 45.119798 -18.4277) (xy 45.127926 -18.424906) (xy 45.160546 -18.414181)
			(xy 45.228217 -18.402568) (xy 45.262546 -18.401792) (xy 45.668946 -18.401792) (xy 45.703277 -18.402546)
			(xy 45.77095 -18.414165) (xy 45.803566 -18.424906) (xy 45.811694 -18.4277) (xy 46.008798 -18.4277)
			(xy 46.016926 -18.424906) (xy 46.049546 -18.414181) (xy 46.117217 -18.402568) (xy 46.151546 -18.401792)
			(xy 46.557946 -18.401792) (xy 46.592277 -18.402546) (xy 46.65995 -18.414165) (xy 46.692566 -18.424906)
			(xy 46.700694 -18.4277) (xy 48.202342 -18.4277) (xy 48.230278 -18.403614) (xy 48.290582 -18.361133)
			(xy 48.35524 -18.32563) (xy 48.42345 -18.297549) (xy 48.494363 -18.277237) (xy 48.567096 -18.264948)
			(xy 48.640746 -18.260835) (xy 48.714396 -18.264948) (xy 48.787129 -18.277237) (xy 48.858042 -18.297549)
			(xy 48.926252 -18.32563) (xy 48.99091 -18.361133) (xy 49.051214 -18.403614) (xy 49.07915 -18.4277)
			(xy 51.307746 -18.4277) (xy 51.542696 -18.192496) (xy 51.542696 -15.335504) (xy 51.561746 -15.335504)
			(xy 51.561746 -14.9987) (xy 46.354746 -9.7917) (xy 27.939746 -9.7917) (xy 27.431746 -10.2997) (xy 27.431746 -17.6657)
			(xy 45.033946 -17.6657) (xy 45.287946 -17.6657) (xy 45.643546 -17.6657) (xy 46.176946 -17.6657) (xy 46.532546 -17.6657)
			(xy 46.786546 -17.6657) (xy 46.786546 -17.9197) (xy 46.532546 -17.9197) (xy 46.532546 -17.6657) (xy 46.176946 -17.6657)
			(xy 46.176946 -17.9197) (xy 45.643546 -17.9197) (xy 45.643546 -17.6657) (xy 45.287946 -17.6657) (xy 45.287946 -17.9197)
			(xy 45.033946 -17.9197) (xy 45.033946 -17.6657) (xy 27.431746 -17.6657) (xy 27.482546 -17.7165) (xy 44.043346 -17.7165)
			(xy 44.297346 -17.7165) (xy 44.602146 -17.7165) (xy 44.856146 -17.7165) (xy 44.856146 -17.9705) (xy 44.602146 -17.9705)
			(xy 44.602146 -17.7165) (xy 44.297346 -17.7165) (xy 44.297346 -17.9705) (xy 44.043346 -17.9705) (xy 44.043346 -17.7165)
			(xy 27.482546 -17.7165) (xy 28.193746 -18.4277) (xy 44.129198 -18.4277)
		)
		(stroke
			(width 0)
			(type solid)
		)
		(fill yes)
		(layer "F.Cu")
		(net "P5VB_LL")
	)
	(gr_poly
		(pts
			(xy 22.732746 -494.2967) (xy 22.732746 -486.9307) (xy 21.589746 -485.7877) (xy 18.541746 -485.7877)
			(xy 17.392396 -484.638604) (xy 14.738604 -484.638604) (xy 14.732 -484.632) (xy 13.335 -484.632) (xy 13.208 -484.505)
			(xy 13.208 -483.997) (xy 12.9667 -483.7557) (xy 11.556746 -483.7557) (xy 11.226546 -484.0859) (xy 12.166346 -484.0859)
			(xy 12.420346 -484.0859) (xy 12.725146 -484.0859) (xy 12.979146 -484.0859) (xy 12.979146 -484.3399)
			(xy 12.725146 -484.3399) (xy 12.725146 -484.0859) (xy 12.420346 -484.0859) (xy 12.420346 -484.3399)
			(xy 12.166346 -484.3399) (xy 12.166346 -484.0859) (xy 11.226546 -484.0859) (xy 9.778746 -485.5337)
			(xy 9.778746 -485.688894) (xy 9.779148 -485.698911) (xy 9.786792 -485.717427) (xy 9.800954 -485.731595)
			(xy 9.819467 -485.739248) (xy 9.839499 -485.739215) (xy 9.857986 -485.731501) (xy 9.86536 -485.724708)
			(xy 9.95299 -485.637332) (xy 9.9568 -485.628188) (xy 9.971499 -485.594646) (xy 10.007273 -485.53074)
			(xy 10.049892 -485.471181) (xy 10.098835 -485.416699) (xy 10.153501 -485.367962) (xy 10.213221 -485.325568)
			(xy 10.277261 -485.290036) (xy 10.344837 -485.261803) (xy 10.41512 -485.241213) (xy 10.487249 -485.22852)
			(xy 10.560339 -485.223879) (xy 10.633494 -485.227348) (xy 10.705817 -485.238883) (xy 10.776421 -485.258343)
			(xy 10.844441 -485.28549) (xy 10.909043 -485.319991) (xy 10.969434 -485.361423) (xy 11.024874 -485.409277)
			(xy 11.074684 -485.462967) (xy 11.118253 -485.521835) (xy 11.155046 -485.58516) (xy 11.184612 -485.652163)
			(xy 11.20659 -485.722025) (xy 11.220709 -485.793888) (xy 11.226796 -485.866872) (xy 11.224777 -485.940081)
			(xy 11.214676 -486.012618) (xy 11.196618 -486.083594) (xy 11.170823 -486.152138) (xy 11.137609 -486.217411)
			(xy 11.097381 -486.278611) (xy 11.050634 -486.334988) (xy 10.997941 -486.385851) (xy 10.939947 -486.430577)
			(xy 10.877364 -486.468617) (xy 10.810959 -486.499505) (xy 10.741546 -486.522861) (xy 10.669977 -486.5384)
			(xy 10.597128 -486.545932) (xy 10.523893 -486.545363) (xy 10.45117 -486.536701) (xy 10.37985 -486.520052)
			(xy 10.345166 -486.508298) (xy 10.31494 -486.49763) (xy 10.05967 -486.7529) (xy 10.286746 -486.7529)
			(xy 10.540746 -486.7529) (xy 10.540746 -487.0069) (xy 10.286746 -487.0069) (xy 10.286746 -486.7529)
			(xy 10.05967 -486.7529) (xy 9.8044 -487.00817) (xy 9.8044 -487.3625) (xy 10.286746 -487.3625) (xy 10.540746 -487.3625)
			(xy 10.540746 -487.8959) (xy 10.286746 -487.8959) (xy 10.286746 -487.3625) (xy 9.8044 -487.3625)
			(xy 9.8044 -487.3879) (xy 9.803709 -487.422221) (xy 9.792216 -487.489894) (xy 9.78154 -487.52252)
			(xy 9.778746 -487.530648) (xy 9.778746 -487.727752) (xy 9.78154 -487.73588) (xy 9.792205 -487.768508)
			(xy 9.803695 -487.83618) (xy 9.8044 -487.8705) (xy 9.8044 -488.225592) (xy 10.724642 -488.225592)
			(xy 10.751419 -488.201253) (xy 10.809387 -488.157936) (xy 10.871739 -488.12121) (xy 10.93773 -488.091515)
			(xy 11.00657 -488.069206) (xy 11.077435 -488.054551) (xy 11.149477 -488.047724) (xy 11.221833 -488.048809)
			(xy 11.293638 -488.05779) (xy 11.364032 -488.074562) (xy 11.432173 -488.098923) (xy 11.497245 -488.130582)
			(xy 11.558469 -488.16916) (xy 11.615112 -488.214194) (xy 11.666497 -488.265147) (xy 11.712009 -488.321408)
			(xy 11.751102 -488.382304) (xy 11.783309 -488.447106) (xy 11.808245 -488.515039) (xy 11.825611 -488.585289)
			(xy 11.835199 -488.657015) (xy 11.836894 -488.72936) (xy 11.830676 -488.801457) (xy 11.81662 -488.872443)
			(xy 11.794894 -488.941469) (xy 11.765757 -489.007708) (xy 11.729559 -489.070369) (xy 11.686733 -489.1287)
			(xy 11.637791 -489.182004) (xy 11.583319 -489.229642) (xy 11.523969 -489.271045) (xy 11.460451 -489.305717)
			(xy 11.393527 -489.333243) (xy 11.323995 -489.353294) (xy 11.25269 -489.365629) (xy 11.180464 -489.370101)
			(xy 11.108181 -489.366657) (xy 11.072368 -489.36148) (xy 11.058267 -489.359755) (xy 11.03009 -489.363269)
			(xy 11.003968 -489.374404) (xy 10.981921 -489.3923) (xy 10.965651 -489.415572) (xy 10.956416 -489.442425)
			(xy 10.954929 -489.470782) (xy 10.961306 -489.498453) (xy 10.975053 -489.523299) (xy 10.984738 -489.533692)
			(xy 11.175746 -489.7247) (xy 11.175746 -489.978192) (xy 11.176 -489.978446) (xy 11.176 -491.151672)
			(xy 11.2268 -491.151672) (xy 11.2268 -492.0488) (xy 11.43 -492.252) (xy 14.351 -492.252) (xy 14.351 -492.264954)
			(xy 17.652746 -495.5667) (xy 21.462746 -495.5667)
		)
		(stroke
			(width 0)
			(type solid)
		)
		(fill yes)
		(layer "F.Cu")
		(net "P5VC_LL")
	)
	(gr_poly
		(pts
			(xy 8.709914 -484.306118) (xy 8.707377 -484.32042) (xy 8.709529 -484.349372) (xy 8.719738 -484.376549)
			(xy 8.73718 -484.399758) (xy 8.760446 -484.417123) (xy 8.787657 -484.427243) (xy 8.816616 -484.429299)
			(xy 8.844984 -484.423127) (xy 8.87047 -484.409224) (xy 8.88111 -484.399336) (xy 10.252964 -483.027482)
			(xy 10.256774 -483.018338) (xy 10.269919 -482.988615) (xy 10.301874 -482.932019) (xy 10.339916 -482.879321)
			(xy 10.383575 -482.831173) (xy 10.43231 -482.788172) (xy 10.485518 -482.750847) (xy 10.513822 -482.734874)
			(xy 10.520172 -482.731318) (xy 10.753598 -482.497892) (xy 10.7823 -482.497892) (xy 12.445746 -480.8347)
			(xy 12.445746 -477.0247) (xy 13.080746 -476.3897) (xy 19.049746 -476.3897) (xy 19.684746 -475.7547)
			(xy 19.684746 -473.5957) (xy 19.616166 -473.52712) (xy 14.79042 -473.52712) (xy 11.836654 -470.573354)
			(xy 11.815572 -470.573608) (xy 11.778134 -470.573364) (xy 11.703684 -470.565452) (xy 11.630605 -470.549177)
			(xy 11.559833 -470.524748) (xy 11.492275 -470.492478) (xy 11.428796 -470.45278) (xy 11.37021 -470.406163)
			(xy 11.317267 -470.353224) (xy 11.270646 -470.294641) (xy 11.230944 -470.231166) (xy 11.198669 -470.16361)
			(xy 11.174236 -470.092839) (xy 11.157956 -470.019761) (xy 11.150038 -469.945311) (xy 11.149838 -469.907874)
			(xy 11.150092 -469.886792) (xy 10.414 -469.1507) (xy 1.650746 -469.1507) (xy 1.269746 -469.5317)
			(xy 1.269746 -471.22461) (xy 1.270293 -471.239745) (xy 1.279154 -471.268688) (xy 1.296111 -471.293762)
			(xy 1.319675 -471.312761) (xy 1.347773 -471.324017) (xy 1.377937 -471.32654) (xy 1.407515 -471.320107)
			(xy 1.433907 -471.305286) (xy 1.444752 -471.294714) (xy 1.482651 -471.255839) (xy 1.563347 -471.18319)
			(xy 1.649213 -471.116734) (xy 1.739777 -471.056836) (xy 1.834538 -471.003828) (xy 1.932973 -470.958001)
			(xy 2.034539 -470.91961) (xy 2.138675 -470.888865) (xy 2.244807 -470.865938) (xy 2.352347 -470.850953)
			(xy 2.460704 -470.843994) (xy 2.569278 -470.845099) (xy 2.67747 -470.854263) (xy 2.784683 -470.871434)
			(xy 2.890326 -470.896519) (xy 2.993814 -470.929377) (xy 3.094577 -470.969829) (xy 3.192059 -471.01765)
			(xy 3.285721 -471.072577) (xy 3.375047 -471.134306) (xy 3.459542 -471.202497) (xy 3.538742 -471.276773)
			(xy 3.612208 -471.356725) (xy 3.679535 -471.441911) (xy 3.740352 -471.53186) (xy 3.794322 -471.626076)
			(xy 3.841149 -471.72404) (xy 3.880572 -471.82521) (xy 3.912375 -471.929027) (xy 3.936382 -472.03492)
			(xy 3.952461 -472.142302) (xy 3.960523 -472.250582) (xy 3.960523 -472.359162) (xy 3.952461 -472.467442)
			(xy 3.936382 -472.574824) (xy 3.912375 -472.680717) (xy 3.880572 -472.784534) (xy 3.841149 -472.885704)
			(xy 3.794322 -472.983668) (xy 3.740352 -473.077884) (xy 3.679535 -473.167833) (xy 3.612208 -473.253019)
			(xy 3.538742 -473.332971) (xy 3.459542 -473.407247) (xy 3.375047 -473.475438) (xy 3.367155 -473.480892)
			(xy 9.118092 -473.480892) (xy 9.62406 -473.480892) (xy 9.637361 -473.480478) (xy 9.663049 -473.473563)
			(xy 9.686079 -473.460245) (xy 9.704884 -473.441428) (xy 9.718188 -473.41839) (xy 9.725087 -473.392697)
			(xy 9.725112 -473.366094) (xy 9.722104 -473.35313) (xy 9.713836 -473.320202) (xy 9.704004 -473.253027)
			(xy 9.702017 -473.185164) (xy 9.707903 -473.117528) (xy 9.721583 -473.051029) (xy 9.742872 -472.986562)
			(xy 9.771484 -472.924994) (xy 9.807034 -472.867155) (xy 9.849044 -472.813821) (xy 9.896947 -472.765712)
			(xy 9.9501 -472.723474) (xy 10.007787 -472.687677) (xy 10.069232 -472.658801) (xy 10.133607 -472.637235)
			(xy 10.200047 -472.623271) (xy 10.267657 -472.617095) (xy 10.335527 -472.61879) (xy 10.402744 -472.628335)
			(xy 10.468404 -472.6456) (xy 10.531622 -472.670353) (xy 10.591548 -472.702261) (xy 10.647375 -472.740895)
			(xy 10.698353 -472.785734) (xy 10.743794 -472.836175) (xy 10.783088 -472.89154) (xy 10.799826 -472.921076)
			(xy 10.803382 -472.927426) (xy 11.356848 -473.480892) (xy 12.522708 -473.480892) (xy 12.522708 -475.234508)
			(xy 9.118092 -475.234508) (xy 9.118092 -473.480892) (xy 3.367155 -473.480892) (xy 3.285721 -473.537167)
			(xy 3.192059 -473.592094) (xy 3.094577 -473.639915) (xy 2.993814 -473.680367) (xy 2.890326 -473.713225)
			(xy 2.784683 -473.73831) (xy 2.67747 -473.755481) (xy 2.569278 -473.764645) (xy 2.460704 -473.76575)
			(xy 2.352347 -473.758791) (xy 2.244807 -473.743806) (xy 2.138675 -473.720879) (xy 2.034539 -473.690134)
			(xy 1.932973 -473.651743) (xy 1.834538 -473.605916) (xy 1.739777 -473.552908) (xy 1.649213 -473.49301)
			(xy 1.563347 -473.426554) (xy 1.482651 -473.353905) (xy 1.444752 -473.31503) (xy 1.433901 -473.304479)
			(xy 1.40751 -473.289694) (xy 1.377947 -473.283286) (xy 1.347803 -473.285818) (xy 1.319722 -473.297067)
			(xy 1.296168 -473.316047) (xy 1.279205 -473.341093) (xy 1.270321 -473.370009) (xy 1.269746 -473.385134)
			(xy 1.269746 -480.295204) (xy 1.270274 -480.310227) (xy 1.279003 -480.338976) (xy 1.295723 -480.363939)
			(xy 1.318986 -480.382953) (xy 1.346778 -480.394371) (xy 1.376689 -480.397203) (xy 1.406129 -480.391204)
			(xy 1.432548 -480.376893) (xy 1.443482 -480.366578) (xy 1.508836 -480.301372) (xy 1.644348 -480.175961)
			(xy 1.785111 -480.056475) (xy 1.930866 -479.943132) (xy 2.081346 -479.836142) (xy 2.236274 -479.7357)
			(xy 2.395365 -479.641992) (xy 2.558327 -479.55519) (xy 2.72486 -479.475453) (xy 2.894658 -479.402928)
			(xy 3.067409 -479.337749) (xy 3.242795 -479.280034) (xy 3.420493 -479.229891) (xy 3.600178 -479.187411)
			(xy 3.781519 -479.152672) (xy 3.964182 -479.125739) (xy 4.147832 -479.106661) (xy 4.33213 -479.095473)
			(xy 4.516739 -479.092195) (xy 4.701319 -479.096834) (xy 4.88553 -479.109381) (xy 5.069034 -479.129812)
			(xy 5.251494 -479.158092) (xy 5.432573 -479.194166) (xy 5.61194 -479.23797) (xy 5.789264 -479.289422)
			(xy 5.96422 -479.348428) (xy 6.136485 -479.414879) (xy 6.305744 -479.488654) (xy 6.471684 -479.569617)
			(xy 6.634002 -479.657618) (xy 6.792398 -479.752496) (xy 6.946581 -479.854077) (xy 7.096268 -479.962174)
			(xy 7.241184 -480.076589) (xy 7.381062 -480.19711) (xy 7.515645 -480.323516) (xy 7.644686 -480.455575)
			(xy 7.767947 -480.593045) (xy 7.885203 -480.735671) (xy 7.996236 -480.883193) (xy 8.100844 -481.035339)
			(xy 8.198834 -481.19183) (xy 8.290025 -481.352376) (xy 8.374251 -481.516685) (xy 8.451356 -481.684453)
			(xy 8.521198 -481.855371) (xy 8.583649 -482.029127) (xy 8.638595 -482.2054) (xy 8.685934 -482.383866)
			(xy 8.72558 -482.564198) (xy 8.757459 -482.746063) (xy 8.781512 -482.929127) (xy 8.797696 -483.113054)
			(xy 8.805981 -483.297507) (xy 8.806352 -483.482144) (xy 8.798808 -483.666628) (xy 8.783362 -483.850619)
			(xy 8.760043 -484.033778) (xy 8.728895 -484.21577)
		)
		(stroke
			(width 0)
			(type solid)
		)
		(fill yes)
		(layer "F.Cu")
		(net "GND")
	)
	(gr_line
		(start 3.192526 -424.49877)
		(end 3.19405 -424.500294)
		(stroke
			(width 0.047498)
			(type default)
		)
		(layer "F.Cu")
	)
	(gr_line
		(start 3.192526 -423.498772)
		(end 3.19405 -423.500296)
		(stroke
			(width 0.047498)
			(type default)
		)
		(layer "F.Cu")
	)
	(gr_line
		(start 3.192526 -420.498778)
		(end 4.71424 -420.498778)
		(stroke
			(width 0.047498)
			(type default)
		)
		(layer "F.Cu")
	)
	(gr_line
		(start 3.192526 -419.49878)
		(end 4.713732 -419.49878)
		(stroke
			(width 0.047498)
			(type default)
		)
		(layer "F.Cu")
	)
	(gr_line
		(start 3.192526 -416.498786)
		(end 4.625594 -416.498786)
		(stroke
			(width 0.047498)
			(type default)
		)
		(layer "F.Cu")
	)
	(gr_line
		(start 3.192526 -415.498788)
		(end 4.66217 -415.498788)
		(stroke
			(width 0.047498)
			(type default)
		)
		(layer "F.Cu")
	)
	(gr_line
		(start 3.192526 -412.498794)
		(end 4.666234 -412.498794)
		(stroke
			(width 0.047498)
			(type default)
		)
		(layer "F.Cu")
	)
	(gr_line
		(start 3.192526 -411.498796)
		(end 4.705096 -411.498796)
		(stroke
			(width 0.047498)
			(type default)
		)
		(layer "F.Cu")
	)
	(gr_line
		(start 3.192526 -408.498802)
		(end 4.647946 -408.498802)
		(stroke
			(width 0.047498)
			(type default)
		)
		(layer "F.Cu")
	)
	(gr_line
		(start 3.192526 -407.498804)
		(end 4.735068 -407.498804)
		(stroke
			(width 0.047498)
			(type default)
		)
		(layer "F.Cu")
	)
	(gr_line
		(start 3.192526 -395.498828)
		(end 4.798568 -395.498828)
		(stroke
			(width 0.047498)
			(type default)
		)
		(layer "F.Cu")
	)
	(gr_line
		(start 3.192526 -394.49883)
		(end 4.689094 -394.49883)
		(stroke
			(width 0.047498)
			(type default)
		)
		(layer "F.Cu")
	)
	(gr_line
		(start 3.192526 -386.498846)
		(end 4.87934 -386.498846)
		(stroke
			(width 0.047498)
			(type default)
		)
		(layer "F.Cu")
	)
	(gr_line
		(start 3.192526 -385.498848)
		(end 4.884674 -385.498848)
		(stroke
			(width 0.047498)
			(type default)
		)
		(layer "F.Cu")
	)
	(gr_line
		(start 3.192526 -382.498854)
		(end 4.67868 -382.498854)
		(stroke
			(width 0.047498)
			(type default)
		)
		(layer "F.Cu")
	)
	(gr_line
		(start 3.192526 -381.498856)
		(end 4.690872 -381.498856)
		(stroke
			(width 0.047498)
			(type default)
		)
		(layer "F.Cu")
	)
	(gr_line
		(start 3.192526 -378.498862)
		(end 4.752848 -378.498862)
		(stroke
			(width 0.047498)
			(type default)
		)
		(layer "F.Cu")
	)
	(gr_line
		(start 3.192526 -377.498864)
		(end 4.760976 -377.498864)
		(stroke
			(width 0.047498)
			(type default)
		)
		(layer "F.Cu")
	)
	(gr_line
		(start 3.192526 -374.49887)
		(end 4.921758 -374.49887)
		(stroke
			(width 0.047498)
			(type default)
		)
		(layer "F.Cu")
	)
	(gr_line
		(start 3.192526 -373.498872)
		(end 4.887214 -373.498872)
		(stroke
			(width 0.047498)
			(type default)
		)
		(layer "F.Cu")
	)
	(gr_line
		(start 3.192526 -370.498878)
		(end 4.89331 -370.498878)
		(stroke
			(width 0.047498)
			(type default)
		)
		(layer "F.Cu")
	)
	(gr_line
		(start 3.192526 -369.49888)
		(end 4.877308 -369.49888)
		(stroke
			(width 0.047498)
			(type default)
		)
		(layer "F.Cu")
	)
	(gr_line
		(start 3.192526 -366.498886)
		(end 4.644898 -366.498886)
		(stroke
			(width 0.047498)
			(type default)
		)
		(layer "F.Cu")
	)
	(gr_line
		(start 3.192526 -365.498888)
		(end 4.647692 -365.498888)
		(stroke
			(width 0.047498)
			(type default)
		)
		(layer "F.Cu")
	)
	(gr_line
		(start 3.192526 -362.498894)
		(end 4.625086 -362.498894)
		(stroke
			(width 0.047498)
			(type default)
		)
		(layer "F.Cu")
	)
	(gr_line
		(start 3.192526 -361.498896)
		(end 4.625594 -361.498896)
		(stroke
			(width 0.047498)
			(type default)
		)
		(layer "F.Cu")
	)
	(gr_line
		(start 3.192526 -358.498902)
		(end 4.688078 -358.498902)
		(stroke
			(width 0.047498)
			(type default)
		)
		(layer "F.Cu")
	)
	(gr_line
		(start 3.192526 -357.49865)
		(end 3.19405 -357.500174)
		(stroke
			(width 0.047498)
			(type default)
		)
		(layer "F.Cu")
	)
	(gr_line
		(start 3.192526 -352.498406)
		(end 4.632706 -352.498406)
		(stroke
			(width 0.047498)
			(type default)
		)
		(layer "F.Cu")
	)
	(gr_line
		(start 3.192526 -351.498408)
		(end 4.833112 -351.498408)
		(stroke
			(width 0.047498)
			(type default)
		)
		(layer "F.Cu")
	)
	(gr_line
		(start 3.192526 -348.498414)
		(end 4.684014 -348.498414)
		(stroke
			(width 0.047498)
			(type default)
		)
		(layer "F.Cu")
	)
	(gr_line
		(start 3.192526 -347.498416)
		(end 4.83235 -347.498416)
		(stroke
			(width 0.047498)
			(type default)
		)
		(layer "F.Cu")
	)
	(gr_line
		(start 3.192526 -174.498762)
		(end 4.976876 -174.498762)
		(stroke
			(width 0.047498)
			(type default)
		)
		(layer "F.Cu")
	)
	(gr_line
		(start 3.192526 -173.498764)
		(end 4.799076 -173.498764)
		(stroke
			(width 0.047498)
			(type default)
		)
		(layer "F.Cu")
	)
	(gr_line
		(start 3.192526 -170.49877)
		(end 4.951476 -170.49877)
		(stroke
			(width 0.047498)
			(type default)
		)
		(layer "F.Cu")
	)
	(gr_line
		(start 3.192526 -169.498772)
		(end 4.741926 -169.498772)
		(stroke
			(width 0.047498)
			(type default)
		)
		(layer "F.Cu")
	)
	(gr_line
		(start 3.192526 -166.498778)
		(end 4.644644 -166.498778)
		(stroke
			(width 0.047498)
			(type default)
		)
		(layer "F.Cu")
	)
	(gr_line
		(start 3.192526 -165.49878)
		(end 4.666234 -165.49878)
		(stroke
			(width 0.047498)
			(type default)
		)
		(layer "F.Cu")
	)
	(gr_line
		(start 3.192526 -162.498786)
		(end 4.648962 -162.498786)
		(stroke
			(width 0.047498)
			(type default)
		)
		(layer "F.Cu")
	)
	(gr_line
		(start 3.192526 -161.498788)
		(end 4.66598 -161.498788)
		(stroke
			(width 0.047498)
			(type default)
		)
		(layer "F.Cu")
	)
	(gr_line
		(start 3.192526 -158.498794)
		(end 4.64439 -158.498794)
		(stroke
			(width 0.047498)
			(type default)
		)
		(layer "F.Cu")
	)
	(gr_line
		(start 3.192526 -157.498796)
		(end 4.657344 -157.498796)
		(stroke
			(width 0.047498)
			(type default)
		)
		(layer "F.Cu")
	)
	(gr_line
		(start 3.192526 -145.49882)
		(end 4.691126 -145.49882)
		(stroke
			(width 0.047498)
			(type default)
		)
		(layer "F.Cu")
	)
	(gr_line
		(start 3.192526 -144.498822)
		(end 4.692904 -144.498822)
		(stroke
			(width 0.047498)
			(type default)
		)
		(layer "F.Cu")
	)
	(gr_line
		(start 3.192526 -136.498838)
		(end 4.86029 -136.498838)
		(stroke
			(width 0.047498)
			(type default)
		)
		(layer "F.Cu")
	)
	(gr_line
		(start 3.192526 -135.49884)
		(end 3.19405 -135.500364)
		(stroke
			(width 0.047498)
			(type default)
		)
		(layer "F.Cu")
	)
	(gr_line
		(start 3.192526 -132.498846)
		(end 4.802632 -132.498846)
		(stroke
			(width 0.047498)
			(type default)
		)
		(layer "F.Cu")
	)
	(gr_line
		(start 3.192526 -131.498848)
		(end 4.890516 -131.498848)
		(stroke
			(width 0.047498)
			(type default)
		)
		(layer "F.Cu")
	)
	(gr_line
		(start 3.192526 -128.498854)
		(end 4.691888 -128.498854)
		(stroke
			(width 0.047498)
			(type default)
		)
		(layer "F.Cu")
	)
	(gr_line
		(start 3.192526 -127.498856)
		(end 4.675886 -127.498856)
		(stroke
			(width 0.047498)
			(type default)
		)
		(layer "F.Cu")
	)
	(gr_line
		(start 3.192526 -124.498862)
		(end 4.814824 -124.498862)
		(stroke
			(width 0.047498)
			(type default)
		)
		(layer "F.Cu")
	)
	(gr_line
		(start 3.192526 -123.498864)
		(end 4.761738 -123.498864)
		(stroke
			(width 0.047498)
			(type default)
		)
		(layer "F.Cu")
	)
	(gr_line
		(start 3.192526 -120.49887)
		(end 4.948428 -120.49887)
		(stroke
			(width 0.047498)
			(type default)
		)
		(layer "F.Cu")
	)
	(gr_line
		(start 3.192526 -119.498872)
		(end 4.930902 -119.498872)
		(stroke
			(width 0.047498)
			(type default)
		)
		(layer "F.Cu")
	)
	(gr_line
		(start 3.192526 -116.498878)
		(end 4.68122 -116.498878)
		(stroke
			(width 0.047498)
			(type default)
		)
		(layer "F.Cu")
	)
	(gr_line
		(start 3.192526 -115.49888)
		(end 4.692904 -115.49888)
		(stroke
			(width 0.047498)
			(type default)
		)
		(layer "F.Cu")
	)
	(gr_line
		(start 3.192526 -112.498886)
		(end 4.835398 -112.498886)
		(stroke
			(width 0.047498)
			(type default)
		)
		(layer "F.Cu")
	)
	(gr_line
		(start 3.192526 -111.498888)
		(end 4.830572 -111.498888)
		(stroke
			(width 0.047498)
			(type default)
		)
		(layer "F.Cu")
	)
	(gr_line
		(start 3.192526 -108.498894)
		(end 4.801616 -108.498894)
		(stroke
			(width 0.047498)
			(type default)
		)
		(layer "F.Cu")
	)
	(gr_line
		(start 3.192526 -107.498642)
		(end 3.19405 -107.500166)
		(stroke
			(width 0.047498)
			(type default)
		)
		(layer "F.Cu")
	)
	(gr_line
		(start 3.192526 -102.498398)
		(end 4.72567 -102.498398)
		(stroke
			(width 0.047498)
			(type default)
		)
		(layer "F.Cu")
	)
	(gr_line
		(start 3.192526 -101.4984)
		(end 3.19405 -101.499924)
		(stroke
			(width 0.047498)
			(type default)
		)
		(layer "F.Cu")
	)
	(gr_line
		(start 3.192526 -98.498406)
		(end 3.19405 -98.49993)
		(stroke
			(width 0.047498)
			(type default)
		)
		(layer "F.Cu")
	)
	(gr_line
		(start 3.192526 -97.498408)
		(end 3.19405 -97.499932)
		(stroke
			(width 0.047498)
			(type default)
		)
		(layer "F.Cu")
	)
	(gr_line
		(start 3.19405 -424.500294)
		(end 5.165852 -424.500294)
		(stroke
			(width 0.047498)
			(type default)
		)
		(layer "F.Cu")
	)
	(gr_line
		(start 3.19405 -423.500296)
		(end 4.96824 -423.500296)
		(stroke
			(width 0.047498)
			(type default)
		)
		(layer "F.Cu")
	)
	(gr_line
		(start 3.19405 -357.500174)
		(end 5.01142 -357.500174)
		(stroke
			(width 0.047498)
			(type default)
		)
		(layer "F.Cu")
	)
	(gr_line
		(start 3.19405 -135.500364)
		(end 5.164074 -135.500364)
		(stroke
			(width 0.047498)
			(type default)
		)
		(layer "F.Cu")
	)
	(gr_line
		(start 3.19405 -107.500166)
		(end 5.343144 -107.500166)
		(stroke
			(width 0.047498)
			(type default)
		)
		(layer "F.Cu")
	)
	(gr_line
		(start 3.19405 -101.499924)
		(end 4.815332 -101.499924)
		(stroke
			(width 0.047498)
			(type default)
		)
		(layer "F.Cu")
	)
	(gr_line
		(start 3.19405 -98.49993)
		(end 4.795774 -98.49993)
		(stroke
			(width 0.047498)
			(type default)
		)
		(layer "F.Cu")
	)
	(gr_line
		(start 3.19405 -97.499932)
		(end 4.837176 -97.499932)
		(stroke
			(width 0.047498)
			(type default)
		)
		(layer "F.Cu")
	)
	(gr_line
		(start 4.625086 -362.498894)
		(end 4.62661 -362.500418)
		(stroke
			(width 0.047498)
			(type default)
		)
		(layer "F.Cu")
	)
	(gr_line
		(start 4.625594 -416.498786)
		(end 4.627118 -416.50031)
		(stroke
			(width 0.047498)
			(type default)
		)
		(layer "F.Cu")
	)
	(gr_line
		(start 4.625594 -361.498896)
		(end 4.627118 -361.50042)
		(stroke
			(width 0.047498)
			(type default)
		)
		(layer "F.Cu")
	)
	(gr_arc
		(start 4.62661 -362.500418)
		(mid 4.948553 -362.436404)
		(end 5.221478 -362.254038)
		(stroke
			(width 0.047498)
			(type default)
		)
		(layer "F.Cu")
	)
	(gr_arc
		(start 4.627118 -416.50031)
		(mid 4.948646 -416.436323)
		(end 5.221224 -416.254184)
		(stroke
			(width 0.047498)
			(type default)
		)
		(layer "F.Cu")
	)
	(gr_line
		(start 4.632706 -352.498406)
		(end 4.63423 -352.49993)
		(stroke
			(width 0.047498)
			(type default)
		)
		(layer "F.Cu")
	)
	(gr_arc
		(start 4.63423 -352.49993)
		(mid 4.947241 -352.437713)
		(end 5.212588 -352.260408)
		(stroke
			(width 0.047498)
			(type default)
		)
		(layer "F.Cu")
	)
	(gr_line
		(start 4.64439 -158.498794)
		(end 4.645914 -158.500318)
		(stroke
			(width 0.047498)
			(type default)
		)
		(layer "F.Cu")
	)
	(gr_line
		(start 4.644644 -166.498778)
		(end 4.646168 -166.500302)
		(stroke
			(width 0.047498)
			(type default)
		)
		(layer "F.Cu")
	)
	(gr_line
		(start 4.644898 -366.498886)
		(end 4.646422 -366.50041)
		(stroke
			(width 0.047498)
			(type default)
		)
		(layer "F.Cu")
	)
	(gr_arc
		(start 4.645914 -158.500318)
		(mid 4.945586 -158.440707)
		(end 5.199634 -158.270956)
		(stroke
			(width 0.047498)
			(type default)
		)
		(layer "F.Cu")
	)
	(gr_arc
		(start 4.646168 -166.500302)
		(mid 4.945565 -166.440782)
		(end 5.19938 -166.271194)
		(stroke
			(width 0.047498)
			(type default)
		)
		(layer "F.Cu")
	)
	(gr_arc
		(start 4.646422 -366.50041)
		(mid 4.945829 -366.440905)
		(end 5.199634 -366.271302)
		(stroke
			(width 0.047498)
			(type default)
		)
		(layer "F.Cu")
	)
	(gr_line
		(start 4.647692 -365.498888)
		(end 4.649216 -365.500412)
		(stroke
			(width 0.047498)
			(type default)
		)
		(layer "F.Cu")
	)
	(gr_line
		(start 4.647946 -408.498802)
		(end 4.64947 -408.500326)
		(stroke
			(width 0.047498)
			(type default)
		)
		(layer "F.Cu")
	)
	(gr_line
		(start 4.648962 -162.498786)
		(end 4.650486 -162.50031)
		(stroke
			(width 0.047498)
			(type default)
		)
		(layer "F.Cu")
	)
	(gr_arc
		(start 4.64947 -408.500326)
		(mid 4.982955 -408.433963)
		(end 5.265674 -408.245056)
		(stroke
			(width 0.047498)
			(type default)
		)
		(layer "F.Cu")
	)
	(gr_arc
		(start 4.650486 -162.50031)
		(mid 4.94425 -162.44192)
		(end 5.193284 -162.27552)
		(stroke
			(width 0.047498)
			(type default)
		)
		(layer "F.Cu")
	)
	(gr_line
		(start 4.657344 -157.498796)
		(end 4.658868 -157.50032)
		(stroke
			(width 0.047498)
			(type default)
		)
		(layer "F.Cu")
	)
	(gr_line
		(start 4.66217 -415.498788)
		(end 4.663694 -415.500312)
		(stroke
			(width 0.047498)
			(type default)
		)
		(layer "F.Cu")
	)
	(gr_line
		(start 4.66598 -161.498788)
		(end 4.667504 -161.500312)
		(stroke
			(width 0.047498)
			(type default)
		)
		(layer "F.Cu")
	)
	(gr_line
		(start 4.666234 -412.498794)
		(end 4.667758 -412.500318)
		(stroke
			(width 0.047498)
			(type default)
		)
		(layer "F.Cu")
	)
	(gr_line
		(start 4.666234 -165.49878)
		(end 4.667758 -165.500304)
		(stroke
			(width 0.047498)
			(type default)
		)
		(layer "F.Cu")
	)
	(gr_arc
		(start 4.667758 -412.500318)
		(mid 4.997681 -412.434733)
		(end 5.277358 -412.247842)
		(stroke
			(width 0.047498)
			(type default)
		)
		(layer "F.Cu")
	)
	(gr_line
		(start 4.675886 -127.498856)
		(end 4.67741 -127.50038)
		(stroke
			(width 0.047498)
			(type default)
		)
		(layer "F.Cu")
	)
	(gr_line
		(start 4.67868 -382.498854)
		(end 4.680204 -382.500378)
		(stroke
			(width 0.047498)
			(type default)
		)
		(layer "F.Cu")
	)
	(gr_arc
		(start 4.680204 -382.500378)
		(mid 4.996097 -382.437517)
		(end 5.263896 -382.25857)
		(stroke
			(width 0.047498)
			(type default)
		)
		(layer "F.Cu")
	)
	(gr_line
		(start 4.68122 -116.498878)
		(end 4.682744 -116.500402)
		(stroke
			(width 0.047498)
			(type default)
		)
		(layer "F.Cu")
	)
	(gr_arc
		(start 4.682744 -116.500402)
		(mid 4.963162 -116.444608)
		(end 5.200904 -116.285772)
		(stroke
			(width 0.047498)
			(type default)
		)
		(layer "F.Cu")
	)
	(gr_line
		(start 4.684014 -348.498414)
		(end 4.685538 -348.499938)
		(stroke
			(width 0.047498)
			(type default)
		)
		(layer "F.Cu")
	)
	(gr_arc
		(start 4.685538 -348.499938)
		(mid 4.935022 -348.450247)
		(end 5.146548 -348.30893)
		(stroke
			(width 0.047498)
			(type default)
		)
		(layer "F.Cu")
	)
	(gr_line
		(start 4.688078 -358.498902)
		(end 4.689602 -358.500426)
		(stroke
			(width 0.047498)
			(type default)
		)
		(layer "F.Cu")
	)
	(gr_line
		(start 4.689094 -394.49883)
		(end 4.690618 -394.500354)
		(stroke
			(width 0.047498)
			(type default)
		)
		(layer "F.Cu")
	)
	(gr_arc
		(start 4.689602 -358.500426)
		(mid 4.963429 -358.445981)
		(end 5.19557 -358.290876)
		(stroke
			(width 0.047498)
			(type default)
		)
		(layer "F.Cu")
	)
	(gr_line
		(start 4.690872 -381.498856)
		(end 4.692396 -381.50038)
		(stroke
			(width 0.047498)
			(type default)
		)
		(layer "F.Cu")
	)
	(gr_line
		(start 4.691126 -145.49882)
		(end 4.69265 -145.500344)
		(stroke
			(width 0.047498)
			(type default)
		)
		(layer "F.Cu")
	)
	(gr_line
		(start 4.691888 -128.498854)
		(end 4.693412 -128.500378)
		(stroke
			(width 0.047498)
			(type default)
		)
		(layer "F.Cu")
	)
	(gr_arc
		(start 4.69265 -145.500344)
		(mid 4.97472 -145.444221)
		(end 5.213858 -145.284444)
		(stroke
			(width 0.047498)
			(type default)
		)
		(layer "F.Cu")
	)
	(gr_line
		(start 4.692904 -144.498822)
		(end 4.694428 -144.500346)
		(stroke
			(width 0.047498)
			(type default)
		)
		(layer "F.Cu")
	)
	(gr_line
		(start 4.692904 -115.49888)
		(end 4.694428 -115.500404)
		(stroke
			(width 0.047498)
			(type default)
		)
		(layer "F.Cu")
	)
	(gr_arc
		(start 4.693412 -128.500378)
		(mid 4.965169 -128.446287)
		(end 5.19557 -128.292352)
		(stroke
			(width 0.047498)
			(type default)
		)
		(layer "F.Cu")
	)
	(gr_line
		(start 4.705096 -411.498796)
		(end 4.70662 -411.50032)
		(stroke
			(width 0.047498)
			(type default)
		)
		(layer "F.Cu")
	)
	(gr_line
		(start 4.713732 -419.49878)
		(end 4.715256 -419.500304)
		(stroke
			(width 0.047498)
			(type default)
		)
		(layer "F.Cu")
	)
	(gr_line
		(start 4.71424 -420.498778)
		(end 4.715764 -420.500302)
		(stroke
			(width 0.047498)
			(type default)
		)
		(layer "F.Cu")
	)
	(gr_arc
		(start 4.715764 -420.500302)
		(mid 4.989169 -420.445872)
		(end 5.22097 -420.291006)
		(stroke
			(width 0.047498)
			(type default)
		)
		(layer "F.Cu")
	)
	(gr_line
		(start 4.72567 -102.498398)
		(end 4.727194 -102.499922)
		(stroke
			(width 0.047498)
			(type default)
		)
		(layer "F.Cu")
	)
	(gr_arc
		(start 4.727194 -102.499922)
		(mid 4.980125 -102.449637)
		(end 5.194554 -102.306374)
		(stroke
			(width 0.047498)
			(type default)
		)
		(layer "F.Cu")
	)
	(gr_line
		(start 4.735068 -407.498804)
		(end 4.736592 -407.500328)
		(stroke
			(width 0.047498)
			(type default)
		)
		(layer "F.Cu")
	)
	(gr_line
		(start 4.741926 -169.498772)
		(end 4.74345 -169.500296)
		(stroke
			(width 0.047498)
			(type default)
		)
		(layer "F.Cu")
	)
	(gr_line
		(start 4.752848 -378.498862)
		(end 4.754372 -378.500386)
		(stroke
			(width 0.047498)
			(type default)
		)
		(layer "F.Cu")
	)
	(gr_arc
		(start 4.754372 -378.500386)
		(mid 5.065044 -378.438623)
		(end 5.328412 -378.262642)
		(stroke
			(width 0.047498)
			(type default)
		)
		(layer "F.Cu")
	)
	(gr_line
		(start 4.760976 -377.498864)
		(end 4.7625 -377.500388)
		(stroke
			(width 0.047498)
			(type default)
		)
		(layer "F.Cu")
	)
	(gr_line
		(start 4.761738 -123.498864)
		(end 4.763262 -123.500388)
		(stroke
			(width 0.047498)
			(type default)
		)
		(layer "F.Cu")
	)
	(gr_arc
		(start 4.795774 -98.49993)
		(mid 5.066299 -98.446148)
		(end 5.295646 -98.29292)
		(stroke
			(width 0.047498)
			(type default)
		)
		(layer "F.Cu")
	)
	(gr_line
		(start 4.798568 -395.498828)
		(end 4.800092 -395.500352)
		(stroke
			(width 0.047498)
			(type default)
		)
		(layer "F.Cu")
	)
	(gr_line
		(start 4.799076 -173.498764)
		(end 4.8006 -173.500288)
		(stroke
			(width 0.047498)
			(type default)
		)
		(layer "F.Cu")
	)
	(gr_arc
		(start 4.800092 -395.500352)
		(mid 5.107042 -395.43927)
		(end 5.367274 -395.265402)
		(stroke
			(width 0.047498)
			(type default)
		)
		(layer "F.Cu")
	)
	(gr_arc
		(start 4.801616 -108.498894)
		(mid 5.021013 -108.455278)
		(end 5.207 -108.331)
		(stroke
			(width 0.047498)
			(type default)
		)
		(layer "F.Cu")
	)
	(gr_line
		(start 4.802632 -132.498846)
		(end 4.804156 -132.50037)
		(stroke
			(width 0.047498)
			(type default)
		)
		(layer "F.Cu")
	)
	(gr_arc
		(start 4.804156 -132.50037)
		(mid 5.104513 -132.440635)
		(end 5.359146 -132.2705)
		(stroke
			(width 0.047498)
			(type default)
		)
		(layer "F.Cu")
	)
	(gr_line
		(start 4.814824 -124.498862)
		(end 4.816348 -124.500386)
		(stroke
			(width 0.047498)
			(type default)
		)
		(layer "F.Cu")
	)
	(gr_arc
		(start 4.816348 -124.500386)
		(mid 5.093761 -124.445205)
		(end 5.32892 -124.288042)
		(stroke
			(width 0.047498)
			(type default)
		)
		(layer "F.Cu")
	)
	(gr_line
		(start 4.830572 -111.498888)
		(end 4.832096 -111.500412)
		(stroke
			(width 0.047498)
			(type default)
		)
		(layer "F.Cu")
	)
	(gr_line
		(start 4.83235 -347.498416)
		(end 4.833874 -347.49994)
		(stroke
			(width 0.047498)
			(type default)
		)
		(layer "F.Cu")
	)
	(gr_line
		(start 4.833112 -351.498408)
		(end 4.834636 -351.499932)
		(stroke
			(width 0.047498)
			(type default)
		)
		(layer "F.Cu")
	)
	(gr_line
		(start 4.835398 -112.498886)
		(end 4.836922 -112.50041)
		(stroke
			(width 0.047498)
			(type default)
		)
		(layer "F.Cu")
	)
	(gr_arc
		(start 4.836922 -112.50041)
		(mid 5.087802 -112.450508)
		(end 5.300472 -112.308386)
		(stroke
			(width 0.047498)
			(type default)
		)
		(layer "F.Cu")
	)
	(gr_line
		(start 4.86029 -136.498838)
		(end 4.861814 -136.500362)
		(stroke
			(width 0.047498)
			(type default)
		)
		(layer "F.Cu")
	)
	(gr_arc
		(start 4.861814 -136.500362)
		(mid 5.184022 -136.43624)
		(end 5.45719 -136.253728)
		(stroke
			(width 0.047498)
			(type default)
		)
		(layer "F.Cu")
	)
	(gr_line
		(start 4.877308 -369.49888)
		(end 4.878832 -369.500404)
		(stroke
			(width 0.047498)
			(type default)
		)
		(layer "F.Cu")
	)
	(gr_line
		(start 4.87934 -386.498846)
		(end 4.880864 -386.50037)
		(stroke
			(width 0.047498)
			(type default)
		)
		(layer "F.Cu")
	)
	(gr_arc
		(start 4.880864 -386.50037)
		(mid 5.116471 -386.453486)
		(end 5.31622 -386.32003)
		(stroke
			(width 0.047498)
			(type default)
		)
		(layer "F.Cu")
	)
	(gr_line
		(start 4.884674 -385.498848)
		(end 4.886198 -385.500372)
		(stroke
			(width 0.047498)
			(type default)
		)
		(layer "F.Cu")
	)
	(gr_line
		(start 4.887214 -373.498872)
		(end 4.888738 -373.500396)
		(stroke
			(width 0.047498)
			(type default)
		)
		(layer "F.Cu")
	)
	(gr_line
		(start 4.890516 -131.498848)
		(end 4.89204 -131.500372)
		(stroke
			(width 0.047498)
			(type default)
		)
		(layer "F.Cu")
	)
	(gr_line
		(start 4.89331 -370.498878)
		(end 4.894834 -370.500402)
		(stroke
			(width 0.047498)
			(type default)
		)
		(layer "F.Cu")
	)
	(gr_arc
		(start 4.894834 -370.500402)
		(mid 5.162341 -370.447208)
		(end 5.389118 -370.295678)
		(stroke
			(width 0.047498)
			(type default)
		)
		(layer "F.Cu")
	)
	(gr_line
		(start 4.921758 -374.49887)
		(end 4.923282 -374.500394)
		(stroke
			(width 0.047498)
			(type default)
		)
		(layer "F.Cu")
	)
	(gr_arc
		(start 4.923282 -374.500394)
		(mid 5.183093 -374.448695)
		(end 5.403342 -374.301512)
		(stroke
			(width 0.047498)
			(type default)
		)
		(layer "F.Cu")
	)
	(gr_line
		(start 4.930902 -119.498872)
		(end 4.932426 -119.500396)
		(stroke
			(width 0.047498)
			(type default)
		)
		(layer "F.Cu")
	)
	(gr_line
		(start 4.948428 -120.49887)
		(end 4.949952 -120.500394)
		(stroke
			(width 0.047498)
			(type default)
		)
		(layer "F.Cu")
	)
	(gr_arc
		(start 4.949952 -120.500394)
		(mid 5.15299 -120.459971)
		(end 5.32511 -120.344946)
		(stroke
			(width 0.047498)
			(type default)
		)
		(layer "F.Cu")
	)
	(gr_line
		(start 4.951476 -170.49877)
		(end 4.953 -170.500294)
		(stroke
			(width 0.047498)
			(type default)
		)
		(layer "F.Cu")
	)
	(gr_arc
		(start 4.953 -170.500294)
		(mid 5.058998 -170.479128)
		(end 5.148834 -170.419014)
		(stroke
			(width 0.047498)
			(type default)
		)
		(layer "F.Cu")
	)
	(gr_line
		(start 4.976876 -174.498762)
		(end 4.9784 -174.500286)
		(stroke
			(width 0.047498)
			(type default)
		)
		(layer "F.Cu")
	)
	(gr_arc
		(start 4.9784 -174.500286)
		(mid 5.070201 -174.4821)
		(end 5.148072 -174.430182)
		(stroke
			(width 0.047498)
			(type default)
		)
		(layer "F.Cu")
	)
	(gr_arc
		(start 5.023358 -111.526828)
		(mid 4.92863 -111.507085)
		(end 4.832096 -111.500412)
		(stroke
			(width 0.047498)
			(type default)
		)
		(layer "F.Cu")
	)
	(gr_arc
		(start 5.098542 -173.623732)
		(mid 4.961845 -173.532394)
		(end 4.8006 -173.500288)
		(stroke
			(width 0.047498)
			(type default)
		)
		(layer "F.Cu")
	)
	(gr_line
		(start 5.098542 -173.623732)
		(end 5.24256 -173.76775)
		(stroke
			(width 0.047498)
			(type default)
		)
		(layer "F.Cu")
	)
	(gr_arc
		(start 5.129784 -169.660316)
		(mid 4.952532 -169.54188)
		(end 4.74345 -169.500296)
		(stroke
			(width 0.047498)
			(type default)
		)
		(layer "F.Cu")
	)
	(gr_arc
		(start 5.129784 -169.660316)
		(mid 5.227634 -169.738934)
		(end 5.340096 -169.794682)
		(stroke
			(width 0.047498)
			(type default)
		)
		(layer "F.Cu")
	)
	(gr_line
		(start 5.148072 -174.430182)
		(end 5.2324 -174.3456)
		(stroke
			(width 0.047498)
			(type default)
		)
		(layer "F.Cu")
	)
	(gr_line
		(start 5.148834 -170.419014)
		(end 5.26415 -170.303952)
		(stroke
			(width 0.047498)
			(type default)
		)
		(layer "F.Cu")
	)
	(gr_arc
		(start 5.163566 -357.563166)
		(mid 5.093761 -357.516524)
		(end 5.01142 -357.500174)
		(stroke
			(width 0.047498)
			(type default)
		)
		(layer "F.Cu")
	)
	(gr_line
		(start 5.163566 -357.563166)
		(end 5.207 -357.6066)
		(stroke
			(width 0.047498)
			(type default)
		)
		(layer "F.Cu")
	)
	(gr_arc
		(start 5.165852 -424.500294)
		(mid 5.22427 -424.488674)
		(end 5.273802 -424.45559)
		(stroke
			(width 0.047498)
			(type default)
		)
		(layer "F.Cu")
	)
	(gr_arc
		(start 5.192014 -165.717474)
		(mid 4.951483 -165.556757)
		(end 4.667758 -165.500304)
		(stroke
			(width 0.047498)
			(type default)
		)
		(layer "F.Cu")
	)
	(gr_arc
		(start 5.192014 -165.717474)
		(mid 5.317162 -165.801147)
		(end 5.46481 -165.830504)
		(stroke
			(width 0.047498)
			(type default)
		)
		(layer "F.Cu")
	)
	(gr_arc
		(start 5.19303 -161.71799)
		(mid 4.951917 -161.556883)
		(end 4.667504 -161.500312)
		(stroke
			(width 0.047498)
			(type default)
		)
		(layer "F.Cu")
	)
	(gr_arc
		(start 5.19303 -161.71799)
		(mid 5.317375 -161.801064)
		(end 5.464048 -161.830258)
		(stroke
			(width 0.047498)
			(type default)
		)
		(layer "F.Cu")
	)
	(gr_arc
		(start 5.194808 -111.653066)
		(mid 5.126614 -111.566146)
		(end 5.023358 -111.526828)
		(stroke
			(width 0.047498)
			(type default)
		)
		(layer "F.Cu")
	)
	(gr_arc
		(start 5.194808 -111.653066)
		(mid 5.28974 -111.771521)
		(end 5.434838 -111.816134)
		(stroke
			(width 0.047498)
			(type default)
		)
		(layer "F.Cu")
	)
	(gr_line
		(start 5.19557 -358.290876)
		(end 5.19938 -358.286812)
		(stroke
			(width 0.047498)
			(type default)
		)
		(layer "F.Cu")
	)
	(gr_arc
		(start 5.197856 -415.721546)
		(mid 4.95278 -415.557792)
		(end 4.663694 -415.500312)
		(stroke
			(width 0.047498)
			(type default)
		)
		(layer "F.Cu")
	)
	(gr_arc
		(start 5.197856 -415.721546)
		(mid 5.318599 -415.802174)
		(end 5.461 -415.830512)
		(stroke
			(width 0.047498)
			(type default)
		)
		(layer "F.Cu")
	)
	(gr_arc
		(start 5.203444 -157.725872)
		(mid 4.95359 -157.558925)
		(end 4.658868 -157.50032)
		(stroke
			(width 0.047498)
			(type default)
		)
		(layer "F.Cu")
	)
	(gr_arc
		(start 5.203444 -157.725872)
		(mid 5.31941 -157.803307)
		(end 5.456174 -157.83052)
		(stroke
			(width 0.047498)
			(type default)
		)
		(layer "F.Cu")
	)
	(gr_arc
		(start 5.205222 -115.711986)
		(mid 4.970868 -115.555395)
		(end 4.694428 -115.500404)
		(stroke
			(width 0.047498)
			(type default)
		)
		(layer "F.Cu")
	)
	(gr_arc
		(start 5.205222 -115.711986)
		(mid 5.336548 -115.799773)
		(end 5.49148 -115.830604)
		(stroke
			(width 0.047498)
			(type default)
		)
		(layer "F.Cu")
	)
	(gr_line
		(start 5.207 -357.6066)
		(end 5.371846 -357.771192)
		(stroke
			(width 0.047498)
			(type default)
		)
		(layer "F.Cu")
	)
	(gr_line
		(start 5.207 -108.331)
		(end 5.228082 -108.309918)
		(stroke
			(width 0.047498)
			(type default)
		)
		(layer "F.Cu")
	)
	(gr_arc
		(start 5.21589 -365.735108)
		(mid 4.955898 -365.561387)
		(end 4.649216 -365.500412)
		(stroke
			(width 0.047498)
			(type default)
		)
		(layer "F.Cu")
	)
	(gr_arc
		(start 5.21589 -365.735108)
		(mid 5.32171 -365.8058)
		(end 5.446522 -365.830612)
		(stroke
			(width 0.047498)
			(type default)
		)
		(layer "F.Cu")
	)
	(gr_line
		(start 5.22097 -420.291006)
		(end 5.221224 -420.291006)
		(stroke
			(width 0.047498)
			(type default)
		)
		(layer "F.Cu")
	)
	(gr_arc
		(start 5.228082 -108.309918)
		(mid 5.272338 -108.255242)
		(end 5.304282 -108.19257)
		(stroke
			(width 0.047498)
			(type default)
		)
		(layer "F.Cu")
	)
	(gr_arc
		(start 5.22859 -127.728726)
		(mid 4.975706 -127.559755)
		(end 4.67741 -127.50038)
		(stroke
			(width 0.047498)
			(type default)
		)
		(layer "F.Cu")
	)
	(gr_arc
		(start 5.22859 -127.728726)
		(mid 5.314439 -127.791579)
		(end 5.41528 -127.8255)
		(stroke
			(width 0.047498)
			(type default)
		)
		(layer "F.Cu")
	)
	(gr_line
		(start 5.2324 -174.3456)
		(end 5.319522 -174.258732)
		(stroke
			(width 0.047498)
			(type default)
		)
		(layer "F.Cu")
	)
	(gr_arc
		(start 5.239512 -394.727684)
		(mid 4.987677 -394.559413)
		(end 4.690618 -394.500354)
		(stroke
			(width 0.047498)
			(type default)
		)
		(layer "F.Cu")
	)
	(gr_arc
		(start 5.239512 -394.727684)
		(mid 5.35349 -394.803826)
		(end 5.487924 -394.830554)
		(stroke
			(width 0.047498)
			(type default)
		)
		(layer "F.Cu")
	)
	(gr_arc
		(start 5.241036 -361.754674)
		(mid 4.959368 -361.566469)
		(end 4.627118 -361.50042)
		(stroke
			(width 0.047498)
			(type default)
		)
		(layer "F.Cu")
	)
	(gr_arc
		(start 5.241036 -361.754674)
		(mid 5.325181 -361.810868)
		(end 5.424424 -361.83062)
		(stroke
			(width 0.047498)
			(type default)
		)
		(layer "F.Cu")
	)
	(gr_arc
		(start 5.242052 -419.71849)
		(mid 5.000356 -419.556994)
		(end 4.715256 -419.500304)
		(stroke
			(width 0.047498)
			(type default)
		)
		(layer "F.Cu")
	)
	(gr_arc
		(start 5.242052 -419.71849)
		(mid 5.366171 -419.801393)
		(end 5.512562 -419.830504)
		(stroke
			(width 0.047498)
			(type default)
		)
		(layer "F.Cu")
	)
	(gr_arc
		(start 5.24256 -173.76775)
		(mid 5.30076 -173.813527)
		(end 5.368036 -173.844458)
		(stroke
			(width 0.047498)
			(type default)
		)
		(layer "F.Cu")
	)
	(gr_arc
		(start 5.252974 -407.714196)
		(mid 5.016056 -407.555892)
		(end 4.736592 -407.500328)
		(stroke
			(width 0.047498)
			(type default)
		)
		(layer "F.Cu")
	)
	(gr_arc
		(start 5.252974 -407.714196)
		(mid 5.358426 -407.784709)
		(end 5.482844 -407.809446)
		(stroke
			(width 0.047498)
			(type default)
		)
		(layer "F.Cu")
	)
	(gr_arc
		(start 5.253482 -411.726888)
		(mid 5.00258 -411.55924)
		(end 4.70662 -411.50032)
		(stroke
			(width 0.047498)
			(type default)
		)
		(layer "F.Cu")
	)
	(gr_arc
		(start 5.253482 -411.726888)
		(mid 5.368268 -411.803597)
		(end 5.503672 -411.83052)
		(stroke
			(width 0.047498)
			(type default)
		)
		(layer "F.Cu")
	)
	(gr_arc
		(start 5.260594 -123.706382)
		(mid 5.032416 -123.553918)
		(end 4.763262 -123.500388)
		(stroke
			(width 0.047498)
			(type default)
		)
		(layer "F.Cu")
	)
	(gr_arc
		(start 5.260594 -123.706382)
		(mid 5.403821 -123.802069)
		(end 5.57276 -123.835668)
		(stroke
			(width 0.047498)
			(type default)
		)
		(layer "F.Cu")
	)
	(gr_arc
		(start 5.262626 -351.677224)
		(mid 5.066263 -351.546018)
		(end 4.834636 -351.499932)
		(stroke
			(width 0.047498)
			(type default)
		)
		(layer "F.Cu")
	)
	(gr_line
		(start 5.262626 -351.677224)
		(end 5.347208 -351.761806)
		(stroke
			(width 0.047498)
			(type default)
		)
		(layer "F.Cu")
	)
	(gr_arc
		(start 5.262626 -347.677486)
		(mid 5.065913 -347.546047)
		(end 4.833874 -347.49994)
		(stroke
			(width 0.047498)
			(type default)
		)
		(layer "F.Cu")
	)
	(gr_line
		(start 5.262626 -347.677486)
		(end 5.31114 -347.726254)
		(stroke
			(width 0.047498)
			(type default)
		)
		(layer "F.Cu")
	)
	(gr_line
		(start 5.265674 -408.245056)
		(end 5.265928 -408.244802)
		(stroke
			(width 0.047498)
			(type default)
		)
		(layer "F.Cu")
	)
	(gr_arc
		(start 5.266182 -423.62374)
		(mid 5.129485 -423.532402)
		(end 4.96824 -423.500296)
		(stroke
			(width 0.047498)
			(type default)
		)
		(layer "F.Cu")
	)
	(gr_line
		(start 5.266182 -423.62374)
		(end 5.470144 -423.827702)
		(stroke
			(width 0.047498)
			(type default)
		)
		(layer "F.Cu")
	)
	(gr_arc
		(start 5.270754 -381.739902)
		(mid 5.005401 -381.562599)
		(end 4.692396 -381.50038)
		(stroke
			(width 0.047498)
			(type default)
		)
		(layer "F.Cu")
	)
	(gr_arc
		(start 5.270754 -381.739902)
		(mid 5.371211 -381.807011)
		(end 5.489702 -381.83058)
		(stroke
			(width 0.047498)
			(type default)
		)
		(layer "F.Cu")
	)
	(gr_line
		(start 5.273802 -424.45559)
		(end 5.384292 -424.3451)
		(stroke
			(width 0.047498)
			(type default)
		)
		(layer "F.Cu")
	)
	(gr_arc
		(start 5.278628 -369.666012)
		(mid 5.0952 -369.543449)
		(end 4.878832 -369.500404)
		(stroke
			(width 0.047498)
			(type default)
		)
		(layer "F.Cu")
	)
	(gr_arc
		(start 5.278628 -369.666012)
		(mid 5.374982 -369.743683)
		(end 5.485638 -369.799108)
		(stroke
			(width 0.047498)
			(type default)
		)
		(layer "F.Cu")
	)
	(gr_arc
		(start 5.289804 -385.667504)
		(mid 5.104628 -385.543773)
		(end 4.886198 -385.500372)
		(stroke
			(width 0.047498)
			(type default)
		)
		(layer "F.Cu")
	)
	(gr_arc
		(start 5.289804 -385.667504)
		(mid 5.420891 -385.764687)
		(end 5.574538 -385.81965)
		(stroke
			(width 0.047498)
			(type default)
		)
		(layer "F.Cu")
	)
	(gr_arc
		(start 5.293614 -101.698044)
		(mid 5.074176 -101.55142)
		(end 4.815332 -101.499924)
		(stroke
			(width 0.047498)
			(type default)
		)
		(layer "F.Cu")
	)
	(gr_line
		(start 5.293614 -101.698044)
		(end 5.293868 -101.698044)
		(stroke
			(width 0.047498)
			(type default)
		)
		(layer "F.Cu")
	)
	(gr_arc
		(start 5.293868 -101.698044)
		(mid 5.439998 -101.795744)
		(end 5.612384 -101.830124)
		(stroke
			(width 0.047498)
			(type default)
		)
		(layer "F.Cu")
	)
	(gr_arc
		(start 5.29971 -377.722892)
		(mid 5.053236 -377.558203)
		(end 4.7625 -377.500388)
		(stroke
			(width 0.047498)
			(type default)
		)
		(layer "F.Cu")
	)
	(gr_arc
		(start 5.29971 -377.722892)
		(mid 5.426624 -377.807666)
		(end 5.576316 -377.837446)
		(stroke
			(width 0.047498)
			(type default)
		)
		(layer "F.Cu")
	)
	(gr_arc
		(start 5.301488 -119.653304)
		(mid 5.132161 -119.540163)
		(end 4.932426 -119.500396)
		(stroke
			(width 0.047498)
			(type default)
		)
		(layer "F.Cu")
	)
	(gr_line
		(start 5.301488 -119.653304)
		(end 5.377688 -119.729504)
		(stroke
			(width 0.047498)
			(type default)
		)
		(layer "F.Cu")
	)
	(gr_arc
		(start 5.302758 -144.752314)
		(mid 5.023654 -144.565823)
		(end 4.694428 -144.500346)
		(stroke
			(width 0.047498)
			(type default)
		)
		(layer "F.Cu")
	)
	(gr_arc
		(start 5.302758 -144.752314)
		(mid 5.389476 -144.810197)
		(end 5.491734 -144.830546)
		(stroke
			(width 0.047498)
			(type default)
		)
		(layer "F.Cu")
	)
	(gr_line
		(start 5.304282 -108.182918)
		(end 5.304282 -108.19257)
		(stroke
			(width 0.047498)
			(type default)
		)
		(layer "F.Cu")
	)
	(gr_arc
		(start 5.31114 -347.726254)
		(mid 5.426406 -347.803195)
		(end 5.562346 -347.83014)
		(stroke
			(width 0.047498)
			(type default)
		)
		(layer "F.Cu")
	)
	(gr_arc
		(start 5.316474 -131.67614)
		(mid 5.121742 -131.546024)
		(end 4.89204 -131.500372)
		(stroke
			(width 0.047498)
			(type default)
		)
		(layer "F.Cu")
	)
	(gr_arc
		(start 5.334 -373.6848)
		(mid 5.129712 -373.548299)
		(end 4.888738 -373.500396)
		(stroke
			(width 0.047498)
			(type default)
		)
		(layer "F.Cu")
	)
	(gr_arc
		(start 5.334 -373.6848)
		(mid 5.379646 -373.723749)
		(end 5.430774 -373.755158)
		(stroke
			(width 0.047498)
			(type default)
		)
		(layer "F.Cu")
	)
	(gr_line
		(start 5.340096 -169.794682)
		(end 5.341112 -169.794936)
		(stroke
			(width 0.047498)
			(type default)
		)
		(layer "F.Cu")
	)
	(gr_arc
		(start 5.341112 -169.794936)
		(mid 5.439236 -169.821524)
		(end 5.540502 -169.830496)
		(stroke
			(width 0.047498)
			(type default)
		)
		(layer "F.Cu")
	)
	(gr_arc
		(start 5.347208 -351.761806)
		(mid 5.422608 -351.812178)
		(end 5.511546 -351.829878)
		(stroke
			(width 0.047498)
			(type default)
		)
		(layer "F.Cu")
	)
	(gr_arc
		(start 5.351018 -97.712784)
		(mid 5.115265 -97.555259)
		(end 4.837176 -97.499932)
		(stroke
			(width 0.047498)
			(type default)
		)
		(layer "F.Cu")
	)
	(gr_line
		(start 5.351018 -97.712784)
		(end 5.351272 -97.712784)
		(stroke
			(width 0.047498)
			(type default)
		)
		(layer "F.Cu")
	)
	(gr_arc
		(start 5.351272 -97.712784)
		(mid 5.481068 -97.799619)
		(end 5.634228 -97.830132)
		(stroke
			(width 0.047498)
			(type default)
		)
		(layer "F.Cu")
	)
	(gr_arc
		(start 5.352288 -128.190498)
		(mid 5.268597 -128.233214)
		(end 5.19557 -128.292352)
		(stroke
			(width 0.047498)
			(type default)
		)
		(layer "F.Cu")
	)
	(gr_arc
		(start 5.363972 -108.0389)
		(mid 5.319821 -108.104976)
		(end 5.304282 -108.182918)
		(stroke
			(width 0.047498)
			(type default)
		)
		(layer "F.Cu")
	)
	(gr_arc
		(start 5.368036 -173.844458)
		(mid 5.416312 -173.85618)
		(end 5.465826 -173.860206)
		(stroke
			(width 0.047498)
			(type default)
		)
		(layer "F.Cu")
	)
	(gr_arc
		(start 5.371846 -357.771192)
		(mid 5.428473 -357.809094)
		(end 5.49529 -357.8225)
		(stroke
			(width 0.047498)
			(type default)
		)
		(layer "F.Cu")
	)
	(gr_arc
		(start 5.377688 -119.729504)
		(mid 5.489684 -119.804317)
		(end 5.621782 -119.830596)
		(stroke
			(width 0.047498)
			(type default)
		)
		(layer "F.Cu")
	)
	(gr_line
		(start 5.384292 -424.3451)
		(end 5.384546 -424.3451)
		(stroke
			(width 0.047498)
			(type default)
		)
		(layer "F.Cu")
	)
	(gr_arc
		(start 5.384546 -131.7371)
		(mid 5.351357 -131.705674)
		(end 5.316474 -131.67614)
		(stroke
			(width 0.047498)
			(type default)
		)
		(layer "F.Cu")
	)
	(gr_arc
		(start 5.384546 -131.7371)
		(mid 5.467875 -131.79696)
		(end 5.565902 -131.82727)
		(stroke
			(width 0.047498)
			(type default)
		)
		(layer "F.Cu")
	)
	(gr_arc
		(start 5.38607 -358.173274)
		(mid 5.285892 -358.218806)
		(end 5.19938 -358.286812)
		(stroke
			(width 0.047498)
			(type default)
		)
		(layer "F.Cu")
	)
	(gr_arc
		(start 5.41528 -127.8255)
		(mid 5.444762 -127.829307)
		(end 5.474462 -127.83058)
		(stroke
			(width 0.047498)
			(type default)
		)
		(layer "F.Cu")
	)
	(gr_line
		(start 5.430774 -373.755158)
		(end 5.486908 -373.784114)
		(stroke
			(width 0.047498)
			(type default)
		)
		(layer "F.Cu")
	)
	(gr_arc
		(start 5.434838 -111.816134)
		(mid 5.535416 -111.827001)
		(end 5.636514 -111.830612)
		(stroke
			(width 0.047498)
			(type default)
		)
		(layer "F.Cu")
	)
	(gr_arc
		(start 5.43941 -112.20958)
		(mid 5.365724 -112.253056)
		(end 5.300472 -112.308386)
		(stroke
			(width 0.047498)
			(type default)
		)
		(layer "F.Cu")
	)
	(gr_arc
		(start 5.442204 -358.159558)
		(mid 5.413922 -358.165537)
		(end 5.38607 -358.173274)
		(stroke
			(width 0.047498)
			(type default)
		)
		(layer "F.Cu")
	)
	(gr_arc
		(start 5.446522 -362.16082)
		(mid 5.324728 -362.185046)
		(end 5.221478 -362.254038)
		(stroke
			(width 0.047498)
			(type default)
		)
		(layer "F.Cu")
	)
	(gr_arc
		(start 5.446776 -416.160712)
		(mid 5.324691 -416.184996)
		(end 5.221224 -416.254184)
		(stroke
			(width 0.047498)
			(type default)
		)
		(layer "F.Cu")
	)
	(gr_arc
		(start 5.454904 -352.160078)
		(mid 5.323779 -352.18616)
		(end 5.212588 -352.260408)
		(stroke
			(width 0.047498)
			(type default)
		)
		(layer "F.Cu")
	)
	(gr_arc
		(start 5.459476 -112.20069)
		(mid 5.449394 -112.205024)
		(end 5.43941 -112.20958)
		(stroke
			(width 0.047498)
			(type default)
		)
		(layer "F.Cu")
	)
	(gr_arc
		(start 5.460746 -135.6233)
		(mid 5.324632 -135.532351)
		(end 5.164074 -135.500364)
		(stroke
			(width 0.047498)
			(type default)
		)
		(layer "F.Cu")
	)
	(gr_arc
		(start 5.460746 -135.6233)
		(mid 5.690325 -135.776685)
		(end 5.961126 -135.830564)
		(stroke
			(width 0.047498)
			(type default)
		)
		(layer "F.Cu")
	)
	(gr_arc
		(start 5.465826 -158.16072)
		(mid 5.321773 -158.189374)
		(end 5.199634 -158.270956)
		(stroke
			(width 0.047498)
			(type default)
		)
		(layer "F.Cu")
	)
	(gr_arc
		(start 5.46608 -166.160704)
		(mid 5.321736 -166.189416)
		(end 5.19938 -166.271194)
		(stroke
			(width 0.047498)
			(type default)
		)
		(layer "F.Cu")
	)
	(gr_arc
		(start 5.466334 -366.160812)
		(mid 5.32199 -366.189524)
		(end 5.199634 -366.271302)
		(stroke
			(width 0.047498)
			(type default)
		)
		(layer "F.Cu")
	)
	(gr_arc
		(start 5.470144 -423.827702)
		(mid 5.552075 -423.889777)
		(end 5.64769 -423.927524)
		(stroke
			(width 0.047498)
			(type default)
		)
		(layer "F.Cu")
	)
	(gr_arc
		(start 5.47116 -162.160458)
		(mid 5.320789 -162.190369)
		(end 5.193284 -162.27552)
		(stroke
			(width 0.047498)
			(type default)
		)
		(layer "F.Cu")
	)
	(gr_arc
		(start 5.484114 -174.190406)
		(mid 5.395034 -174.208219)
		(end 5.319522 -174.258732)
		(stroke
			(width 0.047498)
			(type default)
		)
		(layer "F.Cu")
	)
	(gr_line
		(start 5.485638 -369.799108)
		(end 5.486908 -369.799616)
		(stroke
			(width 0.047498)
			(type default)
		)
		(layer "F.Cu")
	)
	(gr_arc
		(start 5.486908 -373.784114)
		(mid 5.582869 -373.819762)
		(end 5.68452 -373.831866)
		(stroke
			(width 0.047498)
			(type default)
		)
		(layer "F.Cu")
	)
	(gr_arc
		(start 5.486908 -369.799616)
		(mid 5.58686 -369.827122)
		(end 5.690108 -369.836446)
		(stroke
			(width 0.047498)
			(type default)
		)
		(layer "F.Cu")
	)
	(gr_arc
		(start 5.48767 -412.16072)
		(mid 5.373847 -412.183361)
		(end 5.277358 -412.247842)
		(stroke
			(width 0.047498)
			(type default)
		)
		(layer "F.Cu")
	)
	(gr_arc
		(start 5.49529 -357.8225)
		(mid 5.580822 -357.805491)
		(end 5.653278 -357.756968)
		(stroke
			(width 0.047498)
			(type default)
		)
		(layer "F.Cu")
	)
	(gr_arc
		(start 5.497068 -107.56392)
		(mid 5.426447 -107.516733)
		(end 5.343144 -107.500166)
		(stroke
			(width 0.047498)
			(type default)
		)
		(layer "F.Cu")
	)
	(gr_arc
		(start 5.497068 -107.56392)
		(mid 5.529465 -107.590901)
		(end 5.566156 -107.611672)
		(stroke
			(width 0.047498)
			(type default)
		)
		(layer "F.Cu")
	)
	(gr_arc
		(start 5.499862 -382.16078)
		(mid 5.372139 -382.186186)
		(end 5.263896 -382.25857)
		(stroke
			(width 0.047498)
			(type default)
		)
		(layer "F.Cu")
	)
	(gr_arc
		(start 5.500624 -408.140154)
		(mid 5.373589 -408.170748)
		(end 5.265928 -408.244802)
		(stroke
			(width 0.047498)
			(type default)
		)
		(layer "F.Cu")
	)
	(gr_arc
		(start 5.500878 -112.18545)
		(mid 5.480008 -112.192612)
		(end 5.459476 -112.20069)
		(stroke
			(width 0.047498)
			(type default)
		)
		(layer "F.Cu")
	)
	(gr_arc
		(start 5.502656 -116.160804)
		(mid 5.339357 -116.193286)
		(end 5.200904 -116.285772)
		(stroke
			(width 0.047498)
			(type default)
		)
		(layer "F.Cu")
	)
	(gr_arc
		(start 5.505196 -348.16034)
		(mid 5.311084 -348.198951)
		(end 5.146548 -348.30893)
		(stroke
			(width 0.047498)
			(type default)
		)
		(layer "F.Cu")
	)
	(gr_arc
		(start 5.512562 -145.160746)
		(mid 5.350916 -145.192899)
		(end 5.213858 -145.284444)
		(stroke
			(width 0.047498)
			(type default)
		)
		(layer "F.Cu")
	)
	(gr_arc
		(start 5.513324 -128.16078)
		(mid 5.431445 -128.168256)
		(end 5.352288 -128.190498)
		(stroke
			(width 0.047498)
			(type default)
		)
		(layer "F.Cu")
	)
	(gr_arc
		(start 5.520182 -408.139646)
		(mid 5.510399 -408.139765)
		(end 5.500624 -408.140154)
		(stroke
			(width 0.047498)
			(type default)
		)
		(layer "F.Cu")
	)
	(gr_arc
		(start 5.524754 -358.152192)
		(mid 5.483313 -358.154017)
		(end 5.442204 -358.159558)
		(stroke
			(width 0.047498)
			(type default)
		)
		(layer "F.Cu")
	)
	(gr_line
		(start 5.524754 -358.152192)
		(end 5.615432 -358.152192)
		(stroke
			(width 0.047498)
			(type default)
		)
		(layer "F.Cu")
	)
	(gr_arc
		(start 5.52958 -112.176814)
		(mid 5.515164 -112.180917)
		(end 5.500878 -112.18545)
		(stroke
			(width 0.047498)
			(type default)
		)
		(layer "F.Cu")
	)
	(gr_arc
		(start 5.535422 -420.160704)
		(mid 5.365373 -420.194622)
		(end 5.221224 -420.291006)
		(stroke
			(width 0.047498)
			(type default)
		)
		(layer "F.Cu")
	)
	(gr_arc
		(start 5.547106 -102.160324)
		(mid 5.356299 -102.198278)
		(end 5.194554 -102.306374)
		(stroke
			(width 0.047498)
			(type default)
		)
		(layer "F.Cu")
	)
	(gr_arc
		(start 5.557774 -378.167646)
		(mid 5.433648 -378.192336)
		(end 5.328412 -378.262642)
		(stroke
			(width 0.047498)
			(type default)
		)
		(layer "F.Cu")
	)
	(gr_arc
		(start 5.565902 -131.82727)
		(mid 5.587942 -131.829696)
		(end 5.610098 -131.830572)
		(stroke
			(width 0.047498)
			(type default)
		)
		(layer "F.Cu")
	)
	(gr_arc
		(start 5.566156 -107.611672)
		(mid 5.598358 -107.623487)
		(end 5.631942 -107.630468)
		(stroke
			(width 0.047498)
			(type default)
		)
		(layer "F.Cu")
	)
	(gr_arc
		(start 5.569204 -424.268646)
		(mid 5.469268 -424.288497)
		(end 5.384546 -424.3451)
		(stroke
			(width 0.047498)
			(type default)
		)
		(layer "F.Cu")
	)
	(gr_arc
		(start 5.574538 -385.81965)
		(mid 5.628751 -385.827803)
		(end 5.683504 -385.830572)
		(stroke
			(width 0.047498)
			(type default)
		)
		(layer "F.Cu")
	)
	(gr_arc
		(start 5.588 -107.9627)
		(mid 5.469667 -107.982227)
		(end 5.363972 -108.0389)
		(stroke
			(width 0.047498)
			(type default)
		)
		(layer "F.Cu")
	)
	(gr_arc
		(start 5.610098 -170.160696)
		(mid 5.422888 -170.197934)
		(end 5.26415 -170.303952)
		(stroke
			(width 0.047498)
			(type default)
		)
		(layer "F.Cu")
	)
	(gr_arc
		(start 5.615432 -358.152192)
		(mid 5.694481 -358.136515)
		(end 5.761482 -358.09174)
		(stroke
			(width 0.047498)
			(type default)
		)
		(layer "F.Cu")
	)
	(gr_arc
		(start 5.615686 -98.160332)
		(mid 5.442473 -98.194786)
		(end 5.295646 -98.29292)
		(stroke
			(width 0.047498)
			(type default)
		)
		(layer "F.Cu")
	)
	(gr_arc
		(start 5.620004 -395.160754)
		(mid 5.483241 -395.187958)
		(end 5.367274 -395.265402)
		(stroke
			(width 0.047498)
			(type default)
		)
		(layer "F.Cu")
	)
	(gr_arc
		(start 5.623814 -124.165868)
		(mid 5.464218 -124.197634)
		(end 5.32892 -124.288042)
		(stroke
			(width 0.047498)
			(type default)
		)
		(layer "F.Cu")
	)
	(gr_arc
		(start 5.624068 -132.160772)
		(mid 5.480696 -132.189291)
		(end 5.359146 -132.2705)
		(stroke
			(width 0.047498)
			(type default)
		)
		(layer "F.Cu")
	)
	(gr_arc
		(start 5.631942 -107.630468)
		(mid 5.647275 -107.631991)
		(end 5.662676 -107.6325)
		(stroke
			(width 0.047498)
			(type default)
		)
		(layer "F.Cu")
	)
	(gr_line
		(start 5.6388 -424.268646)
		(end 5.969 -424.268646)
		(stroke
			(width 0.047498)
			(type default)
		)
		(layer "F.Cu")
	)
	(gr_line
		(start 5.643626 -111.830612)
		(end 5.669534 -111.830612)
		(stroke
			(width 0.047498)
			(type default)
		)
		(layer "F.Cu")
	)
	(gr_arc
		(start 5.644642 -112.160558)
		(mid 5.586639 -112.165349)
		(end 5.52958 -112.176814)
		(stroke
			(width 0.047498)
			(type default)
		)
		(layer "F.Cu")
	)
	(gr_arc
		(start 5.64769 -423.927524)
		(mid 5.692319 -423.935695)
		(end 5.737606 -423.938446)
		(stroke
			(width 0.047498)
			(type default)
		)
		(layer "F.Cu")
	)
	(gr_arc
		(start 5.65658 -112.160558)
		(mid 5.650611 -112.160524)
		(end 5.644642 -112.160558)
		(stroke
			(width 0.047498)
			(type default)
		)
		(layer "F.Cu")
	)
	(gr_line
		(start 5.65658 -112.160558)
		(end 5.656834 -112.160812)
		(stroke
			(width 0.047498)
			(type default)
		)
		(layer "F.Cu")
	)
	(gr_arc
		(start 5.681726 -136.160764)
		(mid 5.560224 -136.184932)
		(end 5.45719 -136.253728)
		(stroke
			(width 0.047498)
			(type default)
		)
		(layer "F.Cu")
	)
	(gr_arc
		(start 5.700776 -386.160772)
		(mid 5.492667 -386.202167)
		(end 5.31622 -386.32003)
		(stroke
			(width 0.047498)
			(type default)
		)
		(layer "F.Cu")
	)
	(gr_arc
		(start 5.716016 -370.168424)
		(mid 5.543196 -370.207972)
		(end 5.389118 -370.295678)
		(stroke
			(width 0.047498)
			(type default)
		)
		(layer "F.Cu")
	)
	(gr_arc
		(start 5.739638 -374.162066)
		(mid 5.557608 -374.19831)
		(end 5.403342 -374.301512)
		(stroke
			(width 0.047498)
			(type default)
		)
		(layer "F.Cu")
	)
	(gr_arc
		(start 5.740146 -374.162066)
		(mid 5.739892 -374.162066)
		(end 5.739638 -374.162066)
		(stroke
			(width 0.047498)
			(type default)
		)
		(layer "F.Cu")
	)
	(gr_arc
		(start 5.763514 -370.166646)
		(mid 5.739748 -370.167071)
		(end 5.716016 -370.168424)
		(stroke
			(width 0.047498)
			(type default)
		)
		(layer "F.Cu")
	)
	(gr_arc
		(start 5.76961 -120.160796)
		(mid 5.529036 -120.208649)
		(end 5.32511 -120.344946)
		(stroke
			(width 0.047498)
			(type default)
		)
		(layer "F.Cu")
	)
	(gr_arc
		(start 5.801614 -357.6955)
		(mid 5.721325 -357.71147)
		(end 5.653278 -357.756968)
		(stroke
			(width 0.047498)
			(type default)
		)
		(layer "F.Cu")
	)
	(gr_arc
		(start 5.901182 -347.83014)
		(mid 6.220778 -347.766567)
		(end 6.491732 -347.585538)
		(stroke
			(width 0.047498)
			(type default)
		)
		(layer "F.Cu")
	)
	(gr_arc
		(start 5.920994 -358.0257)
		(mid 5.834679 -358.042869)
		(end 5.761482 -358.09174)
		(stroke
			(width 0.047498)
			(type default)
		)
		(layer "F.Cu")
	)
	(gr_line
		(start 5.969 -423.938446)
		(end 5.969 -423.9387)
		(stroke
			(width 0.047498)
			(type default)
		)
		(layer "F.Cu")
	)
	(gr_arc
		(start 6.1214 -161.830258)
		(mid 6.424364 -161.769968)
		(end 6.681216 -161.598356)
		(stroke
			(width 0.047498)
			(type default)
		)
		(layer "F.Cu")
	)
	(gr_arc
		(start 6.214364 -132.277104)
		(mid 6.11229 -132.190705)
		(end 5.981954 -132.160772)
		(stroke
			(width 0.047498)
			(type default)
		)
		(layer "F.Cu")
	)
	(gr_arc
		(start 6.214364 -132.277104)
		(mid 6.316464 -132.363379)
		(end 6.446774 -132.393182)
		(stroke
			(width 0.047498)
			(type default)
		)
		(layer "F.Cu")
	)
	(gr_arc
		(start 6.227572 -165.830504)
		(mid 6.532604 -165.769859)
		(end 6.791198 -165.597078)
		(stroke
			(width 0.047498)
			(type default)
		)
		(layer "F.Cu")
	)
	(gr_arc
		(start 6.262878 -157.83052)
		(mid 6.653561 -157.752869)
		(end 6.984746 -157.531562)
		(stroke
			(width 0.047498)
			(type default)
		)
		(layer "F.Cu")
	)
	(gr_arc
		(start 6.292342 -348.312994)
		(mid 6.123248 -348.200009)
		(end 5.923788 -348.16034)
		(stroke
			(width 0.047498)
			(type default)
		)
		(layer "F.Cu")
	)
	(gr_line
		(start 6.292342 -348.312994)
		(end 6.478778 -348.49943)
		(stroke
			(width 0.047498)
			(type default)
		)
		(layer "F.Cu")
	)
	(gr_line
		(start 6.314694 -131.830572)
		(end 6.864604 -131.830572)
		(stroke
			(width 0.047498)
			(type default)
		)
		(layer "F.Cu")
	)
	(gr_arc
		(start 6.349746 -169.830496)
		(mid 6.704391 -169.760047)
		(end 7.005066 -169.559224)
		(stroke
			(width 0.047498)
			(type default)
		)
		(layer "F.Cu")
	)
	(gr_arc
		(start 6.349746 -111.830612)
		(mid 6.572983 -111.766865)
		(end 6.728968 -111.5949)
		(stroke
			(width 0.047498)
			(type default)
		)
		(layer "F.Cu")
	)
	(gr_arc
		(start 6.37413 -127.83058)
		(mid 6.608336 -127.733569)
		(end 6.705346 -127.499364)
		(stroke
			(width 0.047498)
			(type default)
		)
		(layer "F.Cu")
	)
	(gr_arc
		(start 6.442964 -107.6325)
		(mid 6.584974 -107.604243)
		(end 6.705346 -107.523788)
		(stroke
			(width 0.047498)
			(type default)
		)
		(layer "F.Cu")
	)
	(gr_line
		(start 6.446774 -132.393182)
		(end 6.732524 -132.393182)
		(stroke
			(width 0.047498)
			(type default)
		)
		(layer "F.Cu")
	)
	(gr_arc
		(start 6.452108 -101.830124)
		(mid 6.613204 -101.763388)
		(end 6.679946 -101.602286)
		(stroke
			(width 0.047498)
			(type default)
		)
		(layer "F.Cu")
	)
	(gr_line
		(start 6.479286 -97.830132)
		(end 6.629146 -97.830132)
		(stroke
			(width 0.047498)
			(type default)
		)
		(layer "F.Cu")
	)
	(gr_arc
		(start 6.530086 -102.192582)
		(mid 6.494309 -102.168677)
		(end 6.452108 -102.160324)
		(stroke
			(width 0.047498)
			(type default)
		)
		(layer "F.Cu")
	)
	(gr_arc
		(start 6.533642 -115.830604)
		(mid 6.74483 -115.743101)
		(end 6.832346 -115.5319)
		(stroke
			(width 0.047498)
			(type default)
		)
		(layer "F.Cu")
	)
	(gr_arc
		(start 6.54939 -98.32721)
		(mid 6.364564 -98.203713)
		(end 6.146546 -98.160332)
		(stroke
			(width 0.047498)
			(type default)
		)
		(layer "F.Cu")
	)
	(gr_line
		(start 6.54939 -98.32721)
		(end 6.679946 -98.457766)
		(stroke
			(width 0.047498)
			(type default)
		)
		(layer "F.Cu")
	)
	(gr_arc
		(start 6.622542 -116.273834)
		(mid 6.497382 -116.190205)
		(end 6.349746 -116.160804)
		(stroke
			(width 0.047498)
			(type default)
		)
		(layer "F.Cu")
	)
	(gr_line
		(start 6.622542 -116.273834)
		(end 6.806946 -116.458238)
		(stroke
			(width 0.047498)
			(type default)
		)
		(layer "F.Cu")
	)
	(gr_arc
		(start 6.629146 -97.830132)
		(mid 6.775521 -97.73246)
		(end 6.74116 -97.559876)
		(stroke
			(width 0.047498)
			(type default)
		)
		(layer "F.Cu")
	)
	(gr_arc
		(start 6.679946 -102.457504)
		(mid 6.639887 -102.305316)
		(end 6.530086 -102.192582)
		(stroke
			(width 0.047498)
			(type default)
		)
		(layer "F.Cu")
	)
	(gr_line
		(start 6.679946 -101.498654)
		(end 6.679946 -101.602286)
		(stroke
			(width 0.047498)
			(type default)
		)
		(layer "F.Cu")
	)
	(gr_line
		(start 6.679946 -97.498916)
		(end 6.74116 -97.559876)
		(stroke
			(width 0.047498)
			(type default)
		)
		(layer "F.Cu")
	)
	(gr_arc
		(start 6.681216 -162.39236)
		(mid 6.42437 -162.220741)
		(end 6.1214 -162.160458)
		(stroke
			(width 0.047498)
			(type default)
		)
		(layer "F.Cu")
	)
	(gr_line
		(start 6.681216 -162.39236)
		(end 6.748272 -162.459416)
		(stroke
			(width 0.047498)
			(type default)
		)
		(layer "F.Cu")
	)
	(gr_line
		(start 6.681216 -161.598356)
		(end 6.748272 -161.5313)
		(stroke
			(width 0.047498)
			(type default)
		)
		(layer "F.Cu")
	)
	(gr_arc
		(start 6.705346 -128.458214)
		(mid 6.61823 -128.247896)
		(end 6.407912 -128.16078)
		(stroke
			(width 0.047498)
			(type default)
		)
		(layer "F.Cu")
	)
	(gr_arc
		(start 6.730746 -166.2557)
		(mid 6.625514 -166.185386)
		(end 6.501384 -166.160704)
		(stroke
			(width 0.047498)
			(type default)
		)
		(layer "F.Cu")
	)
	(gr_arc
		(start 6.732524 -132.393182)
		(mid 6.862818 -132.363348)
		(end 6.964934 -132.277104)
		(stroke
			(width 0.047498)
			(type default)
		)
		(layer "F.Cu")
	)
	(gr_arc
		(start 6.737096 -108.38688)
		(mid 6.612857 -108.086939)
		(end 6.312916 -107.9627)
		(stroke
			(width 0.047498)
			(type default)
		)
		(layer "F.Cu")
	)
	(gr_arc
		(start 6.756146 -112.458246)
		(mid 6.601532 -112.243164)
		(end 6.349746 -112.160812)
		(stroke
			(width 0.047498)
			(type default)
		)
		(layer "F.Cu")
	)
	(gr_arc
		(start 6.857746 -166.562278)
		(mid 6.824742 -166.396355)
		(end 6.730746 -166.2557)
		(stroke
			(width 0.047498)
			(type default)
		)
		(layer "F.Cu")
	)
	(gr_line
		(start 6.857746 -166.562278)
		(end 6.857746 -166.7637)
		(stroke
			(width 0.047498)
			(type default)
		)
		(layer "F.Cu")
	)
	(gr_arc
		(start 6.889242 -399.34007)
		(mid 7.063946 -399.022802)
		(end 7.124446 -398.6657)
		(stroke
			(width 0.047498)
			(type default)
		)
		(layer "F.Cu")
	)
	(gr_arc
		(start 6.894322 -158.369254)
		(mid 6.663348 -158.214892)
		(end 6.390894 -158.16072)
		(stroke
			(width 0.047498)
			(type default)
		)
		(layer "F.Cu")
	)
	(gr_line
		(start 6.894322 -158.369254)
		(end 6.984746 -158.459678)
		(stroke
			(width 0.047498)
			(type default)
		)
		(layer "F.Cu")
	)
	(gr_arc
		(start 6.949186 -339.939122)
		(mid 6.979122 -340.069457)
		(end 7.065518 -340.171532)
		(stroke
			(width 0.047498)
			(type default)
		)
		(layer "F.Cu")
	)
	(gr_line
		(start 6.949186 -339.653372)
		(end 6.949186 -339.939122)
		(stroke
			(width 0.047498)
			(type default)
		)
		(layer "F.Cu")
	)
	(gr_arc
		(start 6.949186 -338.437982)
		(mid 6.979122 -338.568317)
		(end 7.065518 -338.670392)
		(stroke
			(width 0.047498)
			(type default)
		)
		(layer "F.Cu")
	)
	(gr_line
		(start 6.949186 -338.152232)
		(end 6.949186 -338.437982)
		(stroke
			(width 0.047498)
			(type default)
		)
		(layer "F.Cu")
	)
	(gr_arc
		(start 6.949186 -336.936842)
		(mid 6.979122 -337.067177)
		(end 7.065518 -337.169252)
		(stroke
			(width 0.047498)
			(type default)
		)
		(layer "F.Cu")
	)
	(gr_line
		(start 6.949186 -336.651092)
		(end 6.949186 -336.936842)
		(stroke
			(width 0.047498)
			(type default)
		)
		(layer "F.Cu")
	)
	(gr_arc
		(start 6.949186 -330.641452)
		(mid 6.979122 -330.771787)
		(end 7.065518 -330.873862)
		(stroke
			(width 0.047498)
			(type default)
		)
		(layer "F.Cu")
	)
	(gr_line
		(start 6.949186 -330.355702)
		(end 6.949186 -330.641452)
		(stroke
			(width 0.047498)
			(type default)
		)
		(layer "F.Cu")
	)
	(gr_arc
		(start 6.949186 -329.140312)
		(mid 6.979122 -329.270647)
		(end 7.065518 -329.372722)
		(stroke
			(width 0.047498)
			(type default)
		)
		(layer "F.Cu")
	)
	(gr_line
		(start 6.949186 -328.854562)
		(end 6.949186 -329.140312)
		(stroke
			(width 0.047498)
			(type default)
		)
		(layer "F.Cu")
	)
	(gr_arc
		(start 6.949186 -311.975246)
		(mid 6.979122 -312.105581)
		(end 7.065518 -312.207656)
		(stroke
			(width 0.047498)
			(type default)
		)
		(layer "F.Cu")
	)
	(gr_line
		(start 6.949186 -311.689496)
		(end 6.949186 -311.975246)
		(stroke
			(width 0.047498)
			(type default)
		)
		(layer "F.Cu")
	)
	(gr_arc
		(start 6.949186 -310.474106)
		(mid 6.979122 -310.604441)
		(end 7.065518 -310.706516)
		(stroke
			(width 0.047498)
			(type default)
		)
		(layer "F.Cu")
	)
	(gr_line
		(start 6.949186 -310.188356)
		(end 6.949186 -310.474106)
		(stroke
			(width 0.047498)
			(type default)
		)
		(layer "F.Cu")
	)
	(gr_arc
		(start 7.005066 -170.431968)
		(mid 6.704388 -170.231154)
		(end 6.349746 -170.160696)
		(stroke
			(width 0.047498)
			(type default)
		)
		(layer "F.Cu")
	)
	(gr_line
		(start 7.005066 -170.431968)
		(end 7.032498 -170.459654)
		(stroke
			(width 0.047498)
			(type default)
		)
		(layer "F.Cu")
	)
	(gr_line
		(start 7.005066 -169.559224)
		(end 7.032498 -169.531538)
		(stroke
			(width 0.047498)
			(type default)
		)
		(layer "F.Cu")
	)
	(gr_arc
		(start 7.065518 -339.420962)
		(mid 6.979119 -339.523036)
		(end 6.949186 -339.653372)
		(stroke
			(width 0.047498)
			(type default)
		)
		(layer "F.Cu")
	)
	(gr_arc
		(start 7.065518 -339.420962)
		(mid 7.151799 -339.318862)
		(end 7.181596 -339.188552)
		(stroke
			(width 0.047498)
			(type default)
		)
		(layer "F.Cu")
	)
	(gr_arc
		(start 7.065518 -337.919822)
		(mid 6.979119 -338.021896)
		(end 6.949186 -338.152232)
		(stroke
			(width 0.047498)
			(type default)
		)
		(layer "F.Cu")
	)
	(gr_arc
		(start 7.065518 -337.919822)
		(mid 7.151784 -337.817719)
		(end 7.181596 -337.687412)
		(stroke
			(width 0.047498)
			(type default)
		)
		(layer "F.Cu")
	)
	(gr_arc
		(start 7.065518 -336.418682)
		(mid 6.979119 -336.520756)
		(end 6.949186 -336.651092)
		(stroke
			(width 0.047498)
			(type default)
		)
		(layer "F.Cu")
	)
	(gr_arc
		(start 7.065518 -336.418682)
		(mid 7.151806 -336.316584)
		(end 7.181596 -336.186272)
		(stroke
			(width 0.047498)
			(type default)
		)
		(layer "F.Cu")
	)
	(gr_arc
		(start 7.065518 -330.123292)
		(mid 6.979119 -330.225366)
		(end 6.949186 -330.355702)
		(stroke
			(width 0.047498)
			(type default)
		)
		(layer "F.Cu")
	)
	(gr_arc
		(start 7.065518 -330.123292)
		(mid 7.15181 -330.021194)
		(end 7.181596 -329.890882)
		(stroke
			(width 0.047498)
			(type default)
		)
		(layer "F.Cu")
	)
	(gr_arc
		(start 7.065518 -328.622152)
		(mid 6.979119 -328.724226)
		(end 6.949186 -328.854562)
		(stroke
			(width 0.047498)
			(type default)
		)
		(layer "F.Cu")
	)
	(gr_arc
		(start 7.065518 -328.622152)
		(mid 7.151795 -328.520051)
		(end 7.181596 -328.389742)
		(stroke
			(width 0.047498)
			(type default)
		)
		(layer "F.Cu")
	)
	(gr_arc
		(start 7.065518 -311.457086)
		(mid 6.979119 -311.55916)
		(end 6.949186 -311.689496)
		(stroke
			(width 0.047498)
			(type default)
		)
		(layer "F.Cu")
	)
	(gr_arc
		(start 7.065518 -311.457086)
		(mid 7.151807 -311.354988)
		(end 7.181596 -311.224676)
		(stroke
			(width 0.047498)
			(type default)
		)
		(layer "F.Cu")
	)
	(gr_arc
		(start 7.065518 -309.955946)
		(mid 6.979119 -310.05802)
		(end 6.949186 -310.188356)
		(stroke
			(width 0.047498)
			(type default)
		)
		(layer "F.Cu")
	)
	(gr_arc
		(start 7.065518 -309.955946)
		(mid 7.151793 -309.853845)
		(end 7.181596 -309.723536)
		(stroke
			(width 0.047498)
			(type default)
		)
		(layer "F.Cu")
	)
	(gr_arc
		(start 7.181596 -340.403942)
		(mid 7.151751 -340.273656)
		(end 7.065518 -340.171532)
		(stroke
			(width 0.047498)
			(type default)
		)
		(layer "F.Cu")
	)
	(gr_arc
		(start 7.181596 -338.902802)
		(mid 7.151736 -338.772528)
		(end 7.065518 -338.670392)
		(stroke
			(width 0.047498)
			(type default)
		)
		(layer "F.Cu")
	)
	(gr_arc
		(start 7.181596 -337.401662)
		(mid 7.151758 -337.271371)
		(end 7.065518 -337.169252)
		(stroke
			(width 0.047498)
			(type default)
		)
		(layer "F.Cu")
	)
	(gr_arc
		(start 7.181596 -331.106272)
		(mid 7.151762 -330.975978)
		(end 7.065518 -330.873862)
		(stroke
			(width 0.047498)
			(type default)
		)
		(layer "F.Cu")
	)
	(gr_arc
		(start 7.181596 -329.605132)
		(mid 7.151747 -329.474849)
		(end 7.065518 -329.372722)
		(stroke
			(width 0.047498)
			(type default)
		)
		(layer "F.Cu")
	)
	(gr_arc
		(start 7.181596 -312.440066)
		(mid 7.15176 -312.309773)
		(end 7.065518 -312.207656)
		(stroke
			(width 0.047498)
			(type default)
		)
		(layer "F.Cu")
	)
	(gr_arc
		(start 7.181596 -310.938926)
		(mid 7.151745 -310.808645)
		(end 7.065518 -310.706516)
		(stroke
			(width 0.047498)
			(type default)
		)
		(layer "F.Cu")
	)
	(gr_arc
		(start 7.197344 -132.160772)
		(mid 7.067009 -132.190708)
		(end 6.964934 -132.277104)
		(stroke
			(width 0.047498)
			(type default)
		)
		(layer "F.Cu")
	)
	(gr_line
		(start 7.238746 -353.3267)
		(end 7.395972 -353.169474)
		(stroke
			(width 0.047498)
			(type default)
		)
		(layer "F.Cu")
	)
	(gr_line
		(start 7.256526 -174.37862)
		(end 7.26186 -174.383954)
		(stroke
			(width 0.047498)
			(type default)
		)
		(layer "F.Cu")
	)
	(gr_line
		(start 7.2644 -421.903906)
		(end 7.491984 -421.676322)
		(stroke
			(width 0.047498)
			(type default)
		)
		(layer "F.Cu")
	)
	(gr_line
		(start 7.289038 -367.867184)
		(end 7.363206 -367.867184)
		(stroke
			(width 0.047498)
			(type default)
		)
		(layer "F.Cu")
	)
	(gr_line
		(start 7.340346 -409.754324)
		(end 7.340346 -409.835096)
		(stroke
			(width 0.047498)
			(type default)
		)
		(layer "F.Cu")
	)
	(gr_arc
		(start 7.363206 -367.867184)
		(mid 7.496548 -367.801296)
		(end 7.525258 -367.655348)
		(stroke
			(width 0.047498)
			(type default)
		)
		(layer "F.Cu")
	)
	(gr_line
		(start 7.365746 -358.5337)
		(end 7.43712 -358.462326)
		(stroke
			(width 0.047498)
			(type default)
		)
		(layer "F.Cu")
	)
	(gr_line
		(start 7.3914 -424.053)
		(end 7.573518 -423.870882)
		(stroke
			(width 0.047498)
			(type default)
		)
		(layer "F.Cu")
	)
	(gr_arc
		(start 7.395972 -353.169474)
		(mid 7.491869 -353.026029)
		(end 7.525512 -352.8568)
		(stroke
			(width 0.047498)
			(type default)
		)
		(layer "F.Cu")
	)
	(gr_arc
		(start 7.43712 -358.462326)
		(mid 7.609874 -358.203722)
		(end 7.670546 -357.8987)
		(stroke
			(width 0.047498)
			(type default)
		)
		(layer "F.Cu")
	)
	(gr_arc
		(start 7.454646 -398.6657)
		(mid 7.532692 -399.016188)
		(end 7.75208 -399.300446)
		(stroke
			(width 0.047498)
			(type default)
		)
		(layer "F.Cu")
	)
	(gr_line
		(start 7.492746 -414.0327)
		(end 7.650988 -413.874458)
		(stroke
			(width 0.047498)
			(type default)
		)
		(layer "F.Cu")
	)
	(gr_line
		(start 7.511796 -339.521292)
		(end 7.511796 -340.071202)
		(stroke
			(width 0.047498)
			(type default)
		)
		(layer "F.Cu")
	)
	(gr_line
		(start 7.511796 -338.020152)
		(end 7.511796 -338.570062)
		(stroke
			(width 0.047498)
			(type default)
		)
		(layer "F.Cu")
	)
	(gr_line
		(start 7.511796 -336.519012)
		(end 7.511796 -337.068922)
		(stroke
			(width 0.047498)
			(type default)
		)
		(layer "F.Cu")
	)
	(gr_line
		(start 7.511796 -330.223622)
		(end 7.511796 -330.773532)
		(stroke
			(width 0.047498)
			(type default)
		)
		(layer "F.Cu")
	)
	(gr_line
		(start 7.511796 -328.722482)
		(end 7.511796 -329.272392)
		(stroke
			(width 0.047498)
			(type default)
		)
		(layer "F.Cu")
	)
	(gr_line
		(start 7.511796 -311.557416)
		(end 7.511796 -312.107326)
		(stroke
			(width 0.047498)
			(type default)
		)
		(layer "F.Cu")
	)
	(gr_line
		(start 7.511796 -310.056276)
		(end 7.511796 -310.606186)
		(stroke
			(width 0.047498)
			(type default)
		)
		(layer "F.Cu")
	)
	(gr_arc
		(start 7.525004 -417.830508)
		(mid 7.608134 -417.714435)
		(end 7.649464 -417.577778)
		(stroke
			(width 0.047498)
			(type default)
		)
		(layer "F.Cu")
	)
	(gr_line
		(start 7.525512 -352.77044)
		(end 7.525512 -352.8568)
		(stroke
			(width 0.047498)
			(type default)
		)
		(layer "F.Cu")
	)
	(gr_arc
		(start 7.573518 -423.870882)
		(mid 7.626701 -423.791288)
		(end 7.6454 -423.6974)
		(stroke
			(width 0.047498)
			(type default)
		)
		(layer "F.Cu")
	)
	(gr_arc
		(start 7.619746 -385.830572)
		(mid 7.657828 -385.829071)
		(end 7.695692 -385.82473)
		(stroke
			(width 0.047498)
			(type default)
		)
		(layer "F.Cu")
	)
	(gr_line
		(start 7.64921 -384.0226)
		(end 7.693152 -384.0226)
		(stroke
			(width 0.047498)
			(type default)
		)
		(layer "F.Cu")
	)
	(gr_line
		(start 7.649464 -417.577778)
		(end 7.675372 -417.379404)
		(stroke
			(width 0.047498)
			(type default)
		)
		(layer "F.Cu")
	)
	(gr_arc
		(start 7.650988 -413.874458)
		(mid 7.798367 -413.653848)
		(end 7.850124 -413.393636)
		(stroke
			(width 0.047498)
			(type default)
		)
		(layer "F.Cu")
	)
	(gr_line
		(start 7.687564 -395.171676)
		(end 7.703312 -395.155928)
		(stroke
			(width 0.047498)
			(type default)
		)
		(layer "F.Cu")
	)
	(gr_arc
		(start 7.693152 -384.0226)
		(mid 7.890392 -383.940932)
		(end 7.972044 -383.743708)
		(stroke
			(width 0.047498)
			(type default)
		)
		(layer "F.Cu")
	)
	(gr_arc
		(start 7.695692 -385.82473)
		(mid 7.849186 -385.775574)
		(end 7.979664 -385.680966)
		(stroke
			(width 0.047498)
			(type default)
		)
		(layer "F.Cu")
	)
	(gr_line
		(start 7.716012 -371.479572)
		(end 7.72795 -371.479572)
		(stroke
			(width 0.047498)
			(type default)
		)
		(layer "F.Cu")
	)
	(gr_line
		(start 7.72795 -371.479572)
		(end 8.474202 -370.73332)
		(stroke
			(width 0.047498)
			(type default)
		)
		(layer "F.Cu")
	)
	(gr_line
		(start 7.729982 -421.075104)
		(end 7.729982 -421.075612)
		(stroke
			(width 0.047498)
			(type default)
		)
		(layer "F.Cu")
	)
	(gr_line
		(start 7.746746 -380.3777)
		(end 7.886192 -380.238254)
		(stroke
			(width 0.047498)
			(type default)
		)
		(layer "F.Cu")
	)
	(gr_line
		(start 7.746746 -364.259622)
		(end 7.746746 -364.3757)
		(stroke
			(width 0.047498)
			(type default)
		)
		(layer "F.Cu")
	)
	(gr_arc
		(start 7.787894 -364.053374)
		(mid 7.757172 -364.154472)
		(end 7.746746 -364.259622)
		(stroke
			(width 0.047498)
			(type default)
		)
		(layer "F.Cu")
	)
	(gr_line
		(start 7.787894 -364.053374)
		(end 7.878318 -363.835188)
		(stroke
			(width 0.047498)
			(type default)
		)
		(layer "F.Cu")
	)
	(gr_line
		(start 7.84733 -409.561284)
		(end 8.062722 -409.776422)
		(stroke
			(width 0.047498)
			(type default)
		)
		(layer "F.Cu")
	)
	(gr_arc
		(start 7.853426 -409.31338)
		(mid 7.848187 -409.31881)
		(end 7.843012 -409.324302)
		(stroke
			(width 0.047498)
			(type default)
		)
		(layer "F.Cu")
	)
	(gr_arc
		(start 7.855712 -352.4377)
		(mid 7.875768 -352.538056)
		(end 7.932674 -352.62312)
		(stroke
			(width 0.047498)
			(type default)
		)
		(layer "F.Cu")
	)
	(gr_arc
		(start 7.87273 -421.591486)
		(mid 7.882252 -421.659845)
		(end 7.919466 -421.717978)
		(stroke
			(width 0.047498)
			(type default)
		)
		(layer "F.Cu")
	)
	(gr_arc
		(start 7.878318 -363.835188)
		(mid 7.912901 -363.720875)
		(end 7.924546 -363.602016)
		(stroke
			(width 0.047498)
			(type default)
		)
		(layer "F.Cu")
	)
	(gr_line
		(start 7.88416 -367.637822)
		(end 8.151876 -367.905792)
		(stroke
			(width 0.047498)
			(type default)
		)
		(layer "F.Cu")
	)
	(gr_arc
		(start 7.886192 -380.238254)
		(mid 7.999169 -380.069158)
		(end 8.038846 -379.8697)
		(stroke
			(width 0.047498)
			(type default)
		)
		(layer "F.Cu")
	)
	(gr_line
		(start 7.905242 -421.390318)
		(end 7.905496 -421.390318)
		(stroke
			(width 0.047498)
			(type default)
		)
		(layer "F.Cu")
	)
	(gr_arc
		(start 7.918196 -395.40815)
		(mid 8.045228 -395.281309)
		(end 8.172196 -395.154404)
		(stroke
			(width 0.047498)
			(type default)
		)
		(layer "F.Cu")
	)
	(gr_line
		(start 7.919466 -421.717978)
		(end 8.127746 -421.926258)
		(stroke
			(width 0.047498)
			(type default)
		)
		(layer "F.Cu")
	)
	(gr_line
		(start 7.932674 -352.62312)
		(end 8.212582 -352.903282)
		(stroke
			(width 0.047498)
			(type default)
		)
		(layer "F.Cu")
	)
	(gr_arc
		(start 7.974584 -386.307584)
		(mid 7.811768 -386.198887)
		(end 7.619746 -386.160772)
		(stroke
			(width 0.047498)
			(type default)
		)
		(layer "F.Cu")
	)
	(gr_line
		(start 7.974584 -386.307584)
		(end 8.127746 -386.461)
		(stroke
			(width 0.047498)
			(type default)
		)
		(layer "F.Cu")
	)
	(gr_arc
		(start 7.9756 -423.6974)
		(mid 7.9995 -423.817539)
		(end 8.067548 -423.919396)
		(stroke
			(width 0.047498)
			(type default)
		)
		(layer "F.Cu")
	)
	(gr_line
		(start 7.979664 -385.680966)
		(end 8.127746 -385.532884)
		(stroke
			(width 0.047498)
			(type default)
		)
		(layer "F.Cu")
	)
	(gr_arc
		(start 8.000746 -357.92918)
		(mid 8.063633 -358.245056)
		(end 8.242554 -358.512872)
		(stroke
			(width 0.047498)
			(type default)
		)
		(layer "F.Cu")
	)
	(gr_line
		(start 8.04037 -423.413936)
		(end 8.056626 -423.39768)
		(stroke
			(width 0.047498)
			(type default)
		)
		(layer "F.Cu")
	)
	(gr_arc
		(start 8.062722 -409.776422)
		(mid 8.127501 -409.819799)
		(end 8.203946 -409.835096)
		(stroke
			(width 0.047498)
			(type default)
		)
		(layer "F.Cu")
	)
	(gr_line
		(start 8.067548 -423.919396)
		(end 8.253476 -424.105324)
		(stroke
			(width 0.047498)
			(type default)
		)
		(layer "F.Cu")
	)
	(gr_arc
		(start 8.071104 -412.964884)
		(mid 7.927177 -413.162025)
		(end 7.850124 -413.393636)
		(stroke
			(width 0.047498)
			(type default)
		)
		(layer "F.Cu")
	)
	(gr_line
		(start 8.071104 -412.964884)
		(end 8.12419 -412.912052)
		(stroke
			(width 0.047498)
			(type default)
		)
		(layer "F.Cu")
	)
	(gr_line
		(start 8.090662 -417.678616)
		(end 8.160512 -417.748466)
		(stroke
			(width 0.047498)
			(type default)
		)
		(layer "F.Cu")
	)
	(gr_arc
		(start 8.12038 -136.277096)
		(mid 8.018306 -136.190697)
		(end 7.88797 -136.160764)
		(stroke
			(width 0.047498)
			(type default)
		)
		(layer "F.Cu")
	)
	(gr_arc
		(start 8.12038 -136.277096)
		(mid 8.222481 -136.363368)
		(end 8.35279 -136.393174)
		(stroke
			(width 0.047498)
			(type default)
		)
		(layer "F.Cu")
	)
	(gr_arc
		(start 8.160512 -417.748466)
		(mid 8.26516 -417.818395)
		(end 8.388604 -417.842954)
		(stroke
			(width 0.047498)
			(type default)
		)
		(layer "F.Cu")
	)
	(gr_line
		(start 8.22071 -135.830564)
		(end 8.77062 -135.830564)
		(stroke
			(width 0.047498)
			(type default)
		)
		(layer "F.Cu")
	)
	(gr_arc
		(start 8.254746 -363.38383)
		(mid 8.301403 -363.618484)
		(end 8.434324 -363.817408)
		(stroke
			(width 0.047498)
			(type default)
		)
		(layer "F.Cu")
	)
	(gr_line
		(start 8.296402 -413.294322)
		(end 8.296402 -413.557974)
		(stroke
			(width 0.047498)
			(type default)
		)
		(layer "F.Cu")
	)
	(gr_arc
		(start 8.302244 -383.85115)
		(mid 8.363694 -383.999504)
		(end 8.512048 -384.060954)
		(stroke
			(width 0.047498)
			(type default)
		)
		(layer "F.Cu")
	)
	(gr_line
		(start 8.302244 -383.743708)
		(end 8.302244 -383.85115)
		(stroke
			(width 0.047498)
			(type default)
		)
		(layer "F.Cu")
	)
	(gr_line
		(start 8.35279 -136.393174)
		(end 8.63854 -136.393174)
		(stroke
			(width 0.047498)
			(type default)
		)
		(layer "F.Cu")
	)
	(gr_arc
		(start 8.355584 -412.81604)
		(mid 8.230345 -412.841045)
		(end 8.12419 -412.912052)
		(stroke
			(width 0.047498)
			(type default)
		)
		(layer "F.Cu")
	)
	(gr_line
		(start 8.36041 -369.477036)
		(end 8.360664 -369.47729)
		(stroke
			(width 0.047498)
			(type default)
		)
		(layer "F.Cu")
	)
	(gr_arc
		(start 8.369046 -379.8697)
		(mid 8.408724 -380.069155)
		(end 8.5217 -380.238254)
		(stroke
			(width 0.047498)
			(type default)
		)
		(layer "F.Cu")
	)
	(gr_arc
		(start 8.381746 -376.012456)
		(mid 8.479856 -376.249393)
		(end 8.716772 -376.347482)
		(stroke
			(width 0.047498)
			(type default)
		)
		(layer "F.Cu")
	)
	(gr_arc
		(start 8.444484 -413.14624)
		(mid 8.339792 -413.189619)
		(end 8.296402 -413.294322)
		(stroke
			(width 0.047498)
			(type default)
		)
		(layer "F.Cu")
	)
	(gr_arc
		(start 8.485886 -375.760996)
		(mid 8.408816 -375.876373)
		(end 8.381746 -376.012456)
		(stroke
			(width 0.047498)
			(type default)
		)
		(layer "F.Cu")
	)
	(gr_line
		(start 8.51535 -361.842558)
		(end 8.748776 -361.609132)
		(stroke
			(width 0.047498)
			(type default)
		)
		(layer "F.Cu")
	)
	(gr_line
		(start 8.5217 -380.238254)
		(end 8.661146 -380.3777)
		(stroke
			(width 0.047498)
			(type default)
		)
		(layer "F.Cu")
	)
	(gr_line
		(start 8.59409 -369.710716)
		(end 8.615426 -369.68938)
		(stroke
			(width 0.047498)
			(type default)
		)
		(layer "F.Cu")
	)
	(gr_line
		(start 8.61441 -371.231414)
		(end 8.61441 -371.520974)
		(stroke
			(width 0.047498)
			(type default)
		)
		(layer "F.Cu")
	)
	(gr_line
		(start 8.615172 -369.689126)
		(end 8.615426 -369.68938)
		(stroke
			(width 0.047498)
			(type default)
		)
		(layer "F.Cu")
	)
	(gr_line
		(start 8.615172 -369.689126)
		(end 8.827262 -369.477036)
		(stroke
			(width 0.047498)
			(type default)
		)
		(layer "F.Cu")
	)
	(gr_arc
		(start 8.63854 -136.393174)
		(mid 8.768829 -136.363334)
		(end 8.87095 -136.277096)
		(stroke
			(width 0.047498)
			(type default)
		)
		(layer "F.Cu")
	)
	(gr_line
		(start 8.657844 -378.887736)
		(end 8.658098 -378.888244)
		(stroke
			(width 0.047498)
			(type default)
		)
		(layer "F.Cu")
	)
	(gr_line
		(start 8.716772 -376.347482)
		(end 8.75411 -376.347482)
		(stroke
			(width 0.047498)
			(type default)
		)
		(layer "F.Cu")
	)
	(gr_arc
		(start 8.735314 -370.939568)
		(mid 8.645845 -371.073468)
		(end 8.61441 -371.231414)
		(stroke
			(width 0.047498)
			(type default)
		)
		(layer "F.Cu")
	)
	(gr_arc
		(start 8.762746 -131.830572)
		(mid 9.061796 -131.745183)
		(end 9.270746 -131.51485)
		(stroke
			(width 0.047498)
			(type default)
		)
		(layer "F.Cu")
	)
	(gr_line
		(start 9.005062 -378.715016)
		(end 9.067038 -378.649992)
		(stroke
			(width 0.047498)
			(type default)
		)
		(layer "F.Cu")
	)
	(gr_line
		(start 9.067038 -378.649992)
		(end 9.099804 -378.616972)
		(stroke
			(width 0.047498)
			(type default)
		)
		(layer "F.Cu")
	)
	(gr_arc
		(start 9.10336 -136.160764)
		(mid 8.973025 -136.1907)
		(end 8.87095 -136.277096)
		(stroke
			(width 0.047498)
			(type default)
		)
		(layer "F.Cu")
	)
	(gr_line
		(start 9.208516 -378.975112)
		(end 9.300464 -378.883418)
		(stroke
			(width 0.047498)
			(type default)
		)
		(layer "F.Cu")
	)
	(gr_arc
		(start 9.270746 -132.4737)
		(mid 9.061083 -132.245245)
		(end 8.762746 -132.160772)
		(stroke
			(width 0.047498)
			(type default)
		)
		(layer "F.Cu")
	)
	(gr_line
		(start 9.300464 -378.883418)
		(end 9.331198 -378.852684)
		(stroke
			(width 0.047498)
			(type default)
		)
		(layer "F.Cu")
	)
	(gr_arc
		(start 9.307322 -413.078422)
		(mid 9.016681 -412.884222)
		(end 8.673846 -412.81604)
		(stroke
			(width 0.047498)
			(type default)
		)
		(layer "F.Cu")
	)
	(gr_line
		(start 9.473692 -176.595786)
		(end 9.479026 -176.60112)
		(stroke
			(width 0.047498)
			(type default)
		)
		(layer "F.Cu")
	)
	(gr_line
		(start 9.525 -438.9882)
		(end 9.525254 -438.9882)
		(stroke
			(width 0.047498)
			(type default)
		)
		(layer "F.Cu")
	)
	(gr_line
		(start 9.553194 -360.337354)
		(end 9.78662 -360.103928)
		(stroke
			(width 0.047498)
			(type default)
		)
		(layer "F.Cu")
	)
	(gr_arc
		(start 9.62152 -136.277096)
		(mid 9.519446 -136.190697)
		(end 9.38911 -136.160764)
		(stroke
			(width 0.047498)
			(type default)
		)
		(layer "F.Cu")
	)
	(gr_arc
		(start 9.62152 -136.277096)
		(mid 9.723616 -136.36339)
		(end 9.85393 -136.393174)
		(stroke
			(width 0.047498)
			(type default)
		)
		(layer "F.Cu")
	)
	(gr_line
		(start 9.696196 -357.051356)
		(end 9.929622 -356.81793)
		(stroke
			(width 0.047498)
			(type default)
		)
		(layer "F.Cu")
	)
	(gr_line
		(start 9.72185 -135.830564)
		(end 10.27176 -135.830564)
		(stroke
			(width 0.047498)
			(type default)
		)
		(layer "F.Cu")
	)
	(gr_line
		(start 9.85393 -136.393174)
		(end 10.13968 -136.393174)
		(stroke
			(width 0.047498)
			(type default)
		)
		(layer "F.Cu")
	)
	(gr_line
		(start 9.8552 -438.658)
		(end 9.8552 -438.9882)
		(stroke
			(width 0.047498)
			(type default)
		)
		(layer "F.Cu")
	)
	(gr_line
		(start 10.091166 -424.492166)
		(end 10.0965 -424.4975)
		(stroke
			(width 0.047498)
			(type default)
		)
		(layer "F.Cu")
	)
	(gr_arc
		(start 10.13968 -136.393174)
		(mid 10.269957 -136.363319)
		(end 10.37209 -136.277096)
		(stroke
			(width 0.047498)
			(type default)
		)
		(layer "F.Cu")
	)
	(gr_arc
		(start 10.6045 -136.160764)
		(mid 10.474165 -136.1907)
		(end 10.37209 -136.277096)
		(stroke
			(width 0.047498)
			(type default)
		)
		(layer "F.Cu")
	)
	(gr_line
		(start 11.0744 -441.2234)
		(end 11.169904 -441.127896)
		(stroke
			(width 0.047498)
			(type default)
		)
		(layer "F.Cu")
	)
	(gr_arc
		(start 11.12266 -136.277096)
		(mid 11.020586 -136.190697)
		(end 10.89025 -136.160764)
		(stroke
			(width 0.047498)
			(type default)
		)
		(layer "F.Cu")
	)
	(gr_arc
		(start 11.12266 -136.277096)
		(mid 11.224759 -136.363375)
		(end 11.35507 -136.393174)
		(stroke
			(width 0.047498)
			(type default)
		)
		(layer "F.Cu")
	)
	(gr_arc
		(start 11.169904 -441.127896)
		(mid 11.249638 -441.008562)
		(end 11.2776 -440.8678)
		(stroke
			(width 0.047498)
			(type default)
		)
		(layer "F.Cu")
	)
	(gr_line
		(start 11.22299 -135.830564)
		(end 11.7729 -135.830564)
		(stroke
			(width 0.047498)
			(type default)
		)
		(layer "F.Cu")
	)
	(gr_line
		(start 11.35507 -136.393174)
		(end 11.64082 -136.393174)
		(stroke
			(width 0.047498)
			(type default)
		)
		(layer "F.Cu")
	)
	(gr_arc
		(start 11.47953 -438.85993)
		(mid 11.340273 -438.766866)
		(end 11.176 -438.7342)
		(stroke
			(width 0.047498)
			(type default)
		)
		(layer "F.Cu")
	)
	(gr_line
		(start 11.47953 -438.85993)
		(end 11.652758 -439.033158)
		(stroke
			(width 0.047498)
			(type default)
		)
		(layer "F.Cu")
	)
	(gr_line
		(start 11.47953 -438.27827)
		(end 11.652758 -438.105042)
		(stroke
			(width 0.047498)
			(type default)
		)
		(layer "F.Cu")
	)
	(gr_arc
		(start 11.6078 -440.7154)
		(mid 11.640473 -440.879673)
		(end 11.73353 -441.01893)
		(stroke
			(width 0.047498)
			(type default)
		)
		(layer "F.Cu")
	)
	(gr_arc
		(start 11.64082 -136.393174)
		(mid 11.771115 -136.363341)
		(end 11.87323 -136.277096)
		(stroke
			(width 0.047498)
			(type default)
		)
		(layer "F.Cu")
	)
	(gr_line
		(start 11.73353 -441.01893)
		(end 11.938 -441.2234)
		(stroke
			(width 0.047498)
			(type default)
		)
		(layer "F.Cu")
	)
	(gr_line
		(start 11.764772 -386.453634)
		(end 11.764772 -386.646674)
		(stroke
			(width 0.047498)
			(type default)
		)
		(layer "F.Cu")
	)
	(gr_line
		(start 12.094718 -386.123434)
		(end 12.094718 -386.316474)
		(stroke
			(width 0.047498)
			(type default)
		)
		(layer "F.Cu")
	)
	(gr_arc
		(start 12.10564 -136.160764)
		(mid 11.975305 -136.1907)
		(end 11.87323 -136.277096)
		(stroke
			(width 0.047498)
			(type default)
		)
		(layer "F.Cu")
	)
	(gr_arc
		(start 12.191492 -176.9872)
		(mid 12.523064 -176.921279)
		(end 12.80414 -176.733454)
		(stroke
			(width 0.047498)
			(type default)
		)
		(layer "F.Cu")
	)
	(gr_arc
		(start 12.6238 -136.277096)
		(mid 12.521726 -136.190697)
		(end 12.39139 -136.160764)
		(stroke
			(width 0.047498)
			(type default)
		)
		(layer "F.Cu")
	)
	(gr_arc
		(start 12.6238 -136.277096)
		(mid 12.725902 -136.36336)
		(end 12.85621 -136.393174)
		(stroke
			(width 0.047498)
			(type default)
		)
		(layer "F.Cu")
	)
	(gr_line
		(start 12.695174 -365.609378)
		(end 12.700762 -365.60379)
		(stroke
			(width 0.047498)
			(type default)
		)
		(layer "F.Cu")
	)
	(gr_line
		(start 12.72413 -135.830564)
		(end 13.27404 -135.830564)
		(stroke
			(width 0.047498)
			(type default)
		)
		(layer "F.Cu")
	)
	(gr_arc
		(start 12.76604 -177.586894)
		(mid 12.467722 -177.387472)
		(end 12.1158 -177.3174)
		(stroke
			(width 0.047498)
			(type default)
		)
		(layer "F.Cu")
	)
	(gr_line
		(start 12.76604 -177.586894)
		(end 12.7762 -177.5968)
		(stroke
			(width 0.047498)
			(type default)
		)
		(layer "F.Cu")
	)
	(gr_line
		(start 12.85621 -136.393174)
		(end 13.14196 -136.393174)
		(stroke
			(width 0.047498)
			(type default)
		)
		(layer "F.Cu")
	)
	(gr_line
		(start 12.936474 -357.573326)
		(end 13.004546 -357.505254)
		(stroke
			(width 0.047498)
			(type default)
		)
		(layer "F.Cu")
	)
	(gr_arc
		(start 13.14196 -136.393174)
		(mid 13.272243 -136.363326)
		(end 13.37437 -136.277096)
		(stroke
			(width 0.047498)
			(type default)
		)
		(layer "F.Cu")
	)
	(gr_line
		(start 13.146278 -357.835454)
		(end 13.215112 -357.766874)
		(stroke
			(width 0.047498)
			(type default)
		)
		(layer "F.Cu")
	)
	(gr_arc
		(start 13.194284 -355.960172)
		(mid 13.194474 -355.953315)
		(end 13.194538 -355.946456)
		(stroke
			(width 0.047498)
			(type default)
		)
		(layer "F.Cu")
	)
	(gr_line
		(start 13.325602 -365.88192)
		(end 13.559028 -365.648494)
		(stroke
			(width 0.047498)
			(type default)
		)
		(layer "F.Cu")
	)
	(gr_line
		(start 13.40231 -275.305012)
		(end 13.402818 -275.30425)
		(stroke
			(width 0.047498)
			(type default)
		)
		(layer "F.Cu")
	)
	(gr_arc
		(start 13.60678 -136.160764)
		(mid 13.476445 -136.1907)
		(end 13.37437 -136.277096)
		(stroke
			(width 0.047498)
			(type default)
		)
		(layer "F.Cu")
	)
	(gr_line
		(start 14.067028 -357.77678)
		(end 14.300454 -357.543354)
		(stroke
			(width 0.047498)
			(type default)
		)
		(layer "F.Cu")
	)
	(gr_arc
		(start 14.324584 -272.57883)
		(mid 14.32433 -272.578956)
		(end 14.324076 -272.579084)
		(stroke
			(width 0.047498)
			(type default)
		)
		(layer "F.Cu")
	)
	(gr_line
		(start 14.55801 -368.358928)
		(end 14.563598 -368.35334)
		(stroke
			(width 0.047498)
			(type default)
		)
		(layer "F.Cu")
	)
	(gr_line
		(start 14.681708 -135.830564)
		(end 14.863064 -135.830564)
		(stroke
			(width 0.047498)
			(type default)
		)
		(layer "F.Cu")
	)
	(gr_line
		(start 15.011908 -136.14781)
		(end 15.011908 -136.148064)
		(stroke
			(width 0.047498)
			(type default)
		)
		(layer "F.Cu")
	)
	(gr_line
		(start 15.023338 -472.150186)
		(end 15.028672 -472.15552)
		(stroke
			(width 0.047498)
			(type default)
		)
		(layer "F.Cu")
	)
	(gr_line
		(start 15.116556 -470.913968)
		(end 15.12189 -470.919302)
		(stroke
			(width 0.047498)
			(type default)
		)
		(layer "F.Cu")
	)
	(gr_line
		(start 15.15364 -358.152446)
		(end 15.387066 -357.91902)
		(stroke
			(width 0.047498)
			(type default)
		)
		(layer "F.Cu")
	)
	(gr_arc
		(start 15.239746 -136.339834)
		(mid 15.170449 -136.19096)
		(end 15.011908 -136.148064)
		(stroke
			(width 0.047498)
			(type default)
		)
		(layer "F.Cu")
	)
	(gr_line
		(start 15.239746 -136.339834)
		(end 15.239746 -136.5377)
		(stroke
			(width 0.047498)
			(type default)
		)
		(layer "F.Cu")
	)
	(gr_line
		(start 15.84833 -119.830596)
		(end 15.91183 -119.830596)
		(stroke
			(width 0.047498)
			(type default)
		)
		(layer "F.Cu")
	)
	(gr_arc
		(start 15.875 -123.835668)
		(mid 15.957766 -123.819121)
		(end 16.027908 -123.772168)
		(stroke
			(width 0.047498)
			(type default)
		)
		(layer "F.Cu")
	)
	(gr_arc
		(start 15.91183 -119.830596)
		(mid 16.153495 -119.782571)
		(end 16.358362 -119.645684)
		(stroke
			(width 0.047498)
			(type default)
		)
		(layer "F.Cu")
	)
	(gr_line
		(start 15.98295 -359.146602)
		(end 16.216376 -358.913176)
		(stroke
			(width 0.047498)
			(type default)
		)
		(layer "F.Cu")
	)
	(gr_line
		(start 16.027908 -123.772168)
		(end 16.301212 -123.499118)
		(stroke
			(width 0.047498)
			(type default)
		)
		(layer "F.Cu")
	)
	(gr_arc
		(start 16.30553 -124.344176)
		(mid 16.10799 -124.212232)
		(end 15.875 -124.165868)
		(stroke
			(width 0.047498)
			(type default)
		)
		(layer "F.Cu")
	)
	(gr_line
		(start 16.30553 -124.344176)
		(end 16.323818 -124.362464)
		(stroke
			(width 0.047498)
			(type default)
		)
		(layer "F.Cu")
	)
	(gr_arc
		(start 16.356838 -120.509284)
		(mid 15.97087 -120.251389)
		(end 15.51559 -120.160796)
		(stroke
			(width 0.047498)
			(type default)
		)
		(layer "F.Cu")
	)
	(gr_line
		(start 17.360646 -443.53353)
		(end 17.360646 -444.08344)
		(stroke
			(width 0.047498)
			(type default)
		)
		(layer "F.Cu")
	)
	(gr_line
		(start 17.360646 -442.03239)
		(end 17.360646 -442.5823)
		(stroke
			(width 0.047498)
			(type default)
		)
		(layer "F.Cu")
	)
	(gr_line
		(start 17.360646 -434.704744)
		(end 17.360646 -435.254654)
		(stroke
			(width 0.047498)
			(type default)
		)
		(layer "F.Cu")
	)
	(gr_line
		(start 17.360646 -433.203604)
		(end 17.360646 -433.753514)
		(stroke
			(width 0.047498)
			(type default)
		)
		(layer "F.Cu")
	)
	(gr_line
		(start 17.360646 -431.702464)
		(end 17.360646 -432.252374)
		(stroke
			(width 0.047498)
			(type default)
		)
		(layer "F.Cu")
	)
	(gr_line
		(start 17.360646 -428.245016)
		(end 17.360646 -428.794926)
		(stroke
			(width 0.047498)
			(type default)
		)
		(layer "F.Cu")
	)
	(gr_line
		(start 17.360646 -426.743876)
		(end 17.360646 -427.293786)
		(stroke
			(width 0.047498)
			(type default)
		)
		(layer "F.Cu")
	)
	(gr_line
		(start 17.360646 -425.242736)
		(end 17.360646 -425.792646)
		(stroke
			(width 0.047498)
			(type default)
		)
		(layer "F.Cu")
	)
	(gr_arc
		(start 17.690846 -443.20079)
		(mid 17.720699 -443.331071)
		(end 17.806924 -443.4332)
		(stroke
			(width 0.047498)
			(type default)
		)
		(layer "F.Cu")
	)
	(gr_arc
		(start 17.690846 -441.69965)
		(mid 17.720684 -441.829943)
		(end 17.806924 -441.93206)
		(stroke
			(width 0.047498)
			(type default)
		)
		(layer "F.Cu")
	)
	(gr_arc
		(start 17.690846 -434.372004)
		(mid 17.720704 -434.502281)
		(end 17.806924 -434.604414)
		(stroke
			(width 0.047498)
			(type default)
		)
		(layer "F.Cu")
	)
	(gr_arc
		(start 17.690846 -432.870864)
		(mid 17.720689 -433.001153)
		(end 17.806924 -433.103274)
		(stroke
			(width 0.047498)
			(type default)
		)
		(layer "F.Cu")
	)
	(gr_arc
		(start 17.690846 -431.369724)
		(mid 17.720675 -431.500025)
		(end 17.806924 -431.602134)
		(stroke
			(width 0.047498)
			(type default)
		)
		(layer "F.Cu")
	)
	(gr_arc
		(start 17.690846 -427.912276)
		(mid 17.720694 -428.042562)
		(end 17.806924 -428.144686)
		(stroke
			(width 0.047498)
			(type default)
		)
		(layer "F.Cu")
	)
	(gr_arc
		(start 17.690846 -426.411136)
		(mid 17.720679 -426.541433)
		(end 17.806924 -426.643546)
		(stroke
			(width 0.047498)
			(type default)
		)
		(layer "F.Cu")
	)
	(gr_arc
		(start 17.690846 -424.909996)
		(mid 17.720701 -425.040276)
		(end 17.806924 -425.142406)
		(stroke
			(width 0.047498)
			(type default)
		)
		(layer "F.Cu")
	)
	(gr_arc
		(start 17.806924 -444.18377)
		(mid 17.720643 -444.285868)
		(end 17.690846 -444.41618)
		(stroke
			(width 0.047498)
			(type default)
		)
		(layer "F.Cu")
	)
	(gr_arc
		(start 17.806924 -444.18377)
		(mid 17.893323 -444.081696)
		(end 17.923256 -443.95136)
		(stroke
			(width 0.047498)
			(type default)
		)
		(layer "F.Cu")
	)
	(gr_arc
		(start 17.806924 -442.68263)
		(mid 17.720628 -442.784725)
		(end 17.690846 -442.91504)
		(stroke
			(width 0.047498)
			(type default)
		)
		(layer "F.Cu")
	)
	(gr_arc
		(start 17.806924 -442.68263)
		(mid 17.893323 -442.580556)
		(end 17.923256 -442.45022)
		(stroke
			(width 0.047498)
			(type default)
		)
		(layer "F.Cu")
	)
	(gr_arc
		(start 17.806924 -435.354984)
		(mid 17.720648 -435.457083)
		(end 17.690846 -435.587394)
		(stroke
			(width 0.047498)
			(type default)
		)
		(layer "F.Cu")
	)
	(gr_arc
		(start 17.806924 -435.354984)
		(mid 17.893323 -435.25291)
		(end 17.923256 -435.122574)
		(stroke
			(width 0.047498)
			(type default)
		)
		(layer "F.Cu")
	)
	(gr_arc
		(start 17.806924 -433.853844)
		(mid 17.720633 -433.95594)
		(end 17.690846 -434.086254)
		(stroke
			(width 0.047498)
			(type default)
		)
		(layer "F.Cu")
	)
	(gr_arc
		(start 17.806924 -433.853844)
		(mid 17.893323 -433.75177)
		(end 17.923256 -433.621434)
		(stroke
			(width 0.047498)
			(type default)
		)
		(layer "F.Cu")
	)
	(gr_arc
		(start 17.806924 -432.352704)
		(mid 17.720655 -432.454805)
		(end 17.690846 -432.585114)
		(stroke
			(width 0.047498)
			(type default)
		)
		(layer "F.Cu")
	)
	(gr_arc
		(start 17.806924 -432.352704)
		(mid 17.893323 -432.25063)
		(end 17.923256 -432.120294)
		(stroke
			(width 0.047498)
			(type default)
		)
		(layer "F.Cu")
	)
	(gr_arc
		(start 17.806924 -428.895256)
		(mid 17.720638 -428.997353)
		(end 17.690846 -429.127666)
		(stroke
			(width 0.047498)
			(type default)
		)
		(layer "F.Cu")
	)
	(gr_arc
		(start 17.806924 -428.895256)
		(mid 17.893323 -428.793182)
		(end 17.923256 -428.662846)
		(stroke
			(width 0.047498)
			(type default)
		)
		(layer "F.Cu")
	)
	(gr_arc
		(start 17.806924 -427.394116)
		(mid 17.720623 -427.49621)
		(end 17.690846 -427.626526)
		(stroke
			(width 0.047498)
			(type default)
		)
		(layer "F.Cu")
	)
	(gr_arc
		(start 17.806924 -427.394116)
		(mid 17.893323 -427.292042)
		(end 17.923256 -427.161706)
		(stroke
			(width 0.047498)
			(type default)
		)
		(layer "F.Cu")
	)
	(gr_arc
		(start 17.806924 -425.892976)
		(mid 17.720645 -425.995075)
		(end 17.690846 -426.125386)
		(stroke
			(width 0.047498)
			(type default)
		)
		(layer "F.Cu")
	)
	(gr_arc
		(start 17.806924 -425.892976)
		(mid 17.893323 -425.790902)
		(end 17.923256 -425.660566)
		(stroke
			(width 0.047498)
			(type default)
		)
		(layer "F.Cu")
	)
	(gr_arc
		(start 17.923256 -443.66561)
		(mid 17.89332 -443.535275)
		(end 17.806924 -443.4332)
		(stroke
			(width 0.047498)
			(type default)
		)
		(layer "F.Cu")
	)
	(gr_line
		(start 17.923256 -443.66561)
		(end 17.923256 -443.95136)
		(stroke
			(width 0.047498)
			(type default)
		)
		(layer "F.Cu")
	)
	(gr_arc
		(start 17.923256 -442.16447)
		(mid 17.89332 -442.034135)
		(end 17.806924 -441.93206)
		(stroke
			(width 0.047498)
			(type default)
		)
		(layer "F.Cu")
	)
	(gr_line
		(start 17.923256 -442.16447)
		(end 17.923256 -442.45022)
		(stroke
			(width 0.047498)
			(type default)
		)
		(layer "F.Cu")
	)
	(gr_arc
		(start 17.923256 -434.836824)
		(mid 17.89332 -434.706489)
		(end 17.806924 -434.604414)
		(stroke
			(width 0.047498)
			(type default)
		)
		(layer "F.Cu")
	)
	(gr_line
		(start 17.923256 -434.836824)
		(end 17.923256 -435.122574)
		(stroke
			(width 0.047498)
			(type default)
		)
		(layer "F.Cu")
	)
	(gr_arc
		(start 17.923256 -433.335684)
		(mid 17.89332 -433.205349)
		(end 17.806924 -433.103274)
		(stroke
			(width 0.047498)
			(type default)
		)
		(layer "F.Cu")
	)
	(gr_line
		(start 17.923256 -433.335684)
		(end 17.923256 -433.621434)
		(stroke
			(width 0.047498)
			(type default)
		)
		(layer "F.Cu")
	)
	(gr_arc
		(start 17.923256 -431.834544)
		(mid 17.89332 -431.704209)
		(end 17.806924 -431.602134)
		(stroke
			(width 0.047498)
			(type default)
		)
		(layer "F.Cu")
	)
	(gr_line
		(start 17.923256 -431.834544)
		(end 17.923256 -432.120294)
		(stroke
			(width 0.047498)
			(type default)
		)
		(layer "F.Cu")
	)
	(gr_arc
		(start 17.923256 -428.377096)
		(mid 17.89332 -428.246761)
		(end 17.806924 -428.144686)
		(stroke
			(width 0.047498)
			(type default)
		)
		(layer "F.Cu")
	)
	(gr_line
		(start 17.923256 -428.377096)
		(end 17.923256 -428.662846)
		(stroke
			(width 0.047498)
			(type default)
		)
		(layer "F.Cu")
	)
	(gr_arc
		(start 17.923256 -426.875956)
		(mid 17.89332 -426.745621)
		(end 17.806924 -426.643546)
		(stroke
			(width 0.047498)
			(type default)
		)
		(layer "F.Cu")
	)
	(gr_line
		(start 17.923256 -426.875956)
		(end 17.923256 -427.161706)
		(stroke
			(width 0.047498)
			(type default)
		)
		(layer "F.Cu")
	)
	(gr_arc
		(start 17.923256 -425.374816)
		(mid 17.89332 -425.244481)
		(end 17.806924 -425.142406)
		(stroke
			(width 0.047498)
			(type default)
		)
		(layer "F.Cu")
	)
	(gr_line
		(start 17.923256 -425.374816)
		(end 17.923256 -425.660566)
		(stroke
			(width 0.047498)
			(type default)
		)
		(layer "F.Cu")
	)
	(gr_line
		(start 18.402046 -308.2544)
		(end 18.40738 -308.259734)
		(stroke
			(width 0.047498)
			(type default)
		)
		(layer "F.Cu")
	)
	(gr_line
		(start 18.42389 -277.390098)
		(end 18.657316 -277.156672)
		(stroke
			(width 0.047498)
			(type default)
		)
		(layer "F.Cu")
	)
	(gr_line
		(start 18.4404 -351.409)
		(end 18.445734 -351.414334)
		(stroke
			(width 0.047498)
			(type default)
		)
		(layer "F.Cu")
	)
	(gr_line
		(start 18.607786 -418.470588)
		(end 18.608548 -418.469826)
		(stroke
			(width 0.047498)
			(type default)
		)
		(layer "F.Cu")
	)
	(gr_line
		(start 18.799048 -358.02189)
		(end 18.949416 -357.871522)
		(stroke
			(width 0.047498)
			(type default)
		)
		(layer "F.Cu")
	)
	(gr_line
		(start 18.816066 -351.784666)
		(end 18.8214 -351.79)
		(stroke
			(width 0.047498)
			(type default)
		)
		(layer "F.Cu")
	)
	(gr_line
		(start 19.032474 -358.255316)
		(end 19.174968 -358.112822)
		(stroke
			(width 0.047498)
			(type default)
		)
		(layer "F.Cu")
	)
	(gr_arc
		(start 19.350736 -313.679586)
		(mid 19.353538 -313.627676)
		(end 19.354546 -313.5757)
		(stroke
			(width 0.047498)
			(type default)
		)
		(layer "F.Cu")
	)
	(gr_arc
		(start 19.557746 -168.7957)
		(mid 19.735046 -168.574118)
		(end 19.859752 -168.319196)
		(stroke
			(width 0.047498)
			(type default)
		)
		(layer "F.Cu")
	)
	(gr_line
		(start 19.600164 -445.010032)
		(end 20.503896 -445.010032)
		(stroke
			(width 0.047498)
			(type default)
		)
		(layer "F.Cu")
	)
	(gr_line
		(start 19.600164 -444.210186)
		(end 20.3073 -444.210186)
		(stroke
			(width 0.047498)
			(type default)
		)
		(layer "F.Cu")
	)
	(gr_line
		(start 19.600164 -442.609986)
		(end 20.743672 -442.609986)
		(stroke
			(width 0.047498)
			(type default)
		)
		(layer "F.Cu")
	)
	(gr_line
		(start 19.600164 -441.81014)
		(end 20.495768 -441.81014)
		(stroke
			(width 0.047498)
			(type default)
		)
		(layer "F.Cu")
	)
	(gr_line
		(start 19.600164 -342.009984)
		(end 20.354036 -342.009984)
		(stroke
			(width 0.047498)
			(type default)
		)
		(layer "F.Cu")
	)
	(gr_line
		(start 19.600164 -341.210138)
		(end 20.53336 -341.210138)
		(stroke
			(width 0.047498)
			(type default)
		)
		(layer "F.Cu")
	)
	(gr_line
		(start 19.600164 -339.609938)
		(end 20.52066 -339.609938)
		(stroke
			(width 0.047498)
			(type default)
		)
		(layer "F.Cu")
	)
	(gr_line
		(start 19.600164 -338.810092)
		(end 20.383754 -338.810092)
		(stroke
			(width 0.047498)
			(type default)
		)
		(layer "F.Cu")
	)
	(gr_line
		(start 19.600164 -239.009936)
		(end 20.530312 -239.009936)
		(stroke
			(width 0.047498)
			(type default)
		)
		(layer "F.Cu")
	)
	(gr_line
		(start 19.600164 -238.21009)
		(end 20.508214 -238.21009)
		(stroke
			(width 0.047498)
			(type default)
		)
		(layer "F.Cu")
	)
	(gr_line
		(start 19.600164 -236.60989)
		(end 20.48637 -236.60989)
		(stroke
			(width 0.047498)
			(type default)
		)
		(layer "F.Cu")
	)
	(gr_line
		(start 19.600164 -235.810044)
		(end 20.586192 -235.810044)
		(stroke
			(width 0.047498)
			(type default)
		)
		(layer "F.Cu")
	)
	(gr_line
		(start 19.600164 -136.009888)
		(end 20.41144 -136.009888)
		(stroke
			(width 0.047498)
			(type default)
		)
		(layer "F.Cu")
	)
	(gr_line
		(start 19.600164 -135.210042)
		(end 20.488148 -135.210042)
		(stroke
			(width 0.047498)
			(type default)
		)
		(layer "F.Cu")
	)
	(gr_line
		(start 19.600164 -133.609842)
		(end 20.362164 -133.609842)
		(stroke
			(width 0.047498)
			(type default)
		)
		(layer "F.Cu")
	)
	(gr_line
		(start 19.600164 -132.809996)
		(end 20.54987 -132.809996)
		(stroke
			(width 0.047498)
			(type default)
		)
		(layer "F.Cu")
	)
	(gr_line
		(start 19.600164 -33.00984)
		(end 20.17903 -33.00984)
		(stroke
			(width 0.047498)
			(type default)
		)
		(layer "F.Cu")
	)
	(gr_line
		(start 19.600164 -32.209994)
		(end 20.089876 -32.209994)
		(stroke
			(width 0.047498)
			(type default)
		)
		(layer "F.Cu")
	)
	(gr_line
		(start 19.600164 -30.609794)
		(end 20.17903 -30.609794)
		(stroke
			(width 0.047498)
			(type default)
		)
		(layer "F.Cu")
	)
	(gr_line
		(start 19.600164 -29.809948)
		(end 20.089876 -29.809948)
		(stroke
			(width 0.047498)
			(type default)
		)
		(layer "F.Cu")
	)
	(gr_arc
		(start 19.859752 -168.319196)
		(mid 19.905835 -168.159948)
		(end 19.931126 -167.996108)
		(stroke
			(width 0.047498)
			(type default)
		)
		(layer "F.Cu")
	)
	(gr_line
		(start 19.986498 -167.644826)
		(end 19.988276 -167.638984)
		(stroke
			(width 0.047498)
			(type default)
		)
		(layer "F.Cu")
	)
	(gr_line
		(start 20.089876 -32.209994)
		(end 20.093178 -32.206692)
		(stroke
			(width 0.047498)
			(type default)
		)
		(layer "F.Cu")
	)
	(gr_line
		(start 20.089876 -29.809948)
		(end 20.093178 -29.806646)
		(stroke
			(width 0.047498)
			(type default)
		)
		(layer "F.Cu")
	)
	(gr_line
		(start 20.116546 -459.1177)
		(end 20.406868 -459.1177)
		(stroke
			(width 0.047498)
			(type default)
		)
		(layer "F.Cu")
	)
	(gr_line
		(start 20.17903 -33.00984)
		(end 20.182332 -33.006538)
		(stroke
			(width 0.047498)
			(type default)
		)
		(layer "F.Cu")
	)
	(gr_line
		(start 20.17903 -30.609794)
		(end 20.182332 -30.606492)
		(stroke
			(width 0.047498)
			(type default)
		)
		(layer "F.Cu")
	)
	(gr_arc
		(start 20.182332 -33.006538)
		(mid 20.420573 -32.964572)
		(end 20.630134 -32.843724)
		(stroke
			(width 0.047498)
			(type default)
		)
		(layer "F.Cu")
	)
	(gr_arc
		(start 20.182332 -30.606492)
		(mid 20.420573 -30.564526)
		(end 20.630134 -30.443678)
		(stroke
			(width 0.047498)
			(type default)
		)
		(layer "F.Cu")
	)
	(gr_arc
		(start 20.23872 -168.208198)
		(mid 20.236613 -168.336009)
		(end 20.257008 -168.462198)
		(stroke
			(width 0.047498)
			(type default)
		)
		(layer "F.Cu")
	)
	(gr_line
		(start 20.23872 -168.208198)
		(end 20.273264 -167.880538)
		(stroke
			(width 0.047498)
			(type default)
		)
		(layer "F.Cu")
	)
	(gr_arc
		(start 20.257008 -168.462198)
		(mid 20.329352 -168.641766)
		(end 20.446746 -168.7957)
		(stroke
			(width 0.047498)
			(type default)
		)
		(layer "F.Cu")
	)
	(gr_line
		(start 20.3073 -444.210186)
		(end 20.310602 -444.206884)
		(stroke
			(width 0.047498)
			(type default)
		)
		(layer "F.Cu")
	)
	(gr_line
		(start 20.314158 -167.707818)
		(end 20.314158 -167.708072)
		(stroke
			(width 0.047498)
			(type default)
		)
		(layer "F.Cu")
	)
	(gr_line
		(start 20.354036 -342.009984)
		(end 20.357338 -342.006682)
		(stroke
			(width 0.047498)
			(type default)
		)
		(layer "F.Cu")
	)
	(gr_arc
		(start 20.357338 -342.006682)
		(mid 20.666925 -341.945101)
		(end 20.929346 -341.7697)
		(stroke
			(width 0.047498)
			(type default)
		)
		(layer "F.Cu")
	)
	(gr_line
		(start 20.362164 -133.609842)
		(end 20.365466 -133.60654)
		(stroke
			(width 0.047498)
			(type default)
		)
		(layer "F.Cu")
	)
	(gr_arc
		(start 20.365466 -133.60654)
		(mid 20.567387 -133.577008)
		(end 20.752308 -133.490716)
		(stroke
			(width 0.047498)
			(type default)
		)
		(layer "F.Cu")
	)
	(gr_line
		(start 20.383754 -338.810092)
		(end 20.387056 -338.80679)
		(stroke
			(width 0.047498)
			(type default)
		)
		(layer "F.Cu")
	)
	(gr_arc
		(start 20.406868 -459.1177)
		(mid 20.426806 -459.118053)
		(end 20.446746 -459.118208)
		(stroke
			(width 0.047498)
			(type default)
		)
		(layer "F.Cu")
	)
	(gr_line
		(start 20.41144 -136.009888)
		(end 20.414742 -136.006586)
		(stroke
			(width 0.047498)
			(type default)
		)
		(layer "F.Cu")
	)
	(gr_arc
		(start 20.414742 -136.006586)
		(mid 20.593982 -135.970933)
		(end 20.745958 -135.869426)
		(stroke
			(width 0.047498)
			(type default)
		)
		(layer "F.Cu")
	)
	(gr_line
		(start 20.446746 -458.7875)
		(end 20.446746 -458.787754)
		(stroke
			(width 0.047498)
			(type default)
		)
		(layer "F.Cu")
	)
	(gr_arc
		(start 20.48637 -236.60989)
		(mid 20.676496 -236.572072)
		(end 20.837652 -236.464348)
		(stroke
			(width 0.047498)
			(type default)
		)
		(layer "F.Cu")
	)
	(gr_line
		(start 20.488148 -135.210042)
		(end 20.49145 -135.20674)
		(stroke
			(width 0.047498)
			(type default)
		)
		(layer "F.Cu")
	)
	(gr_line
		(start 20.495768 -441.81014)
		(end 20.49907 -441.806838)
		(stroke
			(width 0.047498)
			(type default)
		)
		(layer "F.Cu")
	)
	(gr_line
		(start 20.503896 -445.010032)
		(end 20.507198 -445.00673)
		(stroke
			(width 0.047498)
			(type default)
		)
		(layer "F.Cu")
	)
	(gr_arc
		(start 20.507198 -445.00673)
		(mid 20.633403 -444.991228)
		(end 20.752054 -444.945516)
		(stroke
			(width 0.047498)
			(type default)
		)
		(layer "F.Cu")
	)
	(gr_line
		(start 20.508214 -238.21009)
		(end 20.511516 -238.206788)
		(stroke
			(width 0.047498)
			(type default)
		)
		(layer "F.Cu")
	)
	(gr_line
		(start 20.52066 -339.609938)
		(end 20.523962 -339.606636)
		(stroke
			(width 0.047498)
			(type default)
		)
		(layer "F.Cu")
	)
	(gr_arc
		(start 20.522946 -32.384746)
		(mid 20.325777 -32.252957)
		(end 20.093178 -32.206692)
		(stroke
			(width 0.047498)
			(type default)
		)
		(layer "F.Cu")
	)
	(gr_arc
		(start 20.522946 -32.384746)
		(mid 20.619671 -32.449376)
		(end 20.733766 -32.472122)
		(stroke
			(width 0.047498)
			(type default)
		)
		(layer "F.Cu")
	)
	(gr_arc
		(start 20.522946 -29.9847)
		(mid 20.32578 -29.8529)
		(end 20.093178 -29.806646)
		(stroke
			(width 0.047498)
			(type default)
		)
		(layer "F.Cu")
	)
	(gr_arc
		(start 20.522946 -29.9847)
		(mid 20.619671 -30.04933)
		(end 20.733766 -30.072076)
		(stroke
			(width 0.047498)
			(type default)
		)
		(layer "F.Cu")
	)
	(gr_arc
		(start 20.523962 -339.606636)
		(mid 20.687261 -339.574154)
		(end 20.825714 -339.481668)
		(stroke
			(width 0.047498)
			(type default)
		)
		(layer "F.Cu")
	)
	(gr_line
		(start 20.530312 -239.009936)
		(end 20.533614 -239.006634)
		(stroke
			(width 0.047498)
			(type default)
		)
		(layer "F.Cu")
	)
	(gr_line
		(start 20.53336 -341.210138)
		(end 20.536662 -341.206836)
		(stroke
			(width 0.047498)
			(type default)
		)
		(layer "F.Cu")
	)
	(gr_arc
		(start 20.533614 -239.006634)
		(mid 20.706536 -238.972238)
		(end 20.853146 -238.8743)
		(stroke
			(width 0.047498)
			(type default)
		)
		(layer "F.Cu")
	)
	(gr_line
		(start 20.54987 -132.809996)
		(end 20.553172 -132.806694)
		(stroke
			(width 0.047498)
			(type default)
		)
		(layer "F.Cu")
	)
	(gr_arc
		(start 20.648422 -444.346838)
		(mid 20.493438 -444.243241)
		(end 20.310602 -444.206884)
		(stroke
			(width 0.047498)
			(type default)
		)
		(layer "F.Cu")
	)
	(gr_line
		(start 20.648422 -444.346838)
		(end 20.715732 -444.414402)
		(stroke
			(width 0.047498)
			(type default)
		)
		(layer "F.Cu")
	)
	(gr_line
		(start 20.700746 -455.891646)
		(end 20.700746 -455.8919)
		(stroke
			(width 0.047498)
			(type default)
		)
		(layer "F.Cu")
	)
	(gr_line
		(start 20.700746 -455.5617)
		(end 21.030946 -455.5617)
		(stroke
			(width 0.047498)
			(type default)
		)
		(layer "F.Cu")
	)
	(gr_arc
		(start 20.715732 -444.414402)
		(mid 20.824577 -444.48713)
		(end 20.952968 -444.5127)
		(stroke
			(width 0.047498)
			(type default)
		)
		(layer "F.Cu")
	)
	(gr_arc
		(start 20.73021 -32.802322)
		(mid 20.676041 -32.81304)
		(end 20.630134 -32.843724)
		(stroke
			(width 0.047498)
			(type default)
		)
		(layer "F.Cu")
	)
	(gr_arc
		(start 20.73021 -30.402276)
		(mid 20.676038 -30.412992)
		(end 20.630134 -30.443678)
		(stroke
			(width 0.047498)
			(type default)
		)
		(layer "F.Cu")
	)
	(gr_line
		(start 20.743672 -442.609986)
		(end 20.746974 -442.606684)
		(stroke
			(width 0.047498)
			(type default)
		)
		(layer "F.Cu")
	)
	(gr_arc
		(start 20.746974 -442.606684)
		(mid 20.816959 -442.592763)
		(end 20.87626 -442.55309)
		(stroke
			(width 0.047498)
			(type default)
		)
		(layer "F.Cu")
	)
	(gr_line
		(start 20.752054 -444.945516)
		(end 20.784566 -444.913004)
		(stroke
			(width 0.047498)
			(type default)
		)
		(layer "F.Cu")
	)
	(gr_arc
		(start 20.753832 -135.315452)
		(mid 20.63346 -135.234982)
		(end 20.49145 -135.20674)
		(stroke
			(width 0.047498)
			(type default)
		)
		(layer "F.Cu")
	)
	(gr_arc
		(start 20.753832 -135.315452)
		(mid 20.869786 -135.39293)
		(end 21.006562 -135.4201)
		(stroke
			(width 0.047498)
			(type default)
		)
		(layer "F.Cu")
	)
	(gr_arc
		(start 20.764246 -338.963)
		(mid 20.591181 -338.847394)
		(end 20.387056 -338.80679)
		(stroke
			(width 0.047498)
			(type default)
		)
		(layer "F.Cu")
	)
	(gr_arc
		(start 20.764246 -338.963)
		(mid 20.834634 -339.010032)
		(end 20.917662 -339.0265)
		(stroke
			(width 0.047498)
			(type default)
		)
		(layer "F.Cu")
	)
	(gr_arc
		(start 20.776946 -441.9219)
		(mid 20.649447 -441.836738)
		(end 20.49907 -441.806838)
		(stroke
			(width 0.047498)
			(type default)
		)
		(layer "F.Cu")
	)
	(gr_line
		(start 20.776946 -441.9219)
		(end 20.891246 -442.0362)
		(stroke
			(width 0.047498)
			(type default)
		)
		(layer "F.Cu")
	)
	(gr_arc
		(start 20.820888 -444.883286)
		(mid 20.801998 -444.897254)
		(end 20.784566 -444.913004)
		(stroke
			(width 0.047498)
			(type default)
		)
		(layer "F.Cu")
	)
	(gr_arc
		(start 20.853146 -341.3379)
		(mid 20.707933 -341.240903)
		(end 20.536662 -341.206836)
		(stroke
			(width 0.047498)
			(type default)
		)
		(layer "F.Cu")
	)
	(gr_arc
		(start 20.853146 -341.3379)
		(mid 20.909433 -341.37551)
		(end 20.975828 -341.3887)
		(stroke
			(width 0.047498)
			(type default)
		)
		(layer "F.Cu")
	)
	(gr_line
		(start 20.853146 -238.8743)
		(end 20.865084 -238.862616)
		(stroke
			(width 0.047498)
			(type default)
		)
		(layer "F.Cu")
	)
	(gr_arc
		(start 20.853146 -132.9309)
		(mid 20.715503 -132.838984)
		(end 20.553172 -132.806694)
		(stroke
			(width 0.047498)
			(type default)
		)
		(layer "F.Cu")
	)
	(gr_arc
		(start 20.853146 -132.9309)
		(mid 21.013669 -133.045982)
		(end 21.20265 -133.103366)
		(stroke
			(width 0.047498)
			(type default)
		)
		(layer "F.Cu")
	)
	(gr_arc
		(start 20.865846 -238.3536)
		(mid 20.703292 -238.244933)
		(end 20.511516 -238.206788)
		(stroke
			(width 0.047498)
			(type default)
		)
		(layer "F.Cu")
	)
	(gr_arc
		(start 20.865846 -238.3536)
		(mid 20.964319 -238.419398)
		(end 21.080476 -238.4425)
		(stroke
			(width 0.047498)
			(type default)
		)
		(layer "F.Cu")
	)
	(gr_arc
		(start 20.877276 -133.4389)
		(mid 20.809653 -133.452411)
		(end 20.752308 -133.490716)
		(stroke
			(width 0.047498)
			(type default)
		)
		(layer "F.Cu")
	)
	(gr_line
		(start 20.877276 -133.4389)
		(end 20.949666 -133.4389)
		(stroke
			(width 0.047498)
			(type default)
		)
		(layer "F.Cu")
	)
	(gr_arc
		(start 20.891246 -442.0362)
		(mid 20.961634 -442.083232)
		(end 21.044662 -442.0997)
		(stroke
			(width 0.047498)
			(type default)
		)
		(layer "F.Cu")
	)
	(gr_arc
		(start 20.911312 -235.90631)
		(mid 20.755728 -235.834619)
		(end 20.586192 -235.810044)
		(stroke
			(width 0.047498)
			(type default)
		)
		(layer "F.Cu")
	)
	(gr_arc
		(start 20.911312 -235.90631)
		(mid 21.044287 -235.967605)
		(end 21.189188 -235.988606)
		(stroke
			(width 0.047498)
			(type default)
		)
		(layer "F.Cu")
	)
	(gr_arc
		(start 20.954492 -444.8429)
		(mid 20.884703 -444.853207)
		(end 20.820888 -444.883286)
		(stroke
			(width 0.047498)
			(type default)
		)
		(layer "F.Cu")
	)
	(gr_arc
		(start 21.033486 -135.7503)
		(mid 20.877882 -135.781283)
		(end 20.745958 -135.869426)
		(stroke
			(width 0.047498)
			(type default)
		)
		(layer "F.Cu")
	)
	(gr_arc
		(start 21.041106 -238.789718)
		(mid 20.945849 -238.808666)
		(end 20.865084 -238.862616)
		(stroke
			(width 0.047498)
			(type default)
		)
		(layer "F.Cu")
	)
	(gr_line
		(start 21.041106 -238.789718)
		(end 21.652484 -238.789718)
		(stroke
			(width 0.047498)
			(type default)
		)
		(layer "F.Cu")
	)
	(gr_arc
		(start 21.052028 -341.7189)
		(mid 20.985638 -341.732101)
		(end 20.929346 -341.7697)
		(stroke
			(width 0.047498)
			(type default)
		)
		(layer "F.Cu")
	)
	(gr_line
		(start 21.080476 -238.4425)
		(end 21.486368 -238.4425)
		(stroke
			(width 0.047498)
			(type default)
		)
		(layer "F.Cu")
	)
	(gr_arc
		(start 21.127466 -339.3567)
		(mid 20.96416 -339.389168)
		(end 20.825714 -339.481668)
		(stroke
			(width 0.047498)
			(type default)
		)
		(layer "F.Cu")
	)
	(gr_arc
		(start 21.173694 -442.4299)
		(mid 21.012731 -442.461921)
		(end 20.87626 -442.55309)
		(stroke
			(width 0.047498)
			(type default)
		)
		(layer "F.Cu")
	)
	(gr_arc
		(start 21.188934 -236.318806)
		(mid 20.998833 -236.356669)
		(end 20.837652 -236.464348)
		(stroke
			(width 0.047498)
			(type default)
		)
		(layer "F.Cu")
	)
	(gr_arc
		(start 21.20265 -133.103366)
		(mid 21.24244 -133.107345)
		(end 21.282406 -133.1087)
		(stroke
			(width 0.047498)
			(type default)
		)
		(layer "F.Cu")
	)
	(gr_arc
		(start 21.208746 -444.5127)
		(mid 21.387597 -444.477124)
		(end 21.5392 -444.375794)
		(stroke
			(width 0.047498)
			(type default)
		)
		(layer "F.Cu")
	)
	(gr_arc
		(start 21.270976 -444.856108)
		(mid 21.199655 -444.846174)
		(end 21.12772 -444.8429)
		(stroke
			(width 0.047498)
			(type default)
		)
		(layer "F.Cu")
	)
	(gr_arc
		(start 21.340318 -341.3887)
		(mid 21.735248 -341.310144)
		(end 22.07006 -341.08644)
		(stroke
			(width 0.047498)
			(type default)
		)
		(layer "F.Cu")
	)
	(gr_arc
		(start 21.342604 -135.4201)
		(mid 21.641304 -135.360685)
		(end 21.894546 -135.1915)
		(stroke
			(width 0.047498)
			(type default)
		)
		(layer "F.Cu")
	)
	(gr_arc
		(start 21.462746 -32.472122)
		(mid 21.699043 -32.42512)
		(end 21.899372 -32.291274)
		(stroke
			(width 0.047498)
			(type default)
		)
		(layer "F.Cu")
	)
	(gr_arc
		(start 21.486368 -238.4425)
		(mid 21.652291 -238.409496)
		(end 21.792946 -238.3155)
		(stroke
			(width 0.047498)
			(type default)
		)
		(layer "F.Cu")
	)
	(gr_line
		(start 21.5392 -444.375794)
		(end 21.611336 -444.303658)
		(stroke
			(width 0.047498)
			(type default)
		)
		(layer "F.Cu")
	)
	(gr_arc
		(start 21.586444 -135.842248)
		(mid 21.484485 -135.774109)
		(end 21.364194 -135.7503)
		(stroke
			(width 0.047498)
			(type default)
		)
		(layer "F.Cu")
	)
	(gr_line
		(start 21.586444 -135.842248)
		(end 21.894546 -136.15035)
		(stroke
			(width 0.047498)
			(type default)
		)
		(layer "F.Cu")
	)
	(gr_arc
		(start 21.611336 -444.303658)
		(mid 21.632959 -444.271392)
		(end 21.640546 -444.2333)
		(stroke
			(width 0.047498)
			(type default)
		)
		(layer "F.Cu")
	)
	(gr_arc
		(start 21.640546 -444.207392)
		(mid 21.639911 -444.207387)
		(end 21.639276 -444.207392)
		(stroke
			(width 0.047498)
			(type default)
		)
		(layer "F.Cu")
	)
	(gr_line
		(start 21.640546 -444.207392)
		(end 21.640546 -444.2333)
		(stroke
			(width 0.047498)
			(type default)
		)
		(layer "F.Cu")
	)
	(gr_arc
		(start 21.676614 -445.07023)
		(mid 21.489991 -444.932488)
		(end 21.270976 -444.856108)
		(stroke
			(width 0.047498)
			(type default)
		)
		(layer "F.Cu")
	)
	(gr_line
		(start 21.717 -352.6282)
		(end 21.722334 -352.633534)
		(stroke
			(width 0.047498)
			(type default)
		)
		(layer "F.Cu")
	)
	(gr_line
		(start 21.75002 -452.930006)
		(end 23.052532 -452.930006)
		(stroke
			(width 0.047498)
			(type default)
		)
		(layer "F.Cu")
	)
	(gr_line
		(start 21.75002 -451.660006)
		(end 22.973538 -451.660006)
		(stroke
			(width 0.047498)
			(type default)
		)
		(layer "F.Cu")
	)
	(gr_line
		(start 21.75002 -449.120006)
		(end 22.919436 -449.120006)
		(stroke
			(width 0.047498)
			(type default)
		)
		(layer "F.Cu")
	)
	(gr_line
		(start 21.75002 -447.850006)
		(end 22.9616 -447.850006)
		(stroke
			(width 0.047498)
			(type default)
		)
		(layer "F.Cu")
	)
	(gr_line
		(start 21.75002 -349.929958)
		(end 23.039578 -349.929958)
		(stroke
			(width 0.047498)
			(type default)
		)
		(layer "F.Cu")
	)
	(gr_line
		(start 21.75002 -348.659958)
		(end 22.932898 -348.659958)
		(stroke
			(width 0.047498)
			(type default)
		)
		(layer "F.Cu")
	)
	(gr_line
		(start 21.75002 -346.119958)
		(end 23.12162 -346.119958)
		(stroke
			(width 0.047498)
			(type default)
		)
		(layer "F.Cu")
	)
	(gr_line
		(start 21.75002 -344.849958)
		(end 23.050754 -344.849958)
		(stroke
			(width 0.047498)
			(type default)
		)
		(layer "F.Cu")
	)
	(gr_line
		(start 21.75002 -246.92991)
		(end 22.986492 -246.92991)
		(stroke
			(width 0.047498)
			(type default)
		)
		(layer "F.Cu")
	)
	(gr_line
		(start 21.75002 -245.65991)
		(end 23.01367 -245.65991)
		(stroke
			(width 0.047498)
			(type default)
		)
		(layer "F.Cu")
	)
	(gr_line
		(start 21.75002 -243.11991)
		(end 22.986492 -243.11991)
		(stroke
			(width 0.047498)
			(type default)
		)
		(layer "F.Cu")
	)
	(gr_line
		(start 21.75002 -241.84991)
		(end 22.698456 -241.84991)
		(stroke
			(width 0.047498)
			(type default)
		)
		(layer "F.Cu")
	)
	(gr_line
		(start 21.75002 -143.929862)
		(end 23.049992 -143.929862)
		(stroke
			(width 0.047498)
			(type default)
		)
		(layer "F.Cu")
	)
	(gr_line
		(start 21.75002 -142.659862)
		(end 23.009098 -142.659862)
		(stroke
			(width 0.047498)
			(type default)
		)
		(layer "F.Cu")
	)
	(gr_line
		(start 21.75002 -140.119862)
		(end 22.963124 -140.119862)
		(stroke
			(width 0.047498)
			(type default)
		)
		(layer "F.Cu")
	)
	(gr_line
		(start 21.75002 -138.849862)
		(end 23.03653 -138.849862)
		(stroke
			(width 0.047498)
			(type default)
		)
		(layer "F.Cu")
	)
	(gr_line
		(start 21.75002 -40.929814)
		(end 23.011638 -40.929814)
		(stroke
			(width 0.047498)
			(type default)
		)
		(layer "F.Cu")
	)
	(gr_line
		(start 21.75002 -39.659814)
		(end 22.960584 -39.659814)
		(stroke
			(width 0.047498)
			(type default)
		)
		(layer "F.Cu")
	)
	(gr_line
		(start 21.75002 -37.119814)
		(end 23.055072 -37.119814)
		(stroke
			(width 0.047498)
			(type default)
		)
		(layer "F.Cu")
	)
	(gr_line
		(start 21.75002 -35.849814)
		(end 23.0632 -35.849814)
		(stroke
			(width 0.047498)
			(type default)
		)
		(layer "F.Cu")
	)
	(gr_line
		(start 21.792946 -238.3155)
		(end 21.83765 -238.270796)
		(stroke
			(width 0.047498)
			(type default)
		)
		(layer "F.Cu")
	)
	(gr_arc
		(start 21.83765 -238.270796)
		(mid 21.917332 -238.151449)
		(end 21.945346 -238.0107)
		(stroke
			(width 0.047498)
			(type default)
		)
		(layer "F.Cu")
	)
	(gr_arc
		(start 21.843746 -238.868966)
		(mid 21.756 -238.81031)
		(end 21.652484 -238.789718)
		(stroke
			(width 0.047498)
			(type default)
		)
		(layer "F.Cu")
	)
	(gr_line
		(start 21.899372 -32.291274)
		(end 21.996146 -32.1945)
		(stroke
			(width 0.047498)
			(type default)
		)
		(layer "F.Cu")
	)
	(gr_line
		(start 21.991066 -352.902266)
		(end 21.9964 -352.9076)
		(stroke
			(width 0.047498)
			(type default)
		)
		(layer "F.Cu")
	)
	(gr_arc
		(start 22.068028 -342.043258)
		(mid 21.708746 -341.803192)
		(end 21.284946 -341.7189)
		(stroke
			(width 0.047498)
			(type default)
		)
		(layer "F.Cu")
	)
	(gr_line
		(start 22.068028 -342.043258)
		(end 22.07006 -342.04529)
		(stroke
			(width 0.047498)
			(type default)
		)
		(layer "F.Cu")
	)
	(gr_arc
		(start 22.072346 -33.157922)
		(mid 21.968204 -32.906444)
		(end 21.716746 -32.802322)
		(stroke
			(width 0.047498)
			(type default)
		)
		(layer "F.Cu")
	)
	(gr_line
		(start 22.072346 -33.157922)
		(end 22.072346 -33.164018)
		(stroke
			(width 0.047498)
			(type default)
		)
		(layer "F.Cu")
	)
	(gr_arc
		(start 22.34819 -183.43499)
		(mid 22.377987 -183.565308)
		(end 22.464268 -183.6674)
		(stroke
			(width 0.047498)
			(type default)
		)
		(layer "F.Cu")
	)
	(gr_line
		(start 22.34819 -183.14924)
		(end 22.34819 -183.43499)
		(stroke
			(width 0.047498)
			(type default)
		)
		(layer "F.Cu")
	)
	(gr_arc
		(start 22.34819 -180.232558)
		(mid 22.377987 -180.362876)
		(end 22.464268 -180.464968)
		(stroke
			(width 0.047498)
			(type default)
		)
		(layer "F.Cu")
	)
	(gr_line
		(start 22.34819 -179.946808)
		(end 22.34819 -180.232558)
		(stroke
			(width 0.047498)
			(type default)
		)
		(layer "F.Cu")
	)
	(gr_arc
		(start 22.34819 -178.731418)
		(mid 22.377987 -178.861736)
		(end 22.464268 -178.963828)
		(stroke
			(width 0.047498)
			(type default)
		)
		(layer "F.Cu")
	)
	(gr_line
		(start 22.34819 -178.445668)
		(end 22.34819 -178.731418)
		(stroke
			(width 0.047498)
			(type default)
		)
		(layer "F.Cu")
	)
	(gr_arc
		(start 22.34819 -177.230278)
		(mid 22.377987 -177.360596)
		(end 22.464268 -177.462688)
		(stroke
			(width 0.047498)
			(type default)
		)
		(layer "F.Cu")
	)
	(gr_line
		(start 22.34819 -176.944528)
		(end 22.34819 -177.230278)
		(stroke
			(width 0.047498)
			(type default)
		)
		(layer "F.Cu")
	)
	(gr_arc
		(start 22.34819 -171.540932)
		(mid 22.377987 -171.67125)
		(end 22.464268 -171.773342)
		(stroke
			(width 0.047498)
			(type default)
		)
		(layer "F.Cu")
	)
	(gr_line
		(start 22.34819 -171.255182)
		(end 22.34819 -171.540932)
		(stroke
			(width 0.047498)
			(type default)
		)
		(layer "F.Cu")
	)
	(gr_arc
		(start 22.34819 -170.039792)
		(mid 22.377987 -170.17011)
		(end 22.464268 -170.272202)
		(stroke
			(width 0.047498)
			(type default)
		)
		(layer "F.Cu")
	)
	(gr_line
		(start 22.34819 -169.754042)
		(end 22.34819 -170.039792)
		(stroke
			(width 0.047498)
			(type default)
		)
		(layer "F.Cu")
	)
	(gr_arc
		(start 22.34819 -168.538652)
		(mid 22.377987 -168.66897)
		(end 22.464268 -168.771062)
		(stroke
			(width 0.047498)
			(type default)
		)
		(layer "F.Cu")
	)
	(gr_line
		(start 22.34819 -168.252902)
		(end 22.34819 -168.538652)
		(stroke
			(width 0.047498)
			(type default)
		)
		(layer "F.Cu")
	)
	(gr_arc
		(start 22.464268 -182.91683)
		(mid 22.378037 -183.018947)
		(end 22.34819 -183.14924)
		(stroke
			(width 0.047498)
			(type default)
		)
		(layer "F.Cu")
	)
	(gr_arc
		(start 22.464268 -182.91683)
		(mid 22.550661 -182.814756)
		(end 22.5806 -182.68442)
		(stroke
			(width 0.047498)
			(type default)
		)
		(layer "F.Cu")
	)
	(gr_arc
		(start 22.464268 -179.714398)
		(mid 22.378037 -179.816515)
		(end 22.34819 -179.946808)
		(stroke
			(width 0.047498)
			(type default)
		)
		(layer "F.Cu")
	)
	(gr_arc
		(start 22.464268 -179.714398)
		(mid 22.550686 -179.612328)
		(end 22.5806 -179.481988)
		(stroke
			(width 0.047498)
			(type default)
		)
		(layer "F.Cu")
	)
	(gr_arc
		(start 22.464268 -178.213258)
		(mid 22.378037 -178.315375)
		(end 22.34819 -178.445668)
		(stroke
			(width 0.047498)
			(type default)
		)
		(layer "F.Cu")
	)
	(gr_arc
		(start 22.464268 -178.213258)
		(mid 22.550671 -178.111186)
		(end 22.5806 -177.980848)
		(stroke
			(width 0.047498)
			(type default)
		)
		(layer "F.Cu")
	)
	(gr_arc
		(start 22.464268 -176.712118)
		(mid 22.378037 -176.814235)
		(end 22.34819 -176.944528)
		(stroke
			(width 0.047498)
			(type default)
		)
		(layer "F.Cu")
	)
	(gr_arc
		(start 22.464268 -176.712118)
		(mid 22.550657 -176.610043)
		(end 22.5806 -176.479708)
		(stroke
			(width 0.047498)
			(type default)
		)
		(layer "F.Cu")
	)
	(gr_arc
		(start 22.464268 -171.022772)
		(mid 22.378037 -171.124889)
		(end 22.34819 -171.255182)
		(stroke
			(width 0.047498)
			(type default)
		)
		(layer "F.Cu")
	)
	(gr_arc
		(start 22.464268 -171.022772)
		(mid 22.550676 -170.920701)
		(end 22.5806 -170.790362)
		(stroke
			(width 0.047498)
			(type default)
		)
		(layer "F.Cu")
	)
	(gr_arc
		(start 22.464268 -169.521632)
		(mid 22.378037 -169.623749)
		(end 22.34819 -169.754042)
		(stroke
			(width 0.047498)
			(type default)
		)
		(layer "F.Cu")
	)
	(gr_arc
		(start 22.464268 -169.521632)
		(mid 22.550662 -169.419558)
		(end 22.5806 -169.289222)
		(stroke
			(width 0.047498)
			(type default)
		)
		(layer "F.Cu")
	)
	(gr_arc
		(start 22.464268 -168.020492)
		(mid 22.378037 -168.122609)
		(end 22.34819 -168.252902)
		(stroke
			(width 0.047498)
			(type default)
		)
		(layer "F.Cu")
	)
	(gr_arc
		(start 22.464268 -168.020492)
		(mid 22.550684 -167.918422)
		(end 22.5806 -167.788082)
		(stroke
			(width 0.047498)
			(type default)
		)
		(layer "F.Cu")
	)
	(gr_arc
		(start 22.5806 -183.89981)
		(mid 22.550683 -183.76946)
		(end 22.464268 -183.6674)
		(stroke
			(width 0.047498)
			(type default)
		)
		(layer "F.Cu")
	)
	(gr_arc
		(start 22.5806 -180.697378)
		(mid 22.550671 -180.567038)
		(end 22.464268 -180.464968)
		(stroke
			(width 0.047498)
			(type default)
		)
		(layer "F.Cu")
	)
	(gr_arc
		(start 22.5806 -179.196238)
		(mid 22.550657 -179.065909)
		(end 22.464268 -178.963828)
		(stroke
			(width 0.047498)
			(type default)
		)
		(layer "F.Cu")
	)
	(gr_arc
		(start 22.5806 -177.695098)
		(mid 22.550679 -177.564752)
		(end 22.464268 -177.462688)
		(stroke
			(width 0.047498)
			(type default)
		)
		(layer "F.Cu")
	)
	(gr_arc
		(start 22.5806 -172.005752)
		(mid 22.550662 -171.875419)
		(end 22.464268 -171.773342)
		(stroke
			(width 0.047498)
			(type default)
		)
		(layer "F.Cu")
	)
	(gr_arc
		(start 22.5806 -170.504612)
		(mid 22.550684 -170.374261)
		(end 22.464268 -170.272202)
		(stroke
			(width 0.047498)
			(type default)
		)
		(layer "F.Cu")
	)
	(gr_arc
		(start 22.5806 -169.003472)
		(mid 22.550669 -168.873133)
		(end 22.464268 -168.771062)
		(stroke
			(width 0.047498)
			(type default)
		)
		(layer "F.Cu")
	)
	(gr_line
		(start 22.698456 -241.84991)
		(end 22.698964 -241.850418)
		(stroke
			(width 0.047498)
			(type default)
		)
		(layer "F.Cu")
	)
	(gr_line
		(start 22.698964 -241.850418)
		(end 22.899624 -241.850418)
		(stroke
			(width 0.047498)
			(type default)
		)
		(layer "F.Cu")
	)
	(gr_arc
		(start 22.910038 -241.850926)
		(mid 22.904838 -241.85053)
		(end 22.899624 -241.850418)
		(stroke
			(width 0.047498)
			(type default)
		)
		(layer "F.Cu")
	)
	(gr_line
		(start 22.910038 -241.850926)
		(end 22.987 -241.859054)
		(stroke
			(width 0.047498)
			(type default)
		)
		(layer "F.Cu")
	)
	(gr_line
		(start 22.9108 -183.01716)
		(end 22.9108 -183.56707)
		(stroke
			(width 0.047498)
			(type default)
		)
		(layer "F.Cu")
	)
	(gr_line
		(start 22.9108 -179.814728)
		(end 22.9108 -180.364638)
		(stroke
			(width 0.047498)
			(type default)
		)
		(layer "F.Cu")
	)
	(gr_line
		(start 22.9108 -178.313588)
		(end 22.9108 -178.863498)
		(stroke
			(width 0.047498)
			(type default)
		)
		(layer "F.Cu")
	)
	(gr_line
		(start 22.9108 -176.812448)
		(end 22.9108 -177.362358)
		(stroke
			(width 0.047498)
			(type default)
		)
		(layer "F.Cu")
	)
	(gr_line
		(start 22.9108 -171.123102)
		(end 22.9108 -171.673012)
		(stroke
			(width 0.047498)
			(type default)
		)
		(layer "F.Cu")
	)
	(gr_line
		(start 22.9108 -169.621962)
		(end 22.9108 -170.171872)
		(stroke
			(width 0.047498)
			(type default)
		)
		(layer "F.Cu")
	)
	(gr_line
		(start 22.9108 -168.120822)
		(end 22.9108 -168.670732)
		(stroke
			(width 0.047498)
			(type default)
		)
		(layer "F.Cu")
	)
	(gr_arc
		(start 22.919436 -449.120006)
		(mid 22.961254 -449.115903)
		(end 23.001478 -449.10375)
		(stroke
			(width 0.047498)
			(type default)
		)
		(layer "F.Cu")
	)
	(gr_arc
		(start 22.963124 -140.119862)
		(mid 23.043121 -140.10395)
		(end 23.110952 -140.058648)
		(stroke
			(width 0.047498)
			(type default)
		)
		(layer "F.Cu")
	)
	(gr_arc
		(start 22.986492 -246.92991)
		(mid 23.117783 -246.875527)
		(end 23.172166 -246.744236)
		(stroke
			(width 0.047498)
			(type default)
		)
		(layer "F.Cu")
	)
	(gr_arc
		(start 22.986492 -243.11991)
		(mid 23.117783 -243.065527)
		(end 23.172166 -242.934236)
		(stroke
			(width 0.047498)
			(type default)
		)
		(layer "F.Cu")
	)
	(gr_line
		(start 23.001478 -449.10375)
		(end 23.07209 -449.07454)
		(stroke
			(width 0.047498)
			(type default)
		)
		(layer "F.Cu")
	)
	(gr_arc
		(start 23.011638 -40.929814)
		(mid 23.073084 -40.91761)
		(end 23.125176 -40.882824)
		(stroke
			(width 0.047498)
			(type default)
		)
		(layer "F.Cu")
	)
	(gr_arc
		(start 23.039578 -349.929958)
		(mid 23.090303 -349.91985)
		(end 23.133304 -349.891096)
		(stroke
			(width 0.047498)
			(type default)
		)
		(layer "F.Cu")
	)
	(gr_arc
		(start 23.049992 -143.929862)
		(mid 23.096732 -143.920547)
		(end 23.136352 -143.894048)
		(stroke
			(width 0.047498)
			(type default)
		)
		(layer "F.Cu")
	)
	(gr_line
		(start 23.052532 -452.930006)
		(end 23.055834 -452.926704)
		(stroke
			(width 0.047498)
			(type default)
		)
		(layer "F.Cu")
	)
	(gr_arc
		(start 23.055072 -37.119814)
		(mid 23.099882 -37.110901)
		(end 23.137876 -37.085524)
		(stroke
			(width 0.047498)
			(type default)
		)
		(layer "F.Cu")
	)
	(gr_arc
		(start 23.055834 -452.926704)
		(mid 23.197165 -452.898591)
		(end 23.316946 -452.8185)
		(stroke
			(width 0.047498)
			(type default)
		)
		(layer "F.Cu")
	)
	(gr_line
		(start 23.0632 -35.849814)
		(end 23.073106 -35.853624)
		(stroke
			(width 0.047498)
			(type default)
		)
		(layer "F.Cu")
	)
	(gr_arc
		(start 23.07209 -449.07454)
		(mid 23.118508 -449.043635)
		(end 23.14956 -448.997324)
		(stroke
			(width 0.047498)
			(type default)
		)
		(layer "F.Cu")
	)
	(gr_arc
		(start 23.086822 -241.895376)
		(mid 23.038172 -241.87375)
		(end 22.987 -241.859054)
		(stroke
			(width 0.047498)
			(type default)
		)
		(layer "F.Cu")
	)
	(gr_line
		(start 23.086822 -241.895376)
		(end 23.09876 -241.901726)
		(stroke
			(width 0.047498)
			(type default)
		)
		(layer "F.Cu")
	)
	(gr_arc
		(start 23.101808 -348.729808)
		(mid 23.024296 -348.678087)
		(end 22.932898 -348.659958)
		(stroke
			(width 0.047498)
			(type default)
		)
		(layer "F.Cu")
	)
	(gr_line
		(start 23.101808 -348.729808)
		(end 23.129748 -348.757494)
		(stroke
			(width 0.047498)
			(type default)
		)
		(layer "F.Cu")
	)
	(gr_arc
		(start 23.10638 -447.90995)
		(mid 23.039945 -447.865602)
		(end 22.9616 -447.850006)
		(stroke
			(width 0.047498)
			(type default)
		)
		(layer "F.Cu")
	)
	(gr_arc
		(start 23.106634 -138.877802)
		(mid 23.074264 -138.857099)
		(end 23.03653 -138.849862)
		(stroke
			(width 0.047498)
			(type default)
		)
		(layer "F.Cu")
	)
	(gr_line
		(start 23.106634 -138.877802)
		(end 23.138638 -138.908028)
		(stroke
			(width 0.047498)
			(type default)
		)
		(layer "F.Cu")
	)
	(gr_arc
		(start 23.11019 -39.72179)
		(mid 23.041549 -39.675932)
		(end 22.960584 -39.659814)
		(stroke
			(width 0.047498)
			(type default)
		)
		(layer "F.Cu")
	)
	(gr_line
		(start 23.11019 -39.72179)
		(end 23.13813 -39.74973)
		(stroke
			(width 0.047498)
			(type default)
		)
		(layer "F.Cu")
	)
	(gr_line
		(start 23.110952 -140.058648)
		(end 23.138892 -140.030708)
		(stroke
			(width 0.047498)
			(type default)
		)
		(layer "F.Cu")
	)
	(gr_arc
		(start 23.118318 -35.88004)
		(mid 23.096871 -35.864849)
		(end 23.073106 -35.853624)
		(stroke
			(width 0.047498)
			(type default)
		)
		(layer "F.Cu")
	)
	(gr_line
		(start 23.118318 -35.88004)
		(end 23.138384 -35.897312)
		(stroke
			(width 0.047498)
			(type default)
		)
		(layer "F.Cu")
	)
	(gr_arc
		(start 23.12162 -346.119958)
		(mid 23.205855 -346.085067)
		(end 23.240746 -346.000832)
		(stroke
			(width 0.047498)
			(type default)
		)
		(layer "F.Cu")
	)
	(gr_arc
		(start 23.124414 -245.704868)
		(mid 23.073459 -245.671503)
		(end 23.01367 -245.65991)
		(stroke
			(width 0.047498)
			(type default)
		)
		(layer "F.Cu")
	)
	(gr_line
		(start 23.124414 -245.704868)
		(end 23.143464 -245.723664)
		(stroke
			(width 0.047498)
			(type default)
		)
		(layer "F.Cu")
	)
	(gr_arc
		(start 23.124414 -142.707614)
		(mid 23.071503 -142.672278)
		(end 23.009098 -142.659862)
		(stroke
			(width 0.047498)
			(type default)
		)
		(layer "F.Cu")
	)
	(gr_arc
		(start 23.125176 -40.882824)
		(mid 23.159929 -40.830718)
		(end 23.172166 -40.769286)
		(stroke
			(width 0.047498)
			(type default)
		)
		(layer "F.Cu")
	)
	(gr_arc
		(start 23.133304 -349.891096)
		(mid 23.162091 -349.848108)
		(end 23.172166 -349.79737)
		(stroke
			(width 0.047498)
			(type default)
		)
		(layer "F.Cu")
	)
	(gr_arc
		(start 23.136352 -143.894048)
		(mid 23.162881 -143.85444)
		(end 23.172166 -143.807688)
		(stroke
			(width 0.047498)
			(type default)
		)
		(layer "F.Cu")
	)
	(gr_arc
		(start 23.137876 -37.085524)
		(mid 23.163261 -37.047533)
		(end 23.172166 -37.00272)
		(stroke
			(width 0.047498)
			(type default)
		)
		(layer "F.Cu")
	)
	(gr_arc
		(start 23.138892 -140.030708)
		(mid 23.163498 -139.993883)
		(end 23.172166 -139.950444)
		(stroke
			(width 0.047498)
			(type default)
		)
		(layer "F.Cu")
	)
	(gr_arc
		(start 23.139654 -447.964306)
		(mid 23.125149 -447.935823)
		(end 23.10638 -447.90995)
		(stroke
			(width 0.047498)
			(type default)
		)
		(layer "F.Cu")
	)
	(gr_line
		(start 23.139654 -447.964306)
		(end 23.156418 -448.004946)
		(stroke
			(width 0.047498)
			(type default)
		)
		(layer "F.Cu")
	)
	(gr_arc
		(start 23.14829 -451.732396)
		(mid 23.068118 -451.678801)
		(end 22.973538 -451.660006)
		(stroke
			(width 0.047498)
			(type default)
		)
		(layer "F.Cu")
	)
	(gr_line
		(start 23.14956 -448.997324)
		(end 23.161244 -448.968876)
		(stroke
			(width 0.047498)
			(type default)
		)
		(layer "F.Cu")
	)
	(gr_arc
		(start 23.161244 -448.968876)
		(mid 23.169413 -448.942111)
		(end 23.172166 -448.914266)
		(stroke
			(width 0.047498)
			(type default)
		)
		(layer "F.Cu")
	)
	(gr_line
		(start 23.172166 -448.748404)
		(end 23.172166 -448.914266)
		(stroke
			(width 0.047498)
			(type default)
		)
		(layer "F.Cu")
	)
	(gr_arc
		(start 23.172166 -448.215004)
		(mid 23.19092 -448.273656)
		(end 23.240238 -448.310508)
		(stroke
			(width 0.047498)
			(type default)
		)
		(layer "F.Cu")
	)
	(gr_arc
		(start 23.172166 -448.083432)
		(mid 23.168187 -448.043407)
		(end 23.156418 -448.004946)
		(stroke
			(width 0.047498)
			(type default)
		)
		(layer "F.Cu")
	)
	(gr_line
		(start 23.172166 -448.083432)
		(end 23.172166 -448.215004)
		(stroke
			(width 0.047498)
			(type default)
		)
		(layer "F.Cu")
	)
	(gr_line
		(start 23.172166 -349.558356)
		(end 23.172166 -349.79737)
		(stroke
			(width 0.047498)
			(type default)
		)
		(layer "F.Cu")
	)
	(gr_arc
		(start 23.172166 -349.024956)
		(mid 23.191769 -349.084948)
		(end 23.243032 -349.12173)
		(stroke
			(width 0.047498)
			(type default)
		)
		(layer "F.Cu")
	)
	(gr_arc
		(start 23.172166 -348.859856)
		(mid 23.161136 -348.804456)
		(end 23.129748 -348.757494)
		(stroke
			(width 0.047498)
			(type default)
		)
		(layer "F.Cu")
	)
	(gr_line
		(start 23.172166 -348.859856)
		(end 23.172166 -349.024956)
		(stroke
			(width 0.047498)
			(type default)
		)
		(layer "F.Cu")
	)
	(gr_line
		(start 23.172166 -246.558308)
		(end 23.172166 -246.744236)
		(stroke
			(width 0.047498)
			(type default)
		)
		(layer "F.Cu")
	)
	(gr_arc
		(start 23.172166 -246.024908)
		(mid 23.194337 -246.088172)
		(end 23.25116 -246.123714)
		(stroke
			(width 0.047498)
			(type default)
		)
		(layer "F.Cu")
	)
	(gr_arc
		(start 23.172166 -245.791736)
		(mid 23.164696 -245.754803)
		(end 23.143464 -245.723664)
		(stroke
			(width 0.047498)
			(type default)
		)
		(layer "F.Cu")
	)
	(gr_line
		(start 23.172166 -245.791736)
		(end 23.172166 -246.024908)
		(stroke
			(width 0.047498)
			(type default)
		)
		(layer "F.Cu")
	)
	(gr_line
		(start 23.172166 -242.748308)
		(end 23.172166 -242.934236)
		(stroke
			(width 0.047498)
			(type default)
		)
		(layer "F.Cu")
	)
	(gr_arc
		(start 23.172166 -242.214908)
		(mid 23.201925 -242.286757)
		(end 23.273766 -242.316508)
		(stroke
			(width 0.047498)
			(type default)
		)
		(layer "F.Cu")
	)
	(gr_arc
		(start 23.172166 -242.023646)
		(mid 23.152396 -241.952494)
		(end 23.09876 -241.901726)
		(stroke
			(width 0.047498)
			(type default)
		)
		(layer "F.Cu")
	)
	(gr_line
		(start 23.172166 -242.023646)
		(end 23.172166 -242.214908)
		(stroke
			(width 0.047498)
			(type default)
		)
		(layer "F.Cu")
	)
	(gr_line
		(start 23.172166 -143.55826)
		(end 23.172166 -143.807688)
		(stroke
			(width 0.047498)
			(type default)
		)
		(layer "F.Cu")
	)
	(gr_arc
		(start 23.172166 -143.02486)
		(mid 23.190922 -143.083596)
		(end 23.240238 -143.120618)
		(stroke
			(width 0.047498)
			(type default)
		)
		(layer "F.Cu")
	)
	(gr_arc
		(start 23.172166 -142.82293)
		(mid 23.159757 -142.760526)
		(end 23.124414 -142.707614)
		(stroke
			(width 0.047498)
			(type default)
		)
		(layer "F.Cu")
	)
	(gr_line
		(start 23.172166 -142.82293)
		(end 23.172166 -143.02486)
		(stroke
			(width 0.047498)
			(type default)
		)
		(layer "F.Cu")
	)
	(gr_line
		(start 23.172166 -139.74826)
		(end 23.172166 -139.950444)
		(stroke
			(width 0.047498)
			(type default)
		)
		(layer "F.Cu")
	)
	(gr_arc
		(start 23.172166 -139.21486)
		(mid 23.190993 -139.273777)
		(end 23.240492 -139.310872)
		(stroke
			(width 0.047498)
			(type default)
		)
		(layer "F.Cu")
	)
	(gr_arc
		(start 23.172166 -138.980672)
		(mid 23.163377 -138.940667)
		(end 23.138638 -138.908028)
		(stroke
			(width 0.047498)
			(type default)
		)
		(layer "F.Cu")
	)
	(gr_line
		(start 23.172166 -138.980672)
		(end 23.172166 -139.21486)
		(stroke
			(width 0.047498)
			(type default)
		)
		(layer "F.Cu")
	)
	(gr_line
		(start 23.172166 -40.558212)
		(end 23.172166 -40.769286)
		(stroke
			(width 0.047498)
			(type default)
		)
		(layer "F.Cu")
	)
	(gr_arc
		(start 23.172166 -40.024812)
		(mid 23.191063 -40.083827)
		(end 23.240746 -40.120824)
		(stroke
			(width 0.047498)
			(type default)
		)
		(layer "F.Cu")
	)
	(gr_arc
		(start 23.172166 -39.832026)
		(mid 23.163306 -39.787505)
		(end 23.13813 -39.74973)
		(stroke
			(width 0.047498)
			(type default)
		)
		(layer "F.Cu")
	)
	(gr_line
		(start 23.172166 -39.832026)
		(end 23.172166 -40.024812)
		(stroke
			(width 0.047498)
			(type default)
		)
		(layer "F.Cu")
	)
	(gr_line
		(start 23.172166 -36.748212)
		(end 23.172166 -37.00272)
		(stroke
			(width 0.047498)
			(type default)
		)
		(layer "F.Cu")
	)
	(gr_arc
		(start 23.172166 -36.214812)
		(mid 23.190993 -36.273729)
		(end 23.240492 -36.310824)
		(stroke
			(width 0.047498)
			(type default)
		)
		(layer "F.Cu")
	)
	(gr_arc
		(start 23.172166 -35.969956)
		(mid 23.16329 -35.929912)
		(end 23.138384 -35.897312)
		(stroke
			(width 0.047498)
			(type default)
		)
		(layer "F.Cu")
	)
	(gr_line
		(start 23.172166 -35.969956)
		(end 23.172166 -36.214812)
		(stroke
			(width 0.047498)
			(type default)
		)
		(layer "F.Cu")
	)
	(gr_arc
		(start 23.200106 -345.148662)
		(mid 23.249207 -345.267201)
		(end 23.367746 -345.316302)
		(stroke
			(width 0.047498)
			(type default)
		)
		(layer "F.Cu")
	)
	(gr_arc
		(start 23.200106 -344.99931)
		(mid 23.156363 -344.893712)
		(end 23.050754 -344.849958)
		(stroke
			(width 0.047498)
			(type default)
		)
		(layer "F.Cu")
	)
	(gr_line
		(start 23.200106 -344.99931)
		(end 23.200106 -345.148662)
		(stroke
			(width 0.047498)
			(type default)
		)
		(layer "F.Cu")
	)
	(gr_arc
		(start 23.240238 -448.652392)
		(mid 23.1909 -448.689544)
		(end 23.172166 -448.748404)
		(stroke
			(width 0.047498)
			(type default)
		)
		(layer "F.Cu")
	)
	(gr_arc
		(start 23.240238 -448.310508)
		(mid 23.241504 -448.311026)
		(end 23.242778 -448.311524)
		(stroke
			(width 0.047498)
			(type default)
		)
		(layer "F.Cu")
	)
	(gr_arc
		(start 23.240238 -143.462248)
		(mid 23.190883 -143.499396)
		(end 23.172166 -143.55826)
		(stroke
			(width 0.047498)
			(type default)
		)
		(layer "F.Cu")
	)
	(gr_arc
		(start 23.240238 -143.120618)
		(mid 23.240619 -143.120746)
		(end 23.241 -143.120872)
		(stroke
			(width 0.047498)
			(type default)
		)
		(layer "F.Cu")
	)
	(gr_arc
		(start 23.240238 -139.652248)
		(mid 23.190883 -139.689396)
		(end 23.172166 -139.74826)
		(stroke
			(width 0.047498)
			(type default)
		)
		(layer "F.Cu")
	)
	(gr_arc
		(start 23.240492 -139.310872)
		(mid 23.256896 -139.315054)
		(end 23.273766 -139.31646)
		(stroke
			(width 0.047498)
			(type default)
		)
		(layer "F.Cu")
	)
	(gr_arc
		(start 23.240492 -36.310824)
		(mid 23.256896 -36.315006)
		(end 23.273766 -36.316412)
		(stroke
			(width 0.047498)
			(type default)
		)
		(layer "F.Cu")
	)
	(gr_arc
		(start 23.240746 -451.920102)
		(mid 23.213269 -451.817014)
		(end 23.14829 -451.732396)
		(stroke
			(width 0.047498)
			(type default)
		)
		(layer "F.Cu")
	)
	(gr_arc
		(start 23.240746 -451.920102)
		(mid 23.317893 -452.106353)
		(end 23.504144 -452.1835)
		(stroke
			(width 0.047498)
			(type default)
		)
		(layer "F.Cu")
	)
	(gr_line
		(start 23.240746 -345.881706)
		(end 23.240746 -346.000832)
		(stroke
			(width 0.047498)
			(type default)
		)
		(layer "F.Cu")
	)
	(gr_arc
		(start 23.240746 -40.120824)
		(mid 23.241887 -40.121212)
		(end 23.243032 -40.121586)
		(stroke
			(width 0.047498)
			(type default)
		)
		(layer "F.Cu")
	)
	(gr_arc
		(start 23.241 -143.120872)
		(mid 23.257152 -143.125021)
		(end 23.273766 -143.12646)
		(stroke
			(width 0.047498)
			(type default)
		)
		(layer "F.Cu")
	)
	(gr_arc
		(start 23.242524 -349.461582)
		(mid 23.191589 -349.498517)
		(end 23.172166 -349.558356)
		(stroke
			(width 0.047498)
			(type default)
		)
		(layer "F.Cu")
	)
	(gr_arc
		(start 23.242524 -242.65128)
		(mid 23.191514 -242.688318)
		(end 23.172166 -242.748308)
		(stroke
			(width 0.047498)
			(type default)
		)
		(layer "F.Cu")
	)
	(gr_line
		(start 23.242524 -242.65128)
		(end 23.242778 -242.65128)
		(stroke
			(width 0.047498)
			(type default)
		)
		(layer "F.Cu")
	)
	(gr_arc
		(start 23.242524 -40.461438)
		(mid 23.191611 -40.498378)
		(end 23.172166 -40.558212)
		(stroke
			(width 0.047498)
			(type default)
		)
		(layer "F.Cu")
	)
	(gr_arc
		(start 23.242778 -448.311524)
		(mid 23.249824 -448.313568)
		(end 23.257002 -448.31508)
		(stroke
			(width 0.047498)
			(type default)
		)
		(layer "F.Cu")
	)
	(gr_arc
		(start 23.242778 -246.46128)
		(mid 23.191683 -246.498312)
		(end 23.172166 -246.558308)
		(stroke
			(width 0.047498)
			(type default)
		)
		(layer "F.Cu")
	)
	(gr_arc
		(start 23.243032 -349.12173)
		(mid 23.258213 -349.125333)
		(end 23.273766 -349.126556)
		(stroke
			(width 0.047498)
			(type default)
		)
		(layer "F.Cu")
	)
	(gr_arc
		(start 23.243032 -40.121586)
		(mid 23.258213 -40.125189)
		(end 23.273766 -40.126412)
		(stroke
			(width 0.047498)
			(type default)
		)
		(layer "F.Cu")
	)
	(gr_arc
		(start 23.24354 -40.46093)
		(mid 23.243031 -40.461183)
		(end 23.242524 -40.461438)
		(stroke
			(width 0.047498)
			(type default)
		)
		(layer "F.Cu")
	)
	(gr_arc
		(start 23.247858 -36.649914)
		(mid 23.193278 -36.686186)
		(end 23.172166 -36.748212)
		(stroke
			(width 0.047498)
			(type default)
		)
		(layer "F.Cu")
	)
	(gr_arc
		(start 23.250144 -246.459248)
		(mid 23.246442 -246.460197)
		(end 23.242778 -246.46128)
		(stroke
			(width 0.047498)
			(type default)
		)
		(layer "F.Cu")
	)
	(gr_arc
		(start 23.25116 -246.123714)
		(mid 23.262385 -246.125744)
		(end 23.273766 -246.126508)
		(stroke
			(width 0.047498)
			(type default)
		)
		(layer "F.Cu")
	)
	(gr_arc
		(start 23.257002 -448.31508)
		(mid 23.25789 -448.315211)
		(end 23.25878 -448.315334)
		(stroke
			(width 0.047498)
			(type default)
		)
		(layer "F.Cu")
	)
	(gr_arc
		(start 23.25878 -448.315334)
		(mid 23.26625 -448.316243)
		(end 23.273766 -448.316604)
		(stroke
			(width 0.047498)
			(type default)
		)
		(layer "F.Cu")
	)
	(gr_arc
		(start 23.259034 -143.457676)
		(mid 23.249527 -143.459515)
		(end 23.240238 -143.462248)
		(stroke
			(width 0.047498)
			(type default)
		)
		(layer "F.Cu")
	)
	(gr_arc
		(start 23.273766 -448.646804)
		(mid 23.256766 -448.648181)
		(end 23.240238 -448.652392)
		(stroke
			(width 0.047498)
			(type default)
		)
		(layer "F.Cu")
	)
	(gr_arc
		(start 23.273766 -349.456756)
		(mid 23.257956 -349.457943)
		(end 23.242524 -349.461582)
		(stroke
			(width 0.047498)
			(type default)
		)
		(layer "F.Cu")
	)
	(gr_arc
		(start 23.273766 -246.456708)
		(mid 23.26188 -246.457281)
		(end 23.250144 -246.459248)
		(stroke
			(width 0.047498)
			(type default)
		)
		(layer "F.Cu")
	)
	(gr_arc
		(start 23.273766 -242.646708)
		(mid 23.258093 -242.647783)
		(end 23.242778 -242.65128)
		(stroke
			(width 0.047498)
			(type default)
		)
		(layer "F.Cu")
	)
	(gr_arc
		(start 23.273766 -143.45666)
		(mid 23.266382 -143.456909)
		(end 23.259034 -143.457676)
		(stroke
			(width 0.047498)
			(type default)
		)
		(layer "F.Cu")
	)
	(gr_arc
		(start 23.273766 -139.64666)
		(mid 23.256766 -139.648037)
		(end 23.240238 -139.652248)
		(stroke
			(width 0.047498)
			(type default)
		)
		(layer "F.Cu")
	)
	(gr_arc
		(start 23.273766 -40.456612)
		(mid 23.258488 -40.457616)
		(end 23.24354 -40.46093)
		(stroke
			(width 0.047498)
			(type default)
		)
		(layer "F.Cu")
	)
	(gr_arc
		(start 23.273766 -36.646612)
		(mid 23.260705 -36.647429)
		(end 23.247858 -36.649914)
		(stroke
			(width 0.047498)
			(type default)
		)
		(layer "F.Cu")
	)
	(gr_line
		(start 23.316946 -452.8185)
		(end 23.577042 -452.558404)
		(stroke
			(width 0.047498)
			(type default)
		)
		(layer "F.Cu")
	)
	(gr_line
		(start 23.324566 -155.64358)
		(end 23.394924 -155.573222)
		(stroke
			(width 0.047498)
			(type default)
		)
		(layer "F.Cu")
	)
	(gr_arc
		(start 23.367746 -345.316302)
		(mid 23.372951 -345.316513)
		(end 23.37816 -345.316556)
		(stroke
			(width 0.047498)
			(type default)
		)
		(layer "F.Cu")
	)
	(gr_arc
		(start 23.375366 -345.6686)
		(mid 23.277126 -345.755619)
		(end 23.240746 -345.881706)
		(stroke
			(width 0.047498)
			(type default)
		)
		(layer "F.Cu")
	)
	(gr_arc
		(start 23.391368 -345.661742)
		(mid 23.383304 -345.665023)
		(end 23.375366 -345.6686)
		(stroke
			(width 0.047498)
			(type default)
		)
		(layer "F.Cu")
	)
	(gr_arc
		(start 23.3934 -345.661234)
		(mid 23.392383 -345.661485)
		(end 23.391368 -345.661742)
		(stroke
			(width 0.047498)
			(type default)
		)
		(layer "F.Cu")
	)
	(gr_arc
		(start 23.40737 -345.656662)
		(mid 23.400348 -345.658834)
		(end 23.3934 -345.661234)
		(stroke
			(width 0.047498)
			(type default)
		)
		(layer "F.Cu")
	)
	(gr_arc
		(start 23.436072 -345.649804)
		(mid 23.421614 -345.652785)
		(end 23.40737 -345.656662)
		(stroke
			(width 0.047498)
			(type default)
		)
		(layer "F.Cu")
	)
	(gr_arc
		(start 23.475188 -345.646502)
		(mid 23.455561 -345.647331)
		(end 23.436072 -345.649804)
		(stroke
			(width 0.047498)
			(type default)
		)
		(layer "F.Cu")
	)
	(gr_arc
		(start 23.475188 -345.646502)
		(mid 23.475442 -345.646629)
		(end 23.475696 -345.646756)
		(stroke
			(width 0.047498)
			(type default)
		)
		(layer "F.Cu")
	)
	(gr_arc
		(start 23.596092 -452.542148)
		(mid 23.586239 -452.549892)
		(end 23.577042 -452.558404)
		(stroke
			(width 0.047498)
			(type default)
		)
		(layer "F.Cu")
	)
	(gr_arc
		(start 23.597616 -452.540878)
		(mid 23.596852 -452.54151)
		(end 23.596092 -452.542148)
		(stroke
			(width 0.047498)
			(type default)
		)
		(layer "F.Cu")
	)
	(gr_arc
		(start 23.684992 -452.5137)
		(mid 23.639226 -452.520609)
		(end 23.597616 -452.540878)
		(stroke
			(width 0.047498)
			(type default)
		)
		(layer "F.Cu")
	)
	(gr_line
		(start 24.05634 -349.126556)
		(end 24.12365 -349.126556)
		(stroke
			(width 0.047498)
			(type default)
		)
		(layer "F.Cu")
	)
	(gr_arc
		(start 24.12365 -349.126556)
		(mid 24.376291 -349.07632)
		(end 24.590502 -348.933262)
		(stroke
			(width 0.047498)
			(type default)
		)
		(layer "F.Cu")
	)
	(gr_line
		(start 24.184356 -452.5137)
		(end 24.19096 -452.5137)
		(stroke
			(width 0.047498)
			(type default)
		)
		(layer "F.Cu")
	)
	(gr_line
		(start 24.257 -130.4036)
		(end 24.441658 -130.588004)
		(stroke
			(width 0.047498)
			(type default)
		)
		(layer "F.Cu")
	)
	(gr_arc
		(start 24.417782 -235.988606)
		(mid 24.600327 -235.952296)
		(end 24.755094 -235.848906)
		(stroke
			(width 0.047498)
			(type default)
		)
		(layer "F.Cu")
	)
	(gr_arc
		(start 24.509984 -349.782638)
		(mid 24.149196 -349.541501)
		(end 23.7236 -349.456756)
		(stroke
			(width 0.047498)
			(type default)
		)
		(layer "F.Cu")
	)
	(gr_line
		(start 24.509984 -349.782638)
		(end 24.638 -349.9104)
		(stroke
			(width 0.047498)
			(type default)
		)
		(layer "F.Cu")
	)
	(gr_line
		(start 24.514556 -452.26859)
		(end 24.514556 -452.268844)
		(stroke
			(width 0.047498)
			(type default)
		)
		(layer "F.Cu")
	)
	(gr_arc
		(start 24.5364 -130.817112)
		(mid 24.511831 -130.693126)
		(end 24.441658 -130.588004)
		(stroke
			(width 0.047498)
			(type default)
		)
		(layer "F.Cu")
	)
	(gr_line
		(start 24.590502 -348.933262)
		(end 24.696166 -348.827598)
		(stroke
			(width 0.047498)
			(type default)
		)
		(layer "F.Cu")
	)
	(gr_arc
		(start 24.6253 -236.458506)
		(mid 24.470535 -236.35512)
		(end 24.287988 -236.318806)
		(stroke
			(width 0.047498)
			(type default)
		)
		(layer "F.Cu")
	)
	(gr_arc
		(start 24.6253 -236.458506)
		(mid 24.78006 -236.561913)
		(end 24.962612 -236.598206)
		(stroke
			(width 0.047498)
			(type default)
		)
		(layer "F.Cu")
	)
	(gr_arc
		(start 24.714708 -36.316412)
		(mid 25.188566 -36.222156)
		(end 25.590246 -35.9537)
		(stroke
			(width 0.047498)
			(type default)
		)
		(layer "F.Cu")
	)
	(gr_arc
		(start 24.745696 -133.1087)
		(mid 25.264072 -133.005589)
		(end 25.70353 -132.711952)
		(stroke
			(width 0.047498)
			(type default)
		)
		(layer "F.Cu")
	)
	(gr_line
		(start 24.8666 -130.817112)
		(end 24.866854 -130.816858)
		(stroke
			(width 0.047498)
			(type default)
		)
		(layer "F.Cu")
	)
	(gr_arc
		(start 24.917146 -339.0265)
		(mid 25.194268 -338.971377)
		(end 25.42921 -338.81441)
		(stroke
			(width 0.047498)
			(type default)
		)
		(layer "F.Cu")
	)
	(gr_line
		(start 24.962612 -236.598206)
		(end 25.34793 -236.598206)
		(stroke
			(width 0.047498)
			(type default)
		)
		(layer "F.Cu")
	)
	(gr_line
		(start 24.979376 -130.544824)
		(end 25.1206 -130.4036)
		(stroke
			(width 0.047498)
			(type default)
		)
		(layer "F.Cu")
	)
	(gr_line
		(start 25.047448 -36.646612)
		(end 25.11679 -36.646612)
		(stroke
			(width 0.047498)
			(type default)
		)
		(layer "F.Cu")
	)
	(gr_line
		(start 25.078436 -133.4389)
		(end 25.31237 -133.4389)
		(stroke
			(width 0.047498)
			(type default)
		)
		(layer "F.Cu")
	)
	(gr_arc
		(start 25.092406 -235.709206)
		(mid 24.909846 -235.745489)
		(end 24.755094 -235.848906)
		(stroke
			(width 0.047498)
			(type default)
		)
		(layer "F.Cu")
	)
	(gr_line
		(start 25.092406 -235.709206)
		(end 25.34793 -235.709206)
		(stroke
			(width 0.047498)
			(type default)
		)
		(layer "F.Cu")
	)
	(gr_arc
		(start 25.23109 -442.0997)
		(mid 25.562936 -442.033692)
		(end 25.844246 -441.8457)
		(stroke
			(width 0.047498)
			(type default)
		)
		(layer "F.Cu")
	)
	(gr_arc
		(start 25.387808 -139.76223)
		(mid 25.237935 -139.666435)
		(end 25.061672 -139.642596)
		(stroke
			(width 0.047498)
			(type default)
		)
		(layer "F.Cu")
	)
	(gr_line
		(start 25.387808 -139.76223)
		(end 25.57653 -139.950952)
		(stroke
			(width 0.047498)
			(type default)
		)
		(layer "F.Cu")
	)
	(gr_line
		(start 25.413716 -362.19511)
		(end 25.41397 -362.194602)
		(stroke
			(width 0.047498)
			(type default)
		)
		(layer "F.Cu")
	)
	(gr_line
		(start 25.42921 -338.81441)
		(end 25.546812 -338.696808)
		(stroke
			(width 0.047498)
			(type default)
		)
		(layer "F.Cu")
	)
	(gr_arc
		(start 25.488646 -242.316508)
		(mid 25.824883 -242.249663)
		(end 26.10993 -242.059206)
		(stroke
			(width 0.047498)
			(type default)
		)
		(layer "F.Cu")
	)
	(gr_arc
		(start 25.546812 -339.585808)
		(mid 25.292986 -339.41624)
		(end 24.9936 -339.3567)
		(stroke
			(width 0.047498)
			(type default)
		)
		(layer "F.Cu")
	)
	(gr_arc
		(start 25.590246 -36.8427)
		(mid 25.373014 -36.69759)
		(end 25.11679 -36.646612)
		(stroke
			(width 0.047498)
			(type default)
		)
		(layer "F.Cu")
	)
	(gr_line
		(start 25.647904 -362.428282)
		(end 25.648158 -362.427774)
		(stroke
			(width 0.047498)
			(type default)
		)
		(layer "F.Cu")
	)
	(gr_arc
		(start 25.70353 -133.600952)
		(mid 25.524074 -133.481002)
		(end 25.31237 -133.4389)
		(stroke
			(width 0.047498)
			(type default)
		)
		(layer "F.Cu")
	)
	(gr_arc
		(start 25.753822 -448.316604)
		(mid 26.077698 -448.252181)
		(end 26.352246 -448.0687)
		(stroke
			(width 0.047498)
			(type default)
		)
		(layer "F.Cu")
	)
	(gr_arc
		(start 25.781762 -442.67247)
		(mid 25.513271 -442.493008)
		(end 25.196546 -442.4299)
		(stroke
			(width 0.047498)
			(type default)
		)
		(layer "F.Cu")
	)
	(gr_line
		(start 25.781762 -442.67247)
		(end 25.844246 -442.7347)
		(stroke
			(width 0.047498)
			(type default)
		)
		(layer "F.Cu")
	)
	(gr_arc
		(start 25.97531 -345.316556)
		(mid 26.151536 -345.281502)
		(end 26.300938 -345.181682)
		(stroke
			(width 0.047498)
			(type default)
		)
		(layer "F.Cu")
	)
	(gr_line
		(start 25.9969 -342.4301)
		(end 25.9969 -342.431116)
		(stroke
			(width 0.047498)
			(type default)
		)
		(layer "F.Cu")
	)
	(gr_line
		(start 25.9969 -341.503)
		(end 26.134314 -341.64016)
		(stroke
			(width 0.047498)
			(type default)
		)
		(layer "F.Cu")
	)
	(gr_arc
		(start 26.10993 -242.948206)
		(mid 25.775928 -242.725066)
		(end 25.381966 -242.646708)
		(stroke
			(width 0.047498)
			(type default)
		)
		(layer "F.Cu")
	)
	(gr_arc
		(start 26.134314 -341.64016)
		(mid 26.263539 -341.726597)
		(end 26.416 -341.757)
		(stroke
			(width 0.047498)
			(type default)
		)
		(layer "F.Cu")
	)
	(gr_line
		(start 26.23693 -236.598206)
		(end 26.33599 -236.499146)
		(stroke
			(width 0.047498)
			(type default)
		)
		(layer "F.Cu")
	)
	(gr_line
		(start 26.23693 -235.709206)
		(end 26.246074 -235.718604)
		(stroke
			(width 0.047498)
			(type default)
		)
		(layer "F.Cu")
	)
	(gr_arc
		(start 26.246074 -235.718604)
		(mid 26.502696 -235.899492)
		(end 26.805128 -235.98378)
		(stroke
			(width 0.047498)
			(type default)
		)
		(layer "F.Cu")
	)
	(gr_arc
		(start 26.289 -342.138)
		(mid 26.082454 -342.223554)
		(end 25.9969 -342.4301)
		(stroke
			(width 0.047498)
			(type default)
		)
		(layer "F.Cu")
	)
	(gr_arc
		(start 26.291286 -345.791282)
		(mid 26.131158 -345.68431)
		(end 25.94229 -345.646756)
		(stroke
			(width 0.047498)
			(type default)
		)
		(layer "F.Cu")
	)
	(gr_line
		(start 26.291286 -345.791282)
		(end 26.435812 -345.935808)
		(stroke
			(width 0.047498)
			(type default)
		)
		(layer "F.Cu")
	)
	(gr_line
		(start 26.300938 -345.181682)
		(end 26.435812 -345.046808)
		(stroke
			(width 0.047498)
			(type default)
		)
		(layer "F.Cu")
	)
	(gr_arc
		(start 26.352246 -448.9577)
		(mid 26.007878 -448.727617)
		(end 25.601676 -448.646804)
		(stroke
			(width 0.047498)
			(type default)
		)
		(layer "F.Cu")
	)
	(gr_arc
		(start 26.358596 -32.3215)
		(mid 26.423055 -32.308696)
		(end 26.477722 -32.272224)
		(stroke
			(width 0.047498)
			(type default)
		)
		(layer "F.Cu")
	)
	(gr_arc
		(start 26.36139 -85.678518)
		(mid 26.391187 -85.808836)
		(end 26.477468 -85.910928)
		(stroke
			(width 0.047498)
			(type default)
		)
		(layer "F.Cu")
	)
	(gr_line
		(start 26.36139 -85.392768)
		(end 26.36139 -85.678518)
		(stroke
			(width 0.047498)
			(type default)
		)
		(layer "F.Cu")
	)
	(gr_arc
		(start 26.36139 -84.177378)
		(mid 26.391187 -84.307696)
		(end 26.477468 -84.409788)
		(stroke
			(width 0.047498)
			(type default)
		)
		(layer "F.Cu")
	)
	(gr_line
		(start 26.36139 -83.891628)
		(end 26.36139 -84.177378)
		(stroke
			(width 0.047498)
			(type default)
		)
		(layer "F.Cu")
	)
	(gr_arc
		(start 26.36139 -82.676238)
		(mid 26.391187 -82.806556)
		(end 26.477468 -82.908648)
		(stroke
			(width 0.047498)
			(type default)
		)
		(layer "F.Cu")
	)
	(gr_line
		(start 26.36139 -82.390488)
		(end 26.36139 -82.676238)
		(stroke
			(width 0.047498)
			(type default)
		)
		(layer "F.Cu")
	)
	(gr_arc
		(start 26.36139 -59.771026)
		(mid 26.391187 -59.901344)
		(end 26.477468 -60.003436)
		(stroke
			(width 0.047498)
			(type default)
		)
		(layer "F.Cu")
	)
	(gr_line
		(start 26.36139 -59.485276)
		(end 26.36139 -59.771026)
		(stroke
			(width 0.047498)
			(type default)
		)
		(layer "F.Cu")
	)
	(gr_arc
		(start 26.36139 -58.269886)
		(mid 26.391187 -58.400204)
		(end 26.477468 -58.502296)
		(stroke
			(width 0.047498)
			(type default)
		)
		(layer "F.Cu")
	)
	(gr_line
		(start 26.36139 -57.984136)
		(end 26.36139 -58.269886)
		(stroke
			(width 0.047498)
			(type default)
		)
		(layer "F.Cu")
	)
	(gr_arc
		(start 26.36139 -56.768746)
		(mid 26.391187 -56.899064)
		(end 26.477468 -57.001156)
		(stroke
			(width 0.047498)
			(type default)
		)
		(layer "F.Cu")
	)
	(gr_line
		(start 26.36139 -56.482996)
		(end 26.36139 -56.768746)
		(stroke
			(width 0.047498)
			(type default)
		)
		(layer "F.Cu")
	)
	(gr_arc
		(start 26.36139 -49.955196)
		(mid 26.391187 -50.085514)
		(end 26.477468 -50.187606)
		(stroke
			(width 0.047498)
			(type default)
		)
		(layer "F.Cu")
	)
	(gr_line
		(start 26.36139 -49.669446)
		(end 26.36139 -49.955196)
		(stroke
			(width 0.047498)
			(type default)
		)
		(layer "F.Cu")
	)
	(gr_arc
		(start 26.416 -341.757)
		(mid 26.603644 -341.719589)
		(end 26.76271 -341.613236)
		(stroke
			(width 0.047498)
			(type default)
		)
		(layer "F.Cu")
	)
	(gr_line
		(start 26.435812 -339.585808)
		(end 26.567892 -339.453982)
		(stroke
			(width 0.047498)
			(type default)
		)
		(layer "F.Cu")
	)
	(gr_line
		(start 26.435812 -338.696808)
		(end 26.567892 -338.828634)
		(stroke
			(width 0.047498)
			(type default)
		)
		(layer "F.Cu")
	)
	(gr_line
		(start 26.46553 -139.950952)
		(end 26.620724 -139.795758)
		(stroke
			(width 0.047498)
			(type default)
		)
		(layer "F.Cu")
	)
	(gr_arc
		(start 26.46553 -139.061952)
		(mid 26.80466 -139.288904)
		(end 27.20467 -139.369546)
		(stroke
			(width 0.047498)
			(type default)
		)
		(layer "F.Cu")
	)
	(gr_arc
		(start 26.477468 -85.160358)
		(mid 26.391237 -85.262475)
		(end 26.36139 -85.392768)
		(stroke
			(width 0.047498)
			(type default)
		)
		(layer "F.Cu")
	)
	(gr_arc
		(start 26.477468 -85.160358)
		(mid 26.563871 -85.058286)
		(end 26.5938 -84.927948)
		(stroke
			(width 0.047498)
			(type default)
		)
		(layer "F.Cu")
	)
	(gr_arc
		(start 26.477468 -83.659218)
		(mid 26.391237 -83.761335)
		(end 26.36139 -83.891628)
		(stroke
			(width 0.047498)
			(type default)
		)
		(layer "F.Cu")
	)
	(gr_arc
		(start 26.477468 -83.659218)
		(mid 26.563857 -83.557143)
		(end 26.5938 -83.426808)
		(stroke
			(width 0.047498)
			(type default)
		)
		(layer "F.Cu")
	)
	(gr_arc
		(start 26.477468 -82.158078)
		(mid 26.391237 -82.260195)
		(end 26.36139 -82.390488)
		(stroke
			(width 0.047498)
			(type default)
		)
		(layer "F.Cu")
	)
	(gr_arc
		(start 26.477468 -82.158078)
		(mid 26.563879 -82.056007)
		(end 26.5938 -81.925668)
		(stroke
			(width 0.047498)
			(type default)
		)
		(layer "F.Cu")
	)
	(gr_arc
		(start 26.477468 -59.252866)
		(mid 26.391237 -59.354983)
		(end 26.36139 -59.485276)
		(stroke
			(width 0.047498)
			(type default)
		)
		(layer "F.Cu")
	)
	(gr_arc
		(start 26.477468 -59.252866)
		(mid 26.563874 -59.150794)
		(end 26.5938 -59.020456)
		(stroke
			(width 0.047498)
			(type default)
		)
		(layer "F.Cu")
	)
	(gr_arc
		(start 26.477468 -57.751726)
		(mid 26.391237 -57.853843)
		(end 26.36139 -57.984136)
		(stroke
			(width 0.047498)
			(type default)
		)
		(layer "F.Cu")
	)
	(gr_arc
		(start 26.477468 -57.751726)
		(mid 26.56386 -57.649651)
		(end 26.5938 -57.519316)
		(stroke
			(width 0.047498)
			(type default)
		)
		(layer "F.Cu")
	)
	(gr_arc
		(start 26.477468 -56.250586)
		(mid 26.391237 -56.352703)
		(end 26.36139 -56.482996)
		(stroke
			(width 0.047498)
			(type default)
		)
		(layer "F.Cu")
	)
	(gr_arc
		(start 26.477468 -56.250586)
		(mid 26.563882 -56.148516)
		(end 26.5938 -56.018176)
		(stroke
			(width 0.047498)
			(type default)
		)
		(layer "F.Cu")
	)
	(gr_arc
		(start 26.477468 -49.437036)
		(mid 26.391237 -49.539153)
		(end 26.36139 -49.669446)
		(stroke
			(width 0.047498)
			(type default)
		)
		(layer "F.Cu")
	)
	(gr_arc
		(start 26.477468 -49.437036)
		(mid 26.563863 -49.334962)
		(end 26.5938 -49.204626)
		(stroke
			(width 0.047498)
			(type default)
		)
		(layer "F.Cu")
	)
	(gr_line
		(start 26.477722 -32.272224)
		(end 26.733246 -32.0167)
		(stroke
			(width 0.047498)
			(type default)
		)
		(layer "F.Cu")
	)
	(gr_arc
		(start 26.479246 -35.9537)
		(mid 26.78878 -36.160466)
		(end 27.15387 -36.2331)
		(stroke
			(width 0.047498)
			(type default)
		)
		(layer "F.Cu")
	)
	(gr_arc
		(start 26.567892 -338.828634)
		(mid 26.731144 -338.937809)
		(end 26.923746 -338.976208)
		(stroke
			(width 0.047498)
			(type default)
		)
		(layer "F.Cu")
	)
	(gr_arc
		(start 26.59253 -132.711952)
		(mid 26.90205 -132.918767)
		(end 27.267154 -132.991352)
		(stroke
			(width 0.047498)
			(type default)
		)
		(layer "F.Cu")
	)
	(gr_arc
		(start 26.5938 -86.143338)
		(mid 26.563857 -86.013009)
		(end 26.477468 -85.910928)
		(stroke
			(width 0.047498)
			(type default)
		)
		(layer "F.Cu")
	)
	(gr_arc
		(start 26.5938 -84.642198)
		(mid 26.563879 -84.511852)
		(end 26.477468 -84.409788)
		(stroke
			(width 0.047498)
			(type default)
		)
		(layer "F.Cu")
	)
	(gr_arc
		(start 26.5938 -83.141058)
		(mid 26.563864 -83.010723)
		(end 26.477468 -82.908648)
		(stroke
			(width 0.047498)
			(type default)
		)
		(layer "F.Cu")
	)
	(gr_arc
		(start 26.5938 -60.235846)
		(mid 26.563859 -60.105515)
		(end 26.477468 -60.003436)
		(stroke
			(width 0.047498)
			(type default)
		)
		(layer "F.Cu")
	)
	(gr_arc
		(start 26.5938 -58.734706)
		(mid 26.563882 -58.604357)
		(end 26.477468 -58.502296)
		(stroke
			(width 0.047498)
			(type default)
		)
		(layer "F.Cu")
	)
	(gr_arc
		(start 26.5938 -57.233566)
		(mid 26.563867 -57.103229)
		(end 26.477468 -57.001156)
		(stroke
			(width 0.047498)
			(type default)
		)
		(layer "F.Cu")
	)
	(gr_arc
		(start 26.5938 -50.420016)
		(mid 26.563848 -50.289694)
		(end 26.477468 -50.187606)
		(stroke
			(width 0.047498)
			(type default)
		)
		(layer "F.Cu")
	)
	(gr_arc
		(start 26.61412 -32.78632)
		(mid 26.464833 -32.686614)
		(end 26.288746 -32.6517)
		(stroke
			(width 0.047498)
			(type default)
		)
		(layer "F.Cu")
	)
	(gr_line
		(start 26.61412 -32.78632)
		(end 26.733246 -32.9057)
		(stroke
			(width 0.047498)
			(type default)
		)
		(layer "F.Cu")
	)
	(gr_arc
		(start 26.65349 -366.09274)
		(mid 26.685058 -366.251364)
		(end 26.774902 -366.385856)
		(stroke
			(width 0.047498)
			(type default)
		)
		(layer "F.Cu")
	)
	(gr_line
		(start 26.65349 -365.921036)
		(end 26.65349 -366.09274)
		(stroke
			(width 0.047498)
			(type default)
		)
		(layer "F.Cu")
	)
	(gr_line
		(start 26.669746 -367.015014)
		(end 26.737056 -366.947704)
		(stroke
			(width 0.047498)
			(type default)
		)
		(layer "F.Cu")
	)
	(gr_line
		(start 26.733246 -442.7347)
		(end 26.77033 -442.69787)
		(stroke
			(width 0.047498)
			(type default)
		)
		(layer "F.Cu")
	)
	(gr_line
		(start 26.733246 -441.8457)
		(end 26.77033 -441.88253)
		(stroke
			(width 0.047498)
			(type default)
		)
		(layer "F.Cu")
	)
	(gr_line
		(start 26.76271 -341.613236)
		(end 26.8478 -341.5284)
		(stroke
			(width 0.047498)
			(type default)
		)
		(layer "F.Cu")
	)
	(gr_arc
		(start 26.766012 -342.335612)
		(mid 26.547157 -342.189378)
		(end 26.289 -342.138)
		(stroke
			(width 0.047498)
			(type default)
		)
		(layer "F.Cu")
	)
	(gr_line
		(start 26.766012 -342.335612)
		(end 26.8478 -342.4174)
		(stroke
			(width 0.047498)
			(type default)
		)
		(layer "F.Cu")
	)
	(gr_arc
		(start 26.77033 -441.88253)
		(mid 27.038814 -442.062019)
		(end 27.355546 -442.1251)
		(stroke
			(width 0.047498)
			(type default)
		)
		(layer "F.Cu")
	)
	(gr_arc
		(start 26.771346 -236.318806)
		(mid 26.535735 -236.365685)
		(end 26.33599 -236.499146)
		(stroke
			(width 0.047498)
			(type default)
		)
		(layer "F.Cu")
	)
	(gr_line
		(start 26.774902 -366.385856)
		(end 26.796492 -366.407446)
		(stroke
			(width 0.047498)
			(type default)
		)
		(layer "F.Cu")
	)
	(gr_arc
		(start 26.796492 -366.407446)
		(mid 26.954856 -366.513304)
		(end 27.141678 -366.550448)
		(stroke
			(width 0.047498)
			(type default)
		)
		(layer "F.Cu")
	)
	(gr_arc
		(start 26.805128 -235.98378)
		(mid 26.851676 -235.987373)
		(end 26.898346 -235.988606)
		(stroke
			(width 0.047498)
			(type default)
		)
		(layer "F.Cu")
	)
	(gr_arc
		(start 26.851864 -139.7)
		(mid 26.726767 -139.724889)
		(end 26.620724 -139.795758)
		(stroke
			(width 0.047498)
			(type default)
		)
		(layer "F.Cu")
	)
	(gr_line
		(start 26.851864 -139.7)
		(end 26.875994 -139.7)
		(stroke
			(width 0.047498)
			(type default)
		)
		(layer "F.Cu")
	)
	(gr_arc
		(start 26.899108 -366.880648)
		(mid 26.811418 -366.898073)
		(end 26.737056 -366.947704)
		(stroke
			(width 0.047498)
			(type default)
		)
		(layer "F.Cu")
	)
	(gr_arc
		(start 26.923746 -339.306408)
		(mid 26.731148 -339.344814)
		(end 26.567892 -339.453982)
		(stroke
			(width 0.047498)
			(type default)
		)
		(layer "F.Cu")
	)
	(gr_line
		(start 26.924 -85.260688)
		(end 26.924 -85.810598)
		(stroke
			(width 0.047498)
			(type default)
		)
		(layer "F.Cu")
	)
	(gr_line
		(start 26.924 -83.759548)
		(end 26.924 -84.309458)
		(stroke
			(width 0.047498)
			(type default)
		)
		(layer "F.Cu")
	)
	(gr_line
		(start 26.924 -82.258408)
		(end 26.924 -82.808318)
		(stroke
			(width 0.047498)
			(type default)
		)
		(layer "F.Cu")
	)
	(gr_line
		(start 26.924 -59.353196)
		(end 26.924 -59.903106)
		(stroke
			(width 0.047498)
			(type default)
		)
		(layer "F.Cu")
	)
	(gr_line
		(start 26.924 -57.852056)
		(end 26.924 -58.401966)
		(stroke
			(width 0.047498)
			(type default)
		)
		(layer "F.Cu")
	)
	(gr_line
		(start 26.924 -56.350916)
		(end 26.924 -56.900826)
		(stroke
			(width 0.047498)
			(type default)
		)
		(layer "F.Cu")
	)
	(gr_line
		(start 26.924 -49.537366)
		(end 26.924 -50.087276)
		(stroke
			(width 0.047498)
			(type default)
		)
		(layer "F.Cu")
	)
	(gr_arc
		(start 26.99893 -242.059206)
		(mid 27.300735 -242.262698)
		(end 27.65679 -242.338352)
		(stroke
			(width 0.047498)
			(type default)
		)
		(layer "F.Cu")
	)
	(gr_arc
		(start 27.15387 -36.5633)
		(mid 26.788757 -36.635878)
		(end 26.479246 -36.8427)
		(stroke
			(width 0.047498)
			(type default)
		)
		(layer "F.Cu")
	)
	(gr_arc
		(start 27.177746 -338.976208)
		(mid 27.410598 -338.929985)
		(end 27.608022 -338.798154)
		(stroke
			(width 0.047498)
			(type default)
		)
		(layer "F.Cu")
	)
	(gr_arc
		(start 27.20467 -139.369546)
		(mid 27.206702 -139.369675)
		(end 27.208734 -139.3698)
		(stroke
			(width 0.047498)
			(type default)
		)
		(layer "F.Cu")
	)
	(gr_arc
		(start 27.241246 -448.0687)
		(mid 27.478653 -448.274169)
		(end 27.78379 -448.3481)
		(stroke
			(width 0.047498)
			(type default)
		)
		(layer "F.Cu")
	)
	(gr_arc
		(start 27.267154 -133.321552)
		(mid 26.902042 -133.394133)
		(end 26.59253 -133.600952)
		(stroke
			(width 0.047498)
			(type default)
		)
		(layer "F.Cu")
	)
	(gr_arc
		(start 27.314652 -235.988606)
		(mid 27.484021 -235.954823)
		(end 27.62758 -235.858812)
		(stroke
			(width 0.047498)
			(type default)
		)
		(layer "F.Cu")
	)
	(gr_line
		(start 27.324812 -345.935808)
		(end 27.390598 -345.935808)
		(stroke
			(width 0.047498)
			(type default)
		)
		(layer "F.Cu")
	)
	(gr_arc
		(start 27.324812 -345.06916)
		(mid 27.328984 -345.090044)
		(end 27.340814 -345.107768)
		(stroke
			(width 0.047498)
			(type default)
		)
		(layer "F.Cu")
	)
	(gr_line
		(start 27.324812 -345.046808)
		(end 27.324812 -345.06916)
		(stroke
			(width 0.047498)
			(type default)
		)
		(layer "F.Cu")
	)
	(gr_line
		(start 27.340814 -345.107768)
		(end 27.441906 -345.20886)
		(stroke
			(width 0.047498)
			(type default)
		)
		(layer "F.Cu")
	)
	(gr_arc
		(start 27.355546 -442.4553)
		(mid 27.038803 -442.518367)
		(end 26.77033 -442.69787)
		(stroke
			(width 0.047498)
			(type default)
		)
		(layer "F.Cu")
	)
	(gr_arc
		(start 27.355546 -442.1251)
		(mid 27.54524 -442.087461)
		(end 27.706066 -441.980066)
		(stroke
			(width 0.047498)
			(type default)
		)
		(layer "F.Cu")
	)
	(gr_arc
		(start 27.390598 -345.935808)
		(mid 27.4515 -345.923788)
		(end 27.50312 -345.889326)
		(stroke
			(width 0.047498)
			(type default)
		)
		(layer "F.Cu")
	)
	(gr_arc
		(start 27.441906 -345.20886)
		(mid 27.57183 -345.295735)
		(end 27.725116 -345.326208)
		(stroke
			(width 0.047498)
			(type default)
		)
		(layer "F.Cu")
	)
	(gr_arc
		(start 27.442414 -442.491114)
		(mid 27.402548 -442.464549)
		(end 27.355546 -442.4553)
		(stroke
			(width 0.047498)
			(type default)
		)
		(layer "F.Cu")
	)
	(gr_line
		(start 27.442414 -442.491114)
		(end 27.812746 -442.8617)
		(stroke
			(width 0.047498)
			(type default)
		)
		(layer "F.Cu")
	)
	(gr_line
		(start 27.44978 -470.270586)
		(end 27.683206 -470.03716)
		(stroke
			(width 0.047498)
			(type default)
		)
		(layer "F.Cu")
	)
	(gr_line
		(start 27.50312 -345.889326)
		(end 27.596338 -345.796108)
		(stroke
			(width 0.047498)
			(type default)
		)
		(layer "F.Cu")
	)
	(gr_arc
		(start 27.558746 -236.3597)
		(mid 27.513405 -236.329438)
		(end 27.45994 -236.318806)
		(stroke
			(width 0.047498)
			(type default)
		)
		(layer "F.Cu")
	)
	(gr_arc
		(start 27.60726 -339.484462)
		(mid 27.410205 -339.352723)
		(end 27.177746 -339.306408)
		(stroke
			(width 0.047498)
			(type default)
		)
		(layer "F.Cu")
	)
	(gr_line
		(start 27.60726 -339.484462)
		(end 27.743912 -339.62086)
		(stroke
			(width 0.047498)
			(type default)
		)
		(layer "F.Cu")
	)
	(gr_line
		(start 27.608022 -338.798154)
		(end 27.743912 -338.66201)
		(stroke
			(width 0.047498)
			(type default)
		)
		(layer "F.Cu")
	)
	(gr_line
		(start 27.622246 -32.9057)
		(end 27.939746 -32.9057)
		(stroke
			(width 0.047498)
			(type default)
		)
		(layer "F.Cu")
	)
	(gr_line
		(start 27.622246 -32.0167)
		(end 27.939746 -32.0167)
		(stroke
			(width 0.047498)
			(type default)
		)
		(layer "F.Cu")
	)
	(gr_line
		(start 27.62758 -235.858812)
		(end 27.711146 -235.7755)
		(stroke
			(width 0.047498)
			(type default)
		)
		(layer "F.Cu")
	)
	(gr_arc
		(start 27.64663 -236.57179)
		(mid 27.623769 -236.457009)
		(end 27.558746 -236.3597)
		(stroke
			(width 0.047498)
			(type default)
		)
		(layer "F.Cu")
	)
	(gr_line
		(start 27.64663 -236.57179)
		(end 27.64663 -236.640878)
		(stroke
			(width 0.047498)
			(type default)
		)
		(layer "F.Cu")
	)
	(gr_arc
		(start 27.689048 -448.703954)
		(mid 27.447276 -448.79929)
		(end 27.241246 -448.9577)
		(stroke
			(width 0.047498)
			(type default)
		)
		(layer "F.Cu")
	)
	(gr_line
		(start 27.706066 -441.980066)
		(end 27.787346 -441.898532)
		(stroke
			(width 0.047498)
			(type default)
		)
		(layer "F.Cu")
	)
	(gr_line
		(start 27.7368 -342.4174)
		(end 27.800808 -342.353646)
		(stroke
			(width 0.047498)
			(type default)
		)
		(layer "F.Cu")
	)
	(gr_arc
		(start 27.7368 -341.5284)
		(mid 27.990033 -341.697605)
		(end 28.288742 -341.757)
		(stroke
			(width 0.047498)
			(type default)
		)
		(layer "F.Cu")
	)
	(gr_line
		(start 27.78379 -448.3481)
		(end 27.905202 -448.3481)
		(stroke
			(width 0.047498)
			(type default)
		)
		(layer "F.Cu")
	)
	(gr_line
		(start 27.787346 -441.8457)
		(end 27.787346 -441.898532)
		(stroke
			(width 0.047498)
			(type default)
		)
		(layer "F.Cu")
	)
	(gr_line
		(start 27.812492 -131.863846)
		(end 27.812746 -131.863846)
		(stroke
			(width 0.047498)
			(type default)
		)
		(layer "F.Cu")
	)
	(gr_line
		(start 27.83713 -132.804662)
		(end 27.871674 -132.770372)
		(stroke
			(width 0.047498)
			(type default)
		)
		(layer "F.Cu")
	)
	(gr_line
		(start 27.883612 -131.934966)
		(end 27.888946 -131.9403)
		(stroke
			(width 0.047498)
			(type default)
		)
		(layer "F.Cu")
	)
	(gr_arc
		(start 27.93365 -345.656408)
		(mid 27.751102 -345.692709)
		(end 27.596338 -345.796108)
		(stroke
			(width 0.047498)
			(type default)
		)
		(layer "F.Cu")
	)
	(gr_arc
		(start 27.939746 -32.9057)
		(mid 28.076509 -32.878496)
		(end 28.192476 -32.801052)
		(stroke
			(width 0.047498)
			(type default)
		)
		(layer "F.Cu")
	)
	(gr_line
		(start 27.967432 -133.14172)
		(end 27.973274 -133.135878)
		(stroke
			(width 0.047498)
			(type default)
		)
		(layer "F.Cu")
	)
	(gr_line
		(start 28.033472 -133.075426)
		(end 28.104846 -133.003798)
		(stroke
			(width 0.047498)
			(type default)
		)
		(layer "F.Cu")
	)
	(gr_line
		(start 28.046172 -131.63042)
		(end 28.051506 -131.635754)
		(stroke
			(width 0.047498)
			(type default)
		)
		(layer "F.Cu")
	)
	(gr_arc
		(start 28.093162 -345.326208)
		(mid 28.326446 -345.279805)
		(end 28.5242 -345.147646)
		(stroke
			(width 0.047498)
			(type default)
		)
		(layer "F.Cu")
	)
	(gr_line
		(start 28.104846 -133.003798)
		(end 28.1051 -133.003798)
		(stroke
			(width 0.047498)
			(type default)
		)
		(layer "F.Cu")
	)
	(gr_line
		(start 28.122372 -131.70662)
		(end 28.122372 -131.706874)
		(stroke
			(width 0.047498)
			(type default)
		)
		(layer "F.Cu")
	)
	(gr_line
		(start 28.192476 -32.801052)
		(end 28.29179 -32.701738)
		(stroke
			(width 0.047498)
			(type default)
		)
		(layer "F.Cu")
	)
	(gr_arc
		(start 28.192476 -32.121348)
		(mid 28.076513 -32.043902)
		(end 27.939746 -32.0167)
		(stroke
			(width 0.047498)
			(type default)
		)
		(layer "F.Cu")
	)
	(gr_line
		(start 28.192476 -32.121348)
		(end 28.310332 -32.239204)
		(stroke
			(width 0.047498)
			(type default)
		)
		(layer "F.Cu")
	)
	(gr_line
		(start 28.288742 -341.757)
		(end 28.321 -341.757)
		(stroke
			(width 0.047498)
			(type default)
		)
		(layer "F.Cu")
	)
	(gr_arc
		(start 28.29179 -249.576844)
		(mid 28.321587 -249.707162)
		(end 28.407868 -249.809254)
		(stroke
			(width 0.047498)
			(type default)
		)
		(layer "F.Cu")
	)
	(gr_line
		(start 28.29179 -249.291094)
		(end 28.29179 -249.576844)
		(stroke
			(width 0.047498)
			(type default)
		)
		(layer "F.Cu")
	)
	(gr_arc
		(start 28.29179 -248.075704)
		(mid 28.321587 -248.206022)
		(end 28.407868 -248.308114)
		(stroke
			(width 0.047498)
			(type default)
		)
		(layer "F.Cu")
	)
	(gr_line
		(start 28.29179 -247.789954)
		(end 28.29179 -248.075704)
		(stroke
			(width 0.047498)
			(type default)
		)
		(layer "F.Cu")
	)
	(gr_arc
		(start 28.310332 -32.239204)
		(mid 28.373378 -32.28133)
		(end 28.447746 -32.2961)
		(stroke
			(width 0.047498)
			(type default)
		)
		(layer "F.Cu")
	)
	(gr_arc
		(start 28.321 -342.138)
		(mid 28.039451 -342.19408)
		(end 27.800808 -342.353646)
		(stroke
			(width 0.047498)
			(type default)
		)
		(layer "F.Cu")
	)
	(gr_arc
		(start 28.321 -341.757)
		(mid 28.555645 -341.710326)
		(end 28.754578 -341.577422)
		(stroke
			(width 0.047498)
			(type default)
		)
		(layer "F.Cu")
	)
	(gr_arc
		(start 28.332176 -32.668972)
		(mid 28.311157 -32.684337)
		(end 28.29179 -32.701738)
		(stroke
			(width 0.047498)
			(type default)
		)
		(layer "F.Cu")
	)
	(gr_arc
		(start 28.34259 -151.524716)
		(mid 28.372387 -151.655034)
		(end 28.458668 -151.757126)
		(stroke
			(width 0.047498)
			(type default)
		)
		(layer "F.Cu")
	)
	(gr_line
		(start 28.34259 -151.238966)
		(end 28.34259 -151.524716)
		(stroke
			(width 0.047498)
			(type default)
		)
		(layer "F.Cu")
	)
	(gr_arc
		(start 28.34259 -150.023576)
		(mid 28.372387 -150.153894)
		(end 28.458668 -150.255986)
		(stroke
			(width 0.047498)
			(type default)
		)
		(layer "F.Cu")
	)
	(gr_line
		(start 28.34259 -149.737826)
		(end 28.34259 -150.023576)
		(stroke
			(width 0.047498)
			(type default)
		)
		(layer "F.Cu")
	)
	(gr_arc
		(start 28.34259 -147.073112)
		(mid 28.372387 -147.20343)
		(end 28.458668 -147.305522)
		(stroke
			(width 0.047498)
			(type default)
		)
		(layer "F.Cu")
	)
	(gr_line
		(start 28.34259 -146.787362)
		(end 28.34259 -147.073112)
		(stroke
			(width 0.047498)
			(type default)
		)
		(layer "F.Cu")
	)
	(gr_arc
		(start 28.34259 -145.571972)
		(mid 28.372387 -145.70229)
		(end 28.458668 -145.804382)
		(stroke
			(width 0.047498)
			(type default)
		)
		(layer "F.Cu")
	)
	(gr_line
		(start 28.34259 -145.286222)
		(end 28.34259 -145.571972)
		(stroke
			(width 0.047498)
			(type default)
		)
		(layer "F.Cu")
	)
	(gr_arc
		(start 28.34259 -144.070832)
		(mid 28.372387 -144.20115)
		(end 28.458668 -144.303242)
		(stroke
			(width 0.047498)
			(type default)
		)
		(layer "F.Cu")
	)
	(gr_line
		(start 28.34259 -143.785082)
		(end 28.34259 -144.070832)
		(stroke
			(width 0.047498)
			(type default)
		)
		(layer "F.Cu")
	)
	(gr_arc
		(start 28.34259 -142.569692)
		(mid 28.372387 -142.70001)
		(end 28.458668 -142.802102)
		(stroke
			(width 0.047498)
			(type default)
		)
		(layer "F.Cu")
	)
	(gr_line
		(start 28.34259 -142.283942)
		(end 28.34259 -142.569692)
		(stroke
			(width 0.047498)
			(type default)
		)
		(layer "F.Cu")
	)
	(gr_line
		(start 28.350464 -466.72627)
		(end 28.58389 -466.492844)
		(stroke
			(width 0.047498)
			(type default)
		)
		(layer "F.Cu")
	)
	(gr_arc
		(start 28.407868 -249.058684)
		(mid 28.321637 -249.160801)
		(end 28.29179 -249.291094)
		(stroke
			(width 0.047498)
			(type default)
		)
		(layer "F.Cu")
	)
	(gr_arc
		(start 28.407868 -249.058684)
		(mid 28.494281 -248.956613)
		(end 28.5242 -248.826274)
		(stroke
			(width 0.047498)
			(type default)
		)
		(layer "F.Cu")
	)
	(gr_arc
		(start 28.407868 -247.557544)
		(mid 28.321637 -247.659661)
		(end 28.29179 -247.789954)
		(stroke
			(width 0.047498)
			(type default)
		)
		(layer "F.Cu")
	)
	(gr_arc
		(start 28.407868 -247.557544)
		(mid 28.494266 -247.455471)
		(end 28.5242 -247.325134)
		(stroke
			(width 0.047498)
			(type default)
		)
		(layer "F.Cu")
	)
	(gr_arc
		(start 28.4353 -32.6263)
		(mid 28.379475 -32.637344)
		(end 28.332176 -32.668972)
		(stroke
			(width 0.047498)
			(type default)
		)
		(layer "F.Cu")
	)
	(gr_arc
		(start 28.458668 -151.006556)
		(mid 28.372437 -151.108673)
		(end 28.34259 -151.238966)
		(stroke
			(width 0.047498)
			(type default)
		)
		(layer "F.Cu")
	)
	(gr_arc
		(start 28.458668 -151.006556)
		(mid 28.545071 -150.904483)
		(end 28.575 -150.774146)
		(stroke
			(width 0.047498)
			(type default)
		)
		(layer "F.Cu")
	)
	(gr_arc
		(start 28.458668 -149.505416)
		(mid 28.372437 -149.607533)
		(end 28.34259 -149.737826)
		(stroke
			(width 0.047498)
			(type default)
		)
		(layer "F.Cu")
	)
	(gr_arc
		(start 28.458668 -149.505416)
		(mid 28.545056 -149.403341)
		(end 28.575 -149.273006)
		(stroke
			(width 0.047498)
			(type default)
		)
		(layer "F.Cu")
	)
	(gr_arc
		(start 28.458668 -146.554952)
		(mid 28.372437 -146.657069)
		(end 28.34259 -146.787362)
		(stroke
			(width 0.047498)
			(type default)
		)
		(layer "F.Cu")
	)
	(gr_arc
		(start 28.458668 -146.554952)
		(mid 28.545069 -146.452879)
		(end 28.575 -146.322542)
		(stroke
			(width 0.047498)
			(type default)
		)
		(layer "F.Cu")
	)
	(gr_arc
		(start 28.458668 -145.053812)
		(mid 28.372437 -145.155929)
		(end 28.34259 -145.286222)
		(stroke
			(width 0.047498)
			(type default)
		)
		(layer "F.Cu")
	)
	(gr_arc
		(start 28.458668 -145.053812)
		(mid 28.545054 -144.951736)
		(end 28.575 -144.821402)
		(stroke
			(width 0.047498)
			(type default)
		)
		(layer "F.Cu")
	)
	(gr_arc
		(start 28.458668 -143.552672)
		(mid 28.372437 -143.654789)
		(end 28.34259 -143.785082)
		(stroke
			(width 0.047498)
			(type default)
		)
		(layer "F.Cu")
	)
	(gr_arc
		(start 28.458668 -143.552672)
		(mid 28.545076 -143.450601)
		(end 28.575 -143.320262)
		(stroke
			(width 0.047498)
			(type default)
		)
		(layer "F.Cu")
	)
	(gr_arc
		(start 28.458668 -142.051532)
		(mid 28.372437 -142.153649)
		(end 28.34259 -142.283942)
		(stroke
			(width 0.047498)
			(type default)
		)
		(layer "F.Cu")
	)
	(gr_arc
		(start 28.458668 -142.051532)
		(mid 28.545062 -141.949458)
		(end 28.575 -141.819122)
		(stroke
			(width 0.047498)
			(type default)
		)
		(layer "F.Cu")
	)
	(gr_line
		(start 28.5242 -345.147646)
		(end 28.55976 -345.112086)
		(stroke
			(width 0.047498)
			(type default)
		)
		(layer "F.Cu")
	)
	(gr_arc
		(start 28.5242 -250.041664)
		(mid 28.494266 -249.911328)
		(end 28.407868 -249.809254)
		(stroke
			(width 0.047498)
			(type default)
		)
		(layer "F.Cu")
	)
	(gr_arc
		(start 28.5242 -248.540524)
		(mid 28.494251 -248.410199)
		(end 28.407868 -248.308114)
		(stroke
			(width 0.047498)
			(type default)
		)
		(layer "F.Cu")
	)
	(gr_line
		(start 28.55976 -344.981784)
		(end 28.55976 -345.112086)
		(stroke
			(width 0.047498)
			(type default)
		)
		(layer "F.Cu")
	)
	(gr_arc
		(start 28.575 -151.989536)
		(mid 28.545056 -151.859208)
		(end 28.458668 -151.757126)
		(stroke
			(width 0.047498)
			(type default)
		)
		(layer "F.Cu")
	)
	(gr_arc
		(start 28.575 -150.488396)
		(mid 28.545078 -150.35805)
		(end 28.458668 -150.255986)
		(stroke
			(width 0.047498)
			(type default)
		)
		(layer "F.Cu")
	)
	(gr_arc
		(start 28.575 -147.537932)
		(mid 28.545054 -147.407605)
		(end 28.458668 -147.305522)
		(stroke
			(width 0.047498)
			(type default)
		)
		(layer "F.Cu")
	)
	(gr_arc
		(start 28.575 -146.036792)
		(mid 28.545076 -145.906447)
		(end 28.458668 -145.804382)
		(stroke
			(width 0.047498)
			(type default)
		)
		(layer "F.Cu")
	)
	(gr_arc
		(start 28.575 -144.535652)
		(mid 28.545062 -144.405319)
		(end 28.458668 -144.303242)
		(stroke
			(width 0.047498)
			(type default)
		)
		(layer "F.Cu")
	)
	(gr_arc
		(start 28.575 -143.034512)
		(mid 28.545084 -142.904161)
		(end 28.458668 -142.802102)
		(stroke
			(width 0.047498)
			(type default)
		)
		(layer "F.Cu")
	)
	(gr_arc
		(start 28.687776 -342.289892)
		(mid 28.519485 -342.177501)
		(end 28.321 -342.138)
		(stroke
			(width 0.047498)
			(type default)
		)
		(layer "F.Cu")
	)
	(gr_line
		(start 28.687776 -342.289892)
		(end 28.829 -342.431116)
		(stroke
			(width 0.047498)
			(type default)
		)
		(layer "F.Cu")
	)
	(gr_arc
		(start 28.701746 -345.8337)
		(mid 28.505385 -345.702489)
		(end 28.273756 -345.656408)
		(stroke
			(width 0.047498)
			(type default)
		)
		(layer "F.Cu")
	)
	(gr_line
		(start 28.754578 -341.577422)
		(end 28.829 -341.503)
		(stroke
			(width 0.047498)
			(type default)
		)
		(layer "F.Cu")
	)
	(gr_line
		(start 28.8544 -249.159014)
		(end 28.8544 -249.708924)
		(stroke
			(width 0.047498)
			(type default)
		)
		(layer "F.Cu")
	)
	(gr_line
		(start 28.8544 -247.657874)
		(end 28.8544 -248.207784)
		(stroke
			(width 0.047498)
			(type default)
		)
		(layer "F.Cu")
	)
	(gr_line
		(start 28.9052 -151.106886)
		(end 28.9052 -151.656796)
		(stroke
			(width 0.047498)
			(type default)
		)
		(layer "F.Cu")
	)
	(gr_line
		(start 28.9052 -149.605746)
		(end 28.9052 -150.155656)
		(stroke
			(width 0.047498)
			(type default)
		)
		(layer "F.Cu")
	)
	(gr_line
		(start 28.9052 -146.655282)
		(end 28.9052 -147.205192)
		(stroke
			(width 0.047498)
			(type default)
		)
		(layer "F.Cu")
	)
	(gr_line
		(start 28.9052 -145.154142)
		(end 28.9052 -145.704052)
		(stroke
			(width 0.047498)
			(type default)
		)
		(layer "F.Cu")
	)
	(gr_line
		(start 28.9052 -143.653002)
		(end 28.9052 -144.202912)
		(stroke
			(width 0.047498)
			(type default)
		)
		(layer "F.Cu")
	)
	(gr_line
		(start 28.9052 -142.151862)
		(end 28.9052 -142.701772)
		(stroke
			(width 0.047498)
			(type default)
		)
		(layer "F.Cu")
	)
	(gr_arc
		(start 29.082746 -32.2961)
		(mid 29.312804 -32.211176)
		(end 29.432504 -31.997142)
		(stroke
			(width 0.047498)
			(type default)
		)
		(layer "F.Cu")
	)
	(gr_arc
		(start 29.432504 -32.849058)
		(mid 29.367248 -32.691555)
		(end 29.209746 -32.6263)
		(stroke
			(width 0.047498)
			(type default)
		)
		(layer "F.Cu")
	)
	(gr_line
		(start 29.432504 -32.849058)
		(end 29.432504 -33.0327)
		(stroke
			(width 0.047498)
			(type default)
		)
		(layer "F.Cu")
	)
	(gr_line
		(start 29.506672 -160.83788)
		(end 29.740098 -160.604454)
		(stroke
			(width 0.047498)
			(type default)
		)
		(layer "F.Cu")
	)
	(gr_line
		(start 29.81706 -362.255054)
		(end 29.95803 -362.396024)
		(stroke
			(width 0.047498)
			(type default)
		)
		(layer "F.Cu")
	)
	(gr_arc
		(start 29.863288 -363.102652)
		(mid 29.829099 -363.15368)
		(end 29.81706 -363.213904)
		(stroke
			(width 0.047498)
			(type default)
		)
		(layer "F.Cu")
	)
	(gr_line
		(start 29.863288 -363.102652)
		(end 29.95803 -363.007656)
		(stroke
			(width 0.047498)
			(type default)
		)
		(layer "F.Cu")
	)
	(gr_arc
		(start 29.95803 -362.396024)
		(mid 30.113964 -362.50018)
		(end 30.297882 -362.53674)
		(stroke
			(width 0.047498)
			(type default)
		)
		(layer "F.Cu")
	)
	(gr_arc
		(start 30.297882 -362.86694)
		(mid 30.113962 -362.903506)
		(end 29.95803 -363.007656)
		(stroke
			(width 0.047498)
			(type default)
		)
		(layer "F.Cu")
	)
	(gr_line
		(start 30.387036 -161.33699)
		(end 30.39237 -161.331656)
		(stroke
			(width 0.047498)
			(type default)
		)
		(layer "F.Cu")
	)
	(gr_line
		(start 30.826202 -160.897824)
		(end 30.831536 -160.89249)
		(stroke
			(width 0.047498)
			(type default)
		)
		(layer "F.Cu")
	)
	(gr_line
		(start 31.088838 -64.114426)
		(end 31.088838 -64.182752)
		(stroke
			(width 0.047498)
			(type default)
		)
		(layer "F.Cu")
	)
	(gr_arc
		(start 31.190692 -63.868554)
		(mid 31.115317 -63.981361)
		(end 31.088838 -64.114426)
		(stroke
			(width 0.047498)
			(type default)
		)
		(layer "F.Cu")
	)
	(gr_line
		(start 31.190692 -63.868554)
		(end 31.267146 -63.7921)
		(stroke
			(width 0.047498)
			(type default)
		)
		(layer "F.Cu")
	)
	(gr_arc
		(start 31.190946 -63.2841)
		(mid 31.303528 -63.359299)
		(end 31.43631 -63.3857)
		(stroke
			(width 0.047498)
			(type default)
		)
		(layer "F.Cu")
	)
	(gr_arc
		(start 31.28772 -362.983272)
		(mid 31.185646 -362.896873)
		(end 31.05531 -362.86694)
		(stroke
			(width 0.047498)
			(type default)
		)
		(layer "F.Cu")
	)
	(gr_arc
		(start 31.28772 -362.983272)
		(mid 31.389814 -363.069573)
		(end 31.52013 -363.09935)
		(stroke
			(width 0.047498)
			(type default)
		)
		(layer "F.Cu")
	)
	(gr_line
		(start 31.341822 -475.198186)
		(end 31.439866 -475.295976)
		(stroke
			(width 0.047498)
			(type default)
		)
		(layer "F.Cu")
	)
	(gr_line
		(start 31.38805 -362.53674)
		(end 31.93796 -362.53674)
		(stroke
			(width 0.047498)
			(type default)
		)
		(layer "F.Cu")
	)
	(gr_line
		(start 31.392368 -476.060516)
		(end 31.562802 -475.890082)
		(stroke
			(width 0.047498)
			(type default)
		)
		(layer "F.Cu")
	)
	(gr_arc
		(start 31.439866 -475.295976)
		(mid 31.582031 -475.391036)
		(end 31.749746 -475.4245)
		(stroke
			(width 0.047498)
			(type default)
		)
		(layer "F.Cu")
	)
	(gr_arc
		(start 31.447232 -372.1227)
		(mid 31.47949 -372.284931)
		(end 31.571438 -372.42242)
		(stroke
			(width 0.047498)
			(type default)
		)
		(layer "F.Cu")
	)
	(gr_arc
		(start 31.451042 -63.7159)
		(mid 31.351508 -63.735699)
		(end 31.267146 -63.7921)
		(stroke
			(width 0.047498)
			(type default)
		)
		(layer "F.Cu")
	)
	(gr_line
		(start 31.46171 -161.589212)
		(end 31.589472 -161.589212)
		(stroke
			(width 0.047498)
			(type default)
		)
		(layer "F.Cu")
	)
	(gr_line
		(start 31.495746 -266.8651)
		(end 31.521146 -266.8651)
		(stroke
			(width 0.047498)
			(type default)
		)
		(layer "F.Cu")
	)
	(gr_line
		(start 31.52013 -363.09935)
		(end 31.80588 -363.09935)
		(stroke
			(width 0.047498)
			(type default)
		)
		(layer "F.Cu")
	)
	(gr_arc
		(start 31.525464 -267.760704)
		(mid 31.510895 -267.744433)
		(end 31.495746 -267.7287)
		(stroke
			(width 0.047498)
			(type default)
		)
		(layer "F.Cu")
	)
	(gr_line
		(start 31.56966 -373.187214)
		(end 32.42056 -373.187214)
		(stroke
			(width 0.047498)
			(type default)
		)
		(layer "F.Cu")
	)
	(gr_arc
		(start 31.571438 -372.42242)
		(mid 31.745896 -372.538977)
		(end 31.951676 -372.5799)
		(stroke
			(width 0.047498)
			(type default)
		)
		(layer "F.Cu")
	)
	(gr_arc
		(start 31.589472 -161.589212)
		(mid 31.707558 -161.565705)
		(end 31.807658 -161.498788)
		(stroke
			(width 0.047498)
			(type default)
		)
		(layer "F.Cu")
	)
	(gr_line
		(start 31.603442 -274.618958)
		(end 31.687008 -274.535646)
		(stroke
			(width 0.047498)
			(type default)
		)
		(layer "F.Cu")
	)
	(gr_line
		(start 31.603442 -273.690842)
		(end 31.687008 -273.774154)
		(stroke
			(width 0.047498)
			(type default)
		)
		(layer "F.Cu")
	)
	(gr_arc
		(start 31.608522 -366.550448)
		(mid 31.653862 -366.548706)
		(end 31.698946 -366.54359)
		(stroke
			(width 0.047498)
			(type default)
		)
		(layer "F.Cu")
	)
	(gr_arc
		(start 31.644082 -267.971524)
		(mid 31.595404 -267.860129)
		(end 31.525464 -267.760704)
		(stroke
			(width 0.047498)
			(type default)
		)
		(layer "F.Cu")
	)
	(gr_line
		(start 31.65221 -162.068764)
		(end 31.876746 -162.2933)
		(stroke
			(width 0.047498)
			(type default)
		)
		(layer "F.Cu")
	)
	(gr_arc
		(start 31.673546 -268.15796)
		(mid 31.666087 -268.063594)
		(end 31.644082 -267.971524)
		(stroke
			(width 0.047498)
			(type default)
		)
		(layer "F.Cu")
	)
	(gr_arc
		(start 31.687008 -273.774154)
		(mid 31.92566 -273.93371)
		(end 32.2072 -273.9898)
		(stroke
			(width 0.047498)
			(type default)
		)
		(layer "F.Cu")
	)
	(gr_arc
		(start 31.698946 -366.54359)
		(mid 31.883027 -366.485059)
		(end 32.03956 -366.371886)
		(stroke
			(width 0.047498)
			(type default)
		)
		(layer "F.Cu")
	)
	(gr_line
		(start 31.749746 -475.4245)
		(end 32.003746 -475.4245)
		(stroke
			(width 0.047498)
			(type default)
		)
		(layer "F.Cu")
	)
	(gr_line
		(start 31.76016 -263.586214)
		(end 31.887414 -263.458706)
		(stroke
			(width 0.047498)
			(type default)
		)
		(layer "F.Cu")
	)
	(gr_arc
		(start 31.80588 -363.09935)
		(mid 31.936164 -363.069501)
		(end 32.03829 -362.983272)
		(stroke
			(width 0.047498)
			(type default)
		)
		(layer "F.Cu")
	)
	(gr_line
		(start 31.807658 -161.498788)
		(end 31.876746 -161.4297)
		(stroke
			(width 0.047498)
			(type default)
		)
		(layer "F.Cu")
	)
	(gr_arc
		(start 31.825946 -475.781116)
		(mid 31.683546 -475.809441)
		(end 31.562802 -475.890082)
		(stroke
			(width 0.047498)
			(type default)
		)
		(layer "F.Cu")
	)
	(gr_line
		(start 31.825946 -475.781116)
		(end 32.003746 -475.781116)
		(stroke
			(width 0.047498)
			(type default)
		)
		(layer "F.Cu")
	)
	(gr_line
		(start 31.887414 -263.458706)
		(end 31.953708 -263.392412)
		(stroke
			(width 0.047498)
			(type default)
		)
		(layer "F.Cu")
	)
	(gr_arc
		(start 31.931356 -57.3024)
		(mid 32.279828 -57.233095)
		(end 32.575246 -57.0357)
		(stroke
			(width 0.047498)
			(type default)
		)
		(layer "F.Cu")
	)
	(gr_line
		(start 31.941262 -366.880648)
		(end 32.277812 -366.880648)
		(stroke
			(width 0.047498)
			(type default)
		)
		(layer "F.Cu")
	)
	(gr_line
		(start 31.951676 -372.5799)
		(end 32.003746 -372.5799)
		(stroke
			(width 0.047498)
			(type default)
		)
		(layer "F.Cu")
	)
	(gr_arc
		(start 32.000444 -469.19642)
		(mid 32.3243 -469.131961)
		(end 32.598868 -468.948516)
		(stroke
			(width 0.047498)
			(type default)
		)
		(layer "F.Cu")
	)
	(gr_arc
		(start 32.003746 -475.4245)
		(mid 32.319899 -475.361706)
		(end 32.587946 -475.182692)
		(stroke
			(width 0.047498)
			(type default)
		)
		(layer "F.Cu")
	)
	(gr_arc
		(start 32.003746 -372.5799)
		(mid 32.128557 -372.555084)
		(end 32.234378 -372.484396)
		(stroke
			(width 0.047498)
			(type default)
		)
		(layer "F.Cu")
	)
	(gr_arc
		(start 32.003746 -267.3477)
		(mid 31.862396 -267.00645)
		(end 31.521146 -266.8651)
		(stroke
			(width 0.047498)
			(type default)
		)
		(layer "F.Cu")
	)
	(gr_line
		(start 32.003746 -267.3477)
		(end 32.003746 -267.82522)
		(stroke
			(width 0.047498)
			(type default)
		)
		(layer "F.Cu")
	)
	(gr_line
		(start 32.022542 -269.334996)
		(end 32.829246 -270.1417)
		(stroke
			(width 0.047498)
			(type default)
		)
		(layer "F.Cu")
	)
	(gr_line
		(start 32.03956 -366.371886)
		(end 32.306514 -366.104932)
		(stroke
			(width 0.047498)
			(type default)
		)
		(layer "F.Cu")
	)
	(gr_line
		(start 32.155638 -166.6113)
		(end 32.155892 -166.6113)
		(stroke
			(width 0.047498)
			(type default)
		)
		(layer "F.Cu")
	)
	(gr_line
		(start 32.181546 -463.338164)
		(end 32.511746 -463.338164)
		(stroke
			(width 0.047498)
			(type default)
		)
		(layer "F.Cu")
	)
	(gr_line
		(start 32.19069 -164.863018)
		(end 32.22625 -164.827458)
		(stroke
			(width 0.047498)
			(type default)
		)
		(layer "F.Cu")
	)
	(gr_arc
		(start 32.2072 -274.32)
		(mid 31.925661 -274.376095)
		(end 31.687008 -274.535646)
		(stroke
			(width 0.047498)
			(type default)
		)
		(layer "F.Cu")
	)
	(gr_arc
		(start 32.2072 -273.9898)
		(mid 32.512231 -273.929152)
		(end 32.770826 -273.756374)
		(stroke
			(width 0.047498)
			(type default)
		)
		(layer "F.Cu")
	)
	(gr_arc
		(start 32.225996 -63.79845)
		(mid 32.134515 -63.737324)
		(end 32.026606 -63.7159)
		(stroke
			(width 0.047498)
			(type default)
		)
		(layer "F.Cu")
	)
	(gr_line
		(start 32.225996 -63.79845)
		(end 32.575246 -64.1477)
		(stroke
			(width 0.047498)
			(type default)
		)
		(layer "F.Cu")
	)
	(gr_line
		(start 32.22625 -164.827458)
		(end 32.22625 -164.827204)
		(stroke
			(width 0.047498)
			(type default)
		)
		(layer "F.Cu")
	)
	(gr_line
		(start 32.234378 -372.484396)
		(end 32.42056 -372.298214)
		(stroke
			(width 0.047498)
			(type default)
		)
		(layer "F.Cu")
	)
	(gr_arc
		(start 32.268668 -63.3857)
		(mid 32.434578 -63.352675)
		(end 32.575246 -63.2587)
		(stroke
			(width 0.047498)
			(type default)
		)
		(layer "F.Cu")
	)
	(gr_arc
		(start 32.2707 -362.86694)
		(mid 32.140365 -362.896876)
		(end 32.03829 -362.983272)
		(stroke
			(width 0.047498)
			(type default)
		)
		(layer "F.Cu")
	)
	(gr_arc
		(start 32.378396 -366.075214)
		(mid 32.339501 -366.082933)
		(end 32.306514 -366.104932)
		(stroke
			(width 0.047498)
			(type default)
		)
		(layer "F.Cu")
	)
	(gr_line
		(start 32.378396 -366.075214)
		(end 32.42056 -366.075214)
		(stroke
			(width 0.047498)
			(type default)
		)
		(layer "F.Cu")
	)
	(gr_arc
		(start 32.37865 -366.922304)
		(mid 32.332357 -366.891498)
		(end 32.277812 -366.880648)
		(stroke
			(width 0.047498)
			(type default)
		)
		(layer "F.Cu")
	)
	(gr_line
		(start 32.37865 -366.922304)
		(end 32.42056 -366.964214)
		(stroke
			(width 0.047498)
			(type default)
		)
		(layer "F.Cu")
	)
	(gr_arc
		(start 32.44469 -57.794144)
		(mid 32.265808 -57.674589)
		(end 32.0548 -57.6326)
		(stroke
			(width 0.047498)
			(type default)
		)
		(layer "F.Cu")
	)
	(gr_line
		(start 32.44469 -57.794144)
		(end 32.575246 -57.9247)
		(stroke
			(width 0.047498)
			(type default)
		)
		(layer "F.Cu")
	)
	(gr_line
		(start 32.459676 -165.06063)
		(end 32.459676 -165.060884)
		(stroke
			(width 0.047498)
			(type default)
		)
		(layer "F.Cu")
	)
	(gr_line
		(start 32.459676 -165.06063)
		(end 32.693102 -164.827204)
		(stroke
			(width 0.047498)
			(type default)
		)
		(layer "F.Cu")
	)
	(gr_line
		(start 32.511746 -463.007964)
		(end 32.511746 -463.008218)
		(stroke
			(width 0.047498)
			(type default)
		)
		(layer "F.Cu")
	)
	(gr_line
		(start 32.511746 -163.9697)
		(end 32.606996 -164.06495)
		(stroke
			(width 0.047498)
			(type default)
		)
		(layer "F.Cu")
	)
	(gr_arc
		(start 32.542734 -476.004382)
		(mid 32.295444 -475.839148)
		(end 32.003746 -475.781116)
		(stroke
			(width 0.047498)
			(type default)
		)
		(layer "F.Cu")
	)
	(gr_line
		(start 32.542734 -476.004382)
		(end 32.598868 -476.060516)
		(stroke
			(width 0.047498)
			(type default)
		)
		(layer "F.Cu")
	)
	(gr_line
		(start 32.564324 -269.2527)
		(end 32.829246 -269.2527)
		(stroke
			(width 0.047498)
			(type default)
		)
		(layer "F.Cu")
	)
	(gr_arc
		(start 32.578802 -469.81745)
		(mid 32.256696 -469.602226)
		(end 31.876746 -469.52662)
		(stroke
			(width 0.047498)
			(type default)
		)
		(layer "F.Cu")
	)
	(gr_line
		(start 32.578802 -469.81745)
		(end 32.598868 -469.837516)
		(stroke
			(width 0.047498)
			(type default)
		)
		(layer "F.Cu")
	)
	(gr_line
		(start 32.587946 -475.182692)
		(end 32.598868 -475.171516)
		(stroke
			(width 0.047498)
			(type default)
		)
		(layer "F.Cu")
	)
	(gr_arc
		(start 32.606996 -164.44595)
		(mid 32.638215 -164.408198)
		(end 32.662114 -164.365432)
		(stroke
			(width 0.047498)
			(type default)
		)
		(layer "F.Cu")
	)
	(gr_arc
		(start 32.662114 -164.365432)
		(mid 32.662241 -164.365051)
		(end 32.662368 -164.36467)
		(stroke
			(width 0.047498)
			(type default)
		)
		(layer "F.Cu")
	)
	(gr_arc
		(start 32.662368 -164.36467)
		(mid 32.669442 -164.347494)
		(end 32.675322 -164.329872)
		(stroke
			(width 0.047498)
			(type default)
		)
		(layer "F.Cu")
	)
	(gr_arc
		(start 32.675322 -164.329872)
		(mid 32.685789 -164.262157)
		(end 32.678878 -164.193982)
		(stroke
			(width 0.047498)
			(type default)
		)
		(layer "F.Cu")
	)
	(gr_arc
		(start 32.678878 -164.193982)
		(mid 32.651983 -164.124421)
		(end 32.606996 -164.06495)
		(stroke
			(width 0.047498)
			(type default)
		)
		(layer "F.Cu")
	)
	(gr_arc
		(start 32.757618 -263.847072)
		(mid 32.36214 -263.68326)
		(end 31.966662 -263.847072)
		(stroke
			(width 0.047498)
			(type default)
		)
		(layer "F.Cu")
	)
	(gr_line
		(start 32.757618 -263.847072)
		(end 32.829246 -263.9187)
		(stroke
			(width 0.047498)
			(type default)
		)
		(layer "F.Cu")
	)
	(gr_arc
		(start 32.770826 -274.553426)
		(mid 32.512232 -274.380639)
		(end 32.2072 -274.32)
		(stroke
			(width 0.047498)
			(type default)
		)
		(layer "F.Cu")
	)
	(gr_line
		(start 32.770826 -274.553426)
		(end 32.8168 -274.5994)
		(stroke
			(width 0.047498)
			(type default)
		)
		(layer "F.Cu")
	)
	(gr_line
		(start 32.770826 -273.756374)
		(end 32.8168 -273.7104)
		(stroke
			(width 0.047498)
			(type default)
		)
		(layer "F.Cu")
	)
	(gr_arc
		(start 32.789622 -160.30956)
		(mid 33.146352 -160.238602)
		(end 33.448752 -160.03651)
		(stroke
			(width 0.047498)
			(type default)
		)
		(layer "F.Cu")
	)
	(gr_arc
		(start 32.829246 -263.0297)
		(mid 32.355402 -263.123971)
		(end 31.953708 -263.392412)
		(stroke
			(width 0.047498)
			(type default)
		)
		(layer "F.Cu")
	)
	(gr_arc
		(start 32.892746 -166.5097)
		(mid 33.17535 -166.453552)
		(end 33.41497 -166.293546)
		(stroke
			(width 0.047498)
			(type default)
		)
		(layer "F.Cu")
	)
	(gr_line
		(start 33.002474 -164.517832)
		(end 33.17113 -164.34943)
		(stroke
			(width 0.047498)
			(type default)
		)
		(layer "F.Cu")
	)
	(gr_arc
		(start 33.17113 -164.34943)
		(mid 33.322426 -164.123)
		(end 33.3756 -163.855908)
		(stroke
			(width 0.047498)
			(type default)
		)
		(layer "F.Cu")
	)
	(gr_arc
		(start 33.30956 -372.298214)
		(mid 33.668035 -372.5377)
		(end 34.090864 -372.62181)
		(stroke
			(width 0.047498)
			(type default)
		)
		(layer "F.Cu")
	)
	(gr_line
		(start 33.30956 -366.92967)
		(end 33.30956 -366.964214)
		(stroke
			(width 0.047498)
			(type default)
		)
		(layer "F.Cu")
	)
	(gr_line
		(start 33.30956 -366.075214)
		(end 33.445196 -366.21085)
		(stroke
			(width 0.047498)
			(type default)
		)
		(layer "F.Cu")
	)
	(gr_arc
		(start 33.314894 -167.014906)
		(mid 33.121226 -166.885408)
		(end 32.892746 -166.8399)
		(stroke
			(width 0.047498)
			(type default)
		)
		(layer "F.Cu")
	)
	(gr_line
		(start 33.314894 -167.014906)
		(end 33.448752 -167.14851)
		(stroke
			(width 0.047498)
			(type default)
		)
		(layer "F.Cu")
	)
	(gr_arc
		(start 33.333944 -366.870742)
		(mid 33.315879 -366.897778)
		(end 33.30956 -366.92967)
		(stroke
			(width 0.047498)
			(type default)
		)
		(layer "F.Cu")
	)
	(gr_line
		(start 33.333944 -366.870742)
		(end 33.41878 -366.78616)
		(stroke
			(width 0.047498)
			(type default)
		)
		(layer "F.Cu")
	)
	(gr_line
		(start 33.3756 -163.7284)
		(end 33.3756 -163.855908)
		(stroke
			(width 0.047498)
			(type default)
		)
		(layer "F.Cu")
	)
	(gr_line
		(start 33.41497 -166.293546)
		(end 33.448752 -166.25951)
		(stroke
			(width 0.047498)
			(type default)
		)
		(layer "F.Cu")
	)
	(gr_arc
		(start 33.443926 -160.920684)
		(mid 33.132774 -160.712779)
		(end 32.765746 -160.63976)
		(stroke
			(width 0.047498)
			(type default)
		)
		(layer "F.Cu")
	)
	(gr_line
		(start 33.443926 -160.920684)
		(end 33.448752 -160.92551)
		(stroke
			(width 0.047498)
			(type default)
		)
		(layer "F.Cu")
	)
	(gr_arc
		(start 33.445196 -366.21085)
		(mid 33.595636 -366.311408)
		(end 33.77311 -366.34674)
		(stroke
			(width 0.047498)
			(type default)
		)
		(layer "F.Cu")
	)
	(gr_line
		(start 33.464246 -64.024764)
		(end 33.464246 -64.1477)
		(stroke
			(width 0.047498)
			(type default)
		)
		(layer "F.Cu")
	)
	(gr_line
		(start 33.464246 -63.2587)
		(end 33.473644 -63.267844)
		(stroke
			(width 0.047498)
			(type default)
		)
		(layer "F.Cu")
	)
	(gr_arc
		(start 33.464246 -57.0357)
		(mid 33.808613 -57.265785)
		(end 34.214816 -57.346596)
		(stroke
			(width 0.047498)
			(type default)
		)
		(layer "F.Cu")
	)
	(gr_arc
		(start 33.473644 -63.267844)
		(mid 33.735368 -63.452323)
		(end 34.043874 -63.5381)
		(stroke
			(width 0.047498)
			(type default)
		)
		(layer "F.Cu")
	)
	(gr_line
		(start 33.487868 -475.171516)
		(end 33.581594 -475.264988)
		(stroke
			(width 0.047498)
			(type default)
		)
		(layer "F.Cu")
	)
	(gr_arc
		(start 33.487868 -468.948516)
		(mid 33.92894 -469.243303)
		(end 34.449258 -469.346788)
		(stroke
			(width 0.047498)
			(type default)
		)
		(layer "F.Cu")
	)
	(gr_arc
		(start 33.508696 -63.917576)
		(mid 33.475782 -63.96674)
		(end 33.464246 -64.024764)
		(stroke
			(width 0.047498)
			(type default)
		)
		(layer "F.Cu")
	)
	(gr_arc
		(start 33.581594 -475.264988)
		(mid 33.921787 -475.504515)
		(end 34.322766 -475.615508)
		(stroke
			(width 0.047498)
			(type default)
		)
		(layer "F.Cu")
	)
	(gr_arc
		(start 33.615884 -63.873126)
		(mid 33.557869 -63.884684)
		(end 33.508696 -63.917576)
		(stroke
			(width 0.047498)
			(type default)
		)
		(layer "F.Cu")
	)
	(gr_line
		(start 33.615884 -63.873126)
		(end 33.804606 -63.873126)
		(stroke
			(width 0.047498)
			(type default)
		)
		(layer "F.Cu")
	)
	(gr_arc
		(start 33.681924 -366.67694)
		(mid 33.53948 -366.705367)
		(end 33.41878 -366.78616)
		(stroke
			(width 0.047498)
			(type default)
		)
		(layer "F.Cu")
	)
	(gr_line
		(start 33.7058 -274.5994)
		(end 33.724596 -274.58035)
		(stroke
			(width 0.047498)
			(type default)
		)
		(layer "F.Cu")
	)
	(gr_line
		(start 33.7058 -273.7104)
		(end 33.724596 -273.72945)
		(stroke
			(width 0.047498)
			(type default)
		)
		(layer "F.Cu")
	)
	(gr_line
		(start 33.718246 -269.2527)
		(end 33.844738 -269.378938)
		(stroke
			(width 0.047498)
			(type default)
		)
		(layer "F.Cu")
	)
	(gr_arc
		(start 33.718246 -263.0297)
		(mid 33.9295 -263.194182)
		(end 34.174684 -263.301734)
		(stroke
			(width 0.047498)
			(type default)
		)
		(layer "F.Cu")
	)
	(gr_arc
		(start 33.724596 -273.72945)
		(mid 34.013155 -273.922166)
		(end 34.3535 -273.9898)
		(stroke
			(width 0.047498)
			(type default)
		)
		(layer "F.Cu")
	)
	(gr_arc
		(start 33.75025 -475.951804)
		(mid 33.608238 -475.980052)
		(end 33.487868 -476.060516)
		(stroke
			(width 0.047498)
			(type default)
		)
		(layer "F.Cu")
	)
	(gr_line
		(start 33.75025 -475.951804)
		(end 34.109406 -475.951804)
		(stroke
			(width 0.047498)
			(type default)
		)
		(layer "F.Cu")
	)
	(gr_arc
		(start 33.844738 -269.378938)
		(mid 34.095516 -269.546563)
		(end 34.391346 -269.605506)
		(stroke
			(width 0.047498)
			(type default)
		)
		(layer "F.Cu")
	)
	(gr_arc
		(start 33.875472 -469.676988)
		(mid 33.665711 -469.718712)
		(end 33.487868 -469.837516)
		(stroke
			(width 0.047498)
			(type default)
		)
		(layer "F.Cu")
	)
	(gr_line
		(start 33.875472 -469.676988)
		(end 34.116518 -469.676988)
		(stroke
			(width 0.047498)
			(type default)
		)
		(layer "F.Cu")
	)
	(gr_arc
		(start 33.877504 -372.95201)
		(mid 33.570153 -373.013146)
		(end 33.30956 -373.187214)
		(stroke
			(width 0.047498)
			(type default)
		)
		(layer "F.Cu")
	)
	(gr_arc
		(start 34.043874 -63.5381)
		(mid 34.071784 -63.540547)
		(end 34.099754 -63.542164)
		(stroke
			(width 0.047498)
			(type default)
		)
		(layer "F.Cu")
	)
	(gr_arc
		(start 34.052002 -263.714992)
		(mid 33.872955 -263.796913)
		(end 33.718246 -263.9187)
		(stroke
			(width 0.047498)
			(type default)
		)
		(layer "F.Cu")
	)
	(gr_line
		(start 34.052002 -263.714992)
		(end 34.112962 -263.695434)
		(stroke
			(width 0.047498)
			(type default)
		)
		(layer "F.Cu")
	)
	(gr_arc
		(start 34.06267 -57.676796)
		(mid 33.738794 -57.741219)
		(end 33.464246 -57.9247)
		(stroke
			(width 0.047498)
			(type default)
		)
		(layer "F.Cu")
	)
	(gr_arc
		(start 34.099754 -63.542164)
		(mid 34.118546 -63.542733)
		(end 34.137346 -63.542926)
		(stroke
			(width 0.047498)
			(type default)
		)
		(layer "F.Cu")
	)
	(gr_arc
		(start 34.166556 -263.687052)
		(mid 34.139434 -263.689163)
		(end 34.112962 -263.695434)
		(stroke
			(width 0.047498)
			(type default)
		)
		(layer "F.Cu")
	)
	(gr_arc
		(start 34.174684 -263.301734)
		(mid 34.21122 -263.311901)
		(end 34.24809 -263.320784)
		(stroke
			(width 0.047498)
			(type default)
		)
		(layer "F.Cu")
	)
	(gr_arc
		(start 34.215578 -269.935706)
		(mid 33.946427 -269.989244)
		(end 33.718246 -270.1417)
		(stroke
			(width 0.047498)
			(type default)
		)
		(layer "F.Cu")
	)
	(gr_arc
		(start 34.305748 -263.675368)
		(mid 34.235907 -263.678287)
		(end 34.166556 -263.687052)
		(stroke
			(width 0.047498)
			(type default)
		)
		(layer "F.Cu")
	)
	(gr_line
		(start 34.305748 -263.675368)
		(end 34.416238 -263.675368)
		(stroke
			(width 0.047498)
			(type default)
		)
		(layer "F.Cu")
	)
	(gr_arc
		(start 34.322766 -475.615508)
		(mid 34.382381 -475.620021)
		(end 34.442146 -475.621604)
		(stroke
			(width 0.047498)
			(type default)
		)
		(layer "F.Cu")
	)
	(gr_arc
		(start 34.337752 -166.25951)
		(mid 34.755532 -166.538666)
		(end 35.248342 -166.6367)
		(stroke
			(width 0.047498)
			(type default)
		)
		(layer "F.Cu")
	)
	(gr_line
		(start 34.337752 -160.03651)
		(end 34.362136 -160.061148)
		(stroke
			(width 0.047498)
			(type default)
		)
		(layer "F.Cu")
	)
	(gr_arc
		(start 34.3535 -274.32)
		(mid 34.013168 -274.387649)
		(end 33.724596 -274.58035)
		(stroke
			(width 0.047498)
			(type default)
		)
		(layer "F.Cu")
	)
	(gr_arc
		(start 34.362136 -160.061148)
		(mid 34.678537 -160.272511)
		(end 35.051746 -160.346644)
		(stroke
			(width 0.047498)
			(type default)
		)
		(layer "F.Cu")
	)
	(gr_arc
		(start 34.4551 -273.9898)
		(mid 34.616606 -273.957768)
		(end 34.75355 -273.866356)
		(stroke
			(width 0.047498)
			(type default)
		)
		(layer "F.Cu")
	)
	(gr_line
		(start 34.483548 -263.346692)
		(end 34.746438 -263.346692)
		(stroke
			(width 0.047498)
			(type default)
		)
		(layer "F.Cu")
	)
	(gr_arc
		(start 34.736786 -274.43684)
		(mid 34.607561 -274.350403)
		(end 34.4551 -274.32)
		(stroke
			(width 0.047498)
			(type default)
		)
		(layer "F.Cu")
	)
	(gr_line
		(start 34.736786 -274.43684)
		(end 34.919158 -274.618958)
		(stroke
			(width 0.047498)
			(type default)
		)
		(layer "F.Cu")
	)
	(gr_line
		(start 34.75355 -273.866356)
		(end 34.920174 -273.699478)
		(stroke
			(width 0.047498)
			(type default)
		)
		(layer "F.Cu")
	)
	(gr_arc
		(start 34.776156 -166.9669)
		(mid 34.538887 -167.014096)
		(end 34.337752 -167.14851)
		(stroke
			(width 0.047498)
			(type default)
		)
		(layer "F.Cu")
	)
	(gr_line
		(start 34.776156 -166.9669)
		(end 34.915602 -166.9669)
		(stroke
			(width 0.047498)
			(type default)
		)
		(layer "F.Cu")
	)
	(gr_arc
		(start 34.938208 -160.676844)
		(mid 34.613263 -160.74148)
		(end 34.337752 -160.92551)
		(stroke
			(width 0.047498)
			(type default)
		)
		(layer "F.Cu")
	)
	(gr_line
		(start 35.051746 -473.748354)
		(end 35.281362 -473.518738)
		(stroke
			(width 0.047498)
			(type default)
		)
		(layer "F.Cu")
	)
	(gr_line
		(start 35.051746 -472.820238)
		(end 35.144202 -472.912694)
		(stroke
			(width 0.047498)
			(type default)
		)
		(layer "F.Cu")
	)
	(gr_arc
		(start 35.44824 -473.479622)
		(mid 35.359243 -473.475461)
		(end 35.281362 -473.518738)
		(stroke
			(width 0.047498)
			(type default)
		)
		(layer "F.Cu")
	)
	(gr_line
		(start 35.64382 -256.849626)
		(end 35.877246 -256.6162)
		(stroke
			(width 0.047498)
			(type default)
		)
		(layer "F.Cu")
	)
	(gr_line
		(start 36.321746 -369.918742)
		(end 36.436808 -370.034058)
		(stroke
			(width 0.047498)
			(type default)
		)
		(layer "F.Cu")
	)
	(gr_arc
		(start 36.436808 -370.034058)
		(mid 36.640401 -370.170049)
		(end 36.880546 -370.2177)
		(stroke
			(width 0.047498)
			(type default)
		)
		(layer "F.Cu")
	)
	(gr_arc
		(start 36.467796 -362.53674)
		(mid 36.63393 -362.467926)
		(end 36.702746 -362.30179)
		(stroke
			(width 0.047498)
			(type default)
		)
		(layer "F.Cu")
	)
	(gr_line
		(start 36.4744 -190.434214)
		(end 36.4744 -190.627254)
		(stroke
			(width 0.047498)
			(type default)
		)
		(layer "F.Cu")
	)
	(gr_arc
		(start 36.550346 -465.536788)
		(mid 36.575089 -465.534685)
		(end 36.599114 -465.528406)
		(stroke
			(width 0.047498)
			(type default)
		)
		(layer "F.Cu")
	)
	(gr_arc
		(start 36.57092 -362.970318)
		(mid 36.456613 -362.893848)
		(end 36.321746 -362.86694)
		(stroke
			(width 0.047498)
			(type default)
		)
		(layer "F.Cu")
	)
	(gr_line
		(start 36.57092 -362.970318)
		(end 36.702746 -363.10189)
		(stroke
			(width 0.047498)
			(type default)
		)
		(layer "F.Cu")
	)
	(gr_arc
		(start 36.594796 -366.34674)
		(mid 36.627904 -366.344234)
		(end 36.660328 -366.337088)
		(stroke
			(width 0.047498)
			(type default)
		)
		(layer "F.Cu")
	)
	(gr_arc
		(start 36.599114 -465.528406)
		(mid 36.67416 -465.473109)
		(end 36.702746 -465.384388)
		(stroke
			(width 0.047498)
			(type default)
		)
		(layer "F.Cu")
	)
	(gr_arc
		(start 36.636452 -163.920424)
		(mid 36.72529 -164.134847)
		(end 36.939728 -164.2237)
		(stroke
			(width 0.047498)
			(type default)
		)
		(layer "F.Cu")
	)
	(gr_arc
		(start 36.6522 -466.0138)
		(mid 36.661466 -466.060797)
		(end 36.688014 -466.100668)
		(stroke
			(width 0.047498)
			(type default)
		)
		(layer "F.Cu")
	)
	(gr_arc
		(start 36.6522 -465.993988)
		(mid 36.615003 -465.904185)
		(end 36.5252 -465.866988)
		(stroke
			(width 0.047498)
			(type default)
		)
		(layer "F.Cu")
	)
	(gr_line
		(start 36.6522 -465.993988)
		(end 36.6522 -466.0138)
		(stroke
			(width 0.047498)
			(type default)
		)
		(layer "F.Cu")
	)
	(gr_arc
		(start 36.660836 -366.337088)
		(mid 36.660582 -366.337088)
		(end 36.660328 -366.337088)
		(stroke
			(width 0.047498)
			(type default)
		)
		(layer "F.Cu")
	)
	(gr_arc
		(start 36.660836 -366.337088)
		(mid 36.782808 -366.252574)
		(end 36.829746 -366.11179)
		(stroke
			(width 0.047498)
			(type default)
		)
		(layer "F.Cu")
	)
	(gr_line
		(start 36.688014 -466.100668)
		(end 36.7538 -466.1662)
		(stroke
			(width 0.047498)
			(type default)
		)
		(layer "F.Cu")
	)
	(gr_arc
		(start 36.702746 -363.10189)
		(mid 36.962968 -363.275777)
		(end 37.269928 -363.33684)
		(stroke
			(width 0.047498)
			(type default)
		)
		(layer "F.Cu")
	)
	(gr_arc
		(start 36.72586 -469.346788)
		(mid 36.797724 -469.317043)
		(end 36.82746 -469.245188)
		(stroke
			(width 0.047498)
			(type default)
		)
		(layer "F.Cu")
	)
	(gr_arc
		(start 36.72586 -263.346692)
		(mid 36.742345 -263.345231)
		(end 36.758372 -263.341104)
		(stroke
			(width 0.047498)
			(type default)
		)
		(layer "F.Cu")
	)
	(gr_arc
		(start 36.72586 -259.536692)
		(mid 36.741031 -259.535423)
		(end 36.755832 -259.531866)
		(stroke
			(width 0.047498)
			(type default)
		)
		(layer "F.Cu")
	)
	(gr_arc
		(start 36.72586 -160.346644)
		(mid 36.742475 -160.34521)
		(end 36.758626 -160.341056)
		(stroke
			(width 0.047498)
			(type default)
		)
		(layer "F.Cu")
	)
	(gr_arc
		(start 36.72586 -156.536644)
		(mid 36.7401 -156.535605)
		(end 36.754054 -156.53258)
		(stroke
			(width 0.047498)
			(type default)
		)
		(layer "F.Cu")
	)
	(gr_arc
		(start 36.72586 -57.346596)
		(mid 36.737112 -57.345812)
		(end 36.748212 -57.343802)
		(stroke
			(width 0.047498)
			(type default)
		)
		(layer "F.Cu")
	)
	(gr_arc
		(start 36.72586 -53.536596)
		(mid 36.797726 -53.506852)
		(end 36.82746 -53.434996)
		(stroke
			(width 0.047498)
			(type default)
		)
		(layer "F.Cu")
	)
	(gr_arc
		(start 36.745164 -160.678368)
		(mid 36.735548 -160.677156)
		(end 36.72586 -160.676844)
		(stroke
			(width 0.047498)
			(type default)
		)
		(layer "F.Cu")
	)
	(gr_arc
		(start 36.747958 -160.67913)
		(mid 36.746564 -160.678738)
		(end 36.745164 -160.678368)
		(stroke
			(width 0.047498)
			(type default)
		)
		(layer "F.Cu")
	)
	(gr_arc
		(start 36.748212 -57.343802)
		(mid 36.80512 -57.308253)
		(end 36.82746 -57.244996)
		(stroke
			(width 0.047498)
			(type default)
		)
		(layer "F.Cu")
	)
	(gr_arc
		(start 36.7538 -466.1662)
		(mid 36.946556 -466.294981)
		(end 37.173916 -466.34019)
		(stroke
			(width 0.047498)
			(type default)
		)
		(layer "F.Cu")
	)
	(gr_arc
		(start 36.754054 -156.53258)
		(mid 36.807057 -156.496085)
		(end 36.82746 -156.435044)
		(stroke
			(width 0.047498)
			(type default)
		)
		(layer "F.Cu")
	)
	(gr_arc
		(start 36.755832 -259.531866)
		(mid 36.807529 -259.495227)
		(end 36.82746 -259.435092)
		(stroke
			(width 0.047498)
			(type default)
		)
		(layer "F.Cu")
	)
	(gr_arc
		(start 36.756086 -469.68156)
		(mid 36.741147 -469.678117)
		(end 36.72586 -469.676988)
		(stroke
			(width 0.047498)
			(type default)
		)
		(layer "F.Cu")
	)
	(gr_arc
		(start 36.758372 -263.341104)
		(mid 36.808435 -263.304254)
		(end 36.82746 -263.245092)
		(stroke
			(width 0.047498)
			(type default)
		)
		(layer "F.Cu")
	)
	(gr_arc
		(start 36.758372 -259.872226)
		(mid 36.742333 -259.868238)
		(end 36.72586 -259.866892)
		(stroke
			(width 0.047498)
			(type default)
		)
		(layer "F.Cu")
	)
	(gr_arc
		(start 36.758372 -53.87213)
		(mid 36.742333 -53.868142)
		(end 36.72586 -53.866796)
		(stroke
			(width 0.047498)
			(type default)
		)
		(layer "F.Cu")
	)
	(gr_arc
		(start 36.758626 -160.341056)
		(mid 36.808499 -160.30412)
		(end 36.82746 -160.245044)
		(stroke
			(width 0.047498)
			(type default)
		)
		(layer "F.Cu")
	)
	(gr_arc
		(start 36.75888 -156.872178)
		(mid 36.742591 -156.86814)
		(end 36.72586 -156.866844)
		(stroke
			(width 0.047498)
			(type default)
		)
		(layer "F.Cu")
	)
	(gr_arc
		(start 36.778438 -465.201762)
		(mid 36.722398 -465.285537)
		(end 36.702746 -465.384388)
		(stroke
			(width 0.047498)
			(type default)
		)
		(layer "F.Cu")
	)
	(gr_line
		(start 36.804346 -190.764414)
		(end 36.804346 -190.957454)
		(stroke
			(width 0.047498)
			(type default)
		)
		(layer "F.Cu")
	)
	(gr_arc
		(start 36.82746 -469.953848)
		(mid 36.828019 -469.961932)
		(end 36.829746 -469.96985)
		(stroke
			(width 0.047498)
			(type default)
		)
		(layer "F.Cu")
	)
	(gr_arc
		(start 36.82746 -469.778588)
		(mid 36.807691 -469.71837)
		(end 36.756086 -469.68156)
		(stroke
			(width 0.047498)
			(type default)
		)
		(layer "F.Cu")
	)
	(gr_line
		(start 36.82746 -469.778588)
		(end 36.82746 -469.953848)
		(stroke
			(width 0.047498)
			(type default)
		)
		(layer "F.Cu")
	)
	(gr_line
		(start 36.82746 -469.064594)
		(end 36.82746 -469.245188)
		(stroke
			(width 0.047498)
			(type default)
		)
		(layer "F.Cu")
	)
	(gr_arc
		(start 36.82746 -264.028428)
		(mid 36.835057 -264.065815)
		(end 36.85667 -264.097262)
		(stroke
			(width 0.047498)
			(type default)
		)
		(layer "F.Cu")
	)
	(gr_arc
		(start 36.82746 -263.778492)
		(mid 36.797702 -263.70665)
		(end 36.72586 -263.676892)
		(stroke
			(width 0.047498)
			(type default)
		)
		(layer "F.Cu")
	)
	(gr_line
		(start 36.82746 -263.778492)
		(end 36.82746 -264.028428)
		(stroke
			(width 0.047498)
			(type default)
		)
		(layer "F.Cu")
	)
	(gr_line
		(start 36.82746 -263.06272)
		(end 36.82746 -263.245092)
		(stroke
			(width 0.047498)
			(type default)
		)
		(layer "F.Cu")
	)
	(gr_arc
		(start 36.82746 -260.221222)
		(mid 36.836661 -260.267389)
		(end 36.862766 -260.306566)
		(stroke
			(width 0.047498)
			(type default)
		)
		(layer "F.Cu")
	)
	(gr_arc
		(start 36.82746 -259.968492)
		(mid 36.808399 -259.909248)
		(end 36.758372 -259.872226)
		(stroke
			(width 0.047498)
			(type default)
		)
		(layer "F.Cu")
	)
	(gr_line
		(start 36.82746 -259.968492)
		(end 36.82746 -260.221222)
		(stroke
			(width 0.047498)
			(type default)
		)
		(layer "F.Cu")
	)
	(gr_line
		(start 36.82746 -259.24891)
		(end 36.82746 -259.435092)
		(stroke
			(width 0.047498)
			(type default)
		)
		(layer "F.Cu")
	)
	(gr_arc
		(start 36.82746 -160.86582)
		(mid 36.830195 -160.892885)
		(end 36.838128 -160.918906)
		(stroke
			(width 0.047498)
			(type default)
		)
		(layer "F.Cu")
	)
	(gr_arc
		(start 36.82746 -160.778444)
		(mid 36.805143 -160.714819)
		(end 36.747958 -160.67913)
		(stroke
			(width 0.047498)
			(type default)
		)
		(layer "F.Cu")
	)
	(gr_line
		(start 36.82746 -160.778444)
		(end 36.82746 -160.86582)
		(stroke
			(width 0.047498)
			(type default)
		)
		(layer "F.Cu")
	)
	(gr_line
		(start 36.82746 -159.985964)
		(end 36.82746 -160.245044)
		(stroke
			(width 0.047498)
			(type default)
		)
		(layer "F.Cu")
	)
	(gr_arc
		(start 36.82746 -157.10408)
		(mid 36.853097 -157.203633)
		(end 36.923726 -157.278324)
		(stroke
			(width 0.047498)
			(type default)
		)
		(layer "F.Cu")
	)
	(gr_arc
		(start 36.82746 -156.968444)
		(mid 36.808562 -156.909346)
		(end 36.75888 -156.872178)
		(stroke
			(width 0.047498)
			(type default)
		)
		(layer "F.Cu")
	)
	(gr_line
		(start 36.82746 -156.968444)
		(end 36.82746 -157.10408)
		(stroke
			(width 0.047498)
			(type default)
		)
		(layer "F.Cu")
	)
	(gr_line
		(start 36.82746 -156.168344)
		(end 36.82746 -156.435044)
		(stroke
			(width 0.047498)
			(type default)
		)
		(layer "F.Cu")
	)
	(gr_arc
		(start 36.82746 -57.964324)
		(mid 36.881943 -58.095678)
		(end 37.013388 -58.149998)
		(stroke
			(width 0.047498)
			(type default)
		)
		(layer "F.Cu")
	)
	(gr_arc
		(start 36.82746 -57.778396)
		(mid 36.797702 -57.706554)
		(end 36.72586 -57.676796)
		(stroke
			(width 0.047498)
			(type default)
		)
		(layer "F.Cu")
	)
	(gr_line
		(start 36.82746 -57.778396)
		(end 36.82746 -57.964324)
		(stroke
			(width 0.047498)
			(type default)
		)
		(layer "F.Cu")
	)
	(gr_line
		(start 36.82746 -57.062624)
		(end 36.82746 -57.244996)
		(stroke
			(width 0.047498)
			(type default)
		)
		(layer "F.Cu")
	)
	(gr_arc
		(start 36.82746 -54.189376)
		(mid 36.838966 -54.247101)
		(end 36.871656 -54.296056)
		(stroke
			(width 0.047498)
			(type default)
		)
		(layer "F.Cu")
	)
	(gr_arc
		(start 36.82746 -53.968396)
		(mid 36.808399 -53.909152)
		(end 36.758372 -53.87213)
		(stroke
			(width 0.047498)
			(type default)
		)
		(layer "F.Cu")
	)
	(gr_line
		(start 36.82746 -53.968396)
		(end 36.82746 -54.189376)
		(stroke
			(width 0.047498)
			(type default)
		)
		(layer "F.Cu")
	)
	(gr_line
		(start 36.82746 -53.231542)
		(end 36.82746 -53.434996)
		(stroke
			(width 0.047498)
			(type default)
		)
		(layer "F.Cu")
	)
	(gr_line
		(start 36.829746 -469.96985)
		(end 36.834064 -469.983312)
		(stroke
			(width 0.047498)
			(type default)
		)
		(layer "F.Cu")
	)
	(gr_arc
		(start 36.829746 -366.91189)
		(mid 36.760931 -366.745755)
		(end 36.594796 -366.67694)
		(stroke
			(width 0.047498)
			(type default)
		)
		(layer "F.Cu")
	)
	(gr_arc
		(start 36.829746 -366.91189)
		(mid 36.839057 -366.958517)
		(end 36.86556 -366.997996)
		(stroke
			(width 0.047498)
			(type default)
		)
		(layer "F.Cu")
	)
	(gr_arc
		(start 36.834064 -469.983312)
		(mid 36.920336 -470.104065)
		(end 37.061394 -470.15019)
		(stroke
			(width 0.047498)
			(type default)
		)
		(layer "F.Cu")
	)
	(gr_line
		(start 36.838128 -160.918906)
		(end 36.866068 -160.986724)
		(stroke
			(width 0.047498)
			(type default)
		)
		(layer "F.Cu")
	)
	(gr_arc
		(start 36.8554 -159.9184)
		(mid 36.834687 -159.949399)
		(end 36.82746 -159.985964)
		(stroke
			(width 0.047498)
			(type default)
		)
		(layer "F.Cu")
	)
	(gr_line
		(start 36.85667 -264.097262)
		(end 36.883594 -264.123932)
		(stroke
			(width 0.047498)
			(type default)
		)
		(layer "F.Cu")
	)
	(gr_arc
		(start 36.862766 -260.306566)
		(mid 36.896203 -260.328942)
		(end 36.935664 -260.336792)
		(stroke
			(width 0.047498)
			(type default)
		)
		(layer "F.Cu")
	)
	(gr_line
		(start 36.86556 -366.997996)
		(end 36.900358 -367.033048)
		(stroke
			(width 0.047498)
			(type default)
		)
		(layer "F.Cu")
	)
	(gr_arc
		(start 36.866068 -160.986724)
		(mid 36.918865 -161.065858)
		(end 36.997894 -161.118804)
		(stroke
			(width 0.047498)
			(type default)
		)
		(layer "F.Cu")
	)
	(gr_arc
		(start 36.871656 -54.296056)
		(mid 36.92038 -54.328568)
		(end 36.977828 -54.339998)
		(stroke
			(width 0.047498)
			(type default)
		)
		(layer "F.Cu")
	)
	(gr_arc
		(start 36.874704 -53.117496)
		(mid 36.839742 -53.169821)
		(end 36.82746 -53.231542)
		(stroke
			(width 0.047498)
			(type default)
		)
		(layer "F.Cu")
	)
	(gr_arc
		(start 36.879784 -259.122672)
		(mid 36.841084 -259.18059)
		(end 36.82746 -259.24891)
		(stroke
			(width 0.047498)
			(type default)
		)
		(layer "F.Cu")
	)
	(gr_arc
		(start 36.881562 -468.934038)
		(mid 36.841538 -468.993938)
		(end 36.82746 -469.064594)
		(stroke
			(width 0.047498)
			(type default)
		)
		(layer "F.Cu")
	)
	(gr_arc
		(start 36.883594 -264.123932)
		(mid 36.91289 -264.143309)
		(end 36.947348 -264.150094)
		(stroke
			(width 0.047498)
			(type default)
		)
		(layer "F.Cu")
	)
	(gr_arc
		(start 36.900358 -367.033048)
		(mid 37.045289 -367.119876)
		(end 37.211508 -367.150142)
		(stroke
			(width 0.047498)
			(type default)
		)
		(layer "F.Cu")
	)
	(gr_line
		(start 36.923726 -157.278324)
		(end 36.949126 -157.294326)
		(stroke
			(width 0.047498)
			(type default)
		)
		(layer "F.Cu")
	)
	(gr_arc
		(start 36.92906 -156.066744)
		(mid 36.857218 -156.096502)
		(end 36.82746 -156.168344)
		(stroke
			(width 0.047498)
			(type default)
		)
		(layer "F.Cu")
	)
	(gr_line
		(start 36.92906 -156.066744)
		(end 36.966144 -156.064966)
		(stroke
			(width 0.047498)
			(type default)
		)
		(layer "F.Cu")
	)
	(gr_line
		(start 36.935664 -260.336792)
		(end 37.0332 -260.336792)
		(stroke
			(width 0.047498)
			(type default)
		)
		(layer "F.Cu")
	)
	(gr_arc
		(start 36.937696 -362.06684)
		(mid 36.771561 -362.135655)
		(end 36.702746 -362.30179)
		(stroke
			(width 0.047498)
			(type default)
		)
		(layer "F.Cu")
	)
	(gr_line
		(start 36.937696 -362.06684)
		(end 37.5666 -362.06684)
		(stroke
			(width 0.047498)
			(type default)
		)
		(layer "F.Cu")
	)
	(gr_line
		(start 36.947348 -264.150094)
		(end 38.250114 -264.150094)
		(stroke
			(width 0.047498)
			(type default)
		)
		(layer "F.Cu")
	)
	(gr_arc
		(start 36.94811 -159.880046)
		(mid 36.897954 -159.890023)
		(end 36.8554 -159.9184)
		(stroke
			(width 0.047498)
			(type default)
		)
		(layer "F.Cu")
	)
	(gr_line
		(start 36.94811 -159.880046)
		(end 38.250114 -159.880046)
		(stroke
			(width 0.047498)
			(type default)
		)
		(layer "F.Cu")
	)
	(gr_arc
		(start 36.949126 -157.294326)
		(mid 37.01687 -157.32462)
		(end 37.09035 -157.334966)
		(stroke
			(width 0.047498)
			(type default)
		)
		(layer "F.Cu")
	)
	(gr_arc
		(start 36.961826 -164.5539)
		(mid 36.731752 -164.6492)
		(end 36.636452 -164.879274)
		(stroke
			(width 0.047498)
			(type default)
		)
		(layer "F.Cu")
	)
	(gr_line
		(start 36.966144 -156.064966)
		(end 38.245034 -156.064966)
		(stroke
			(width 0.047498)
			(type default)
		)
		(layer "F.Cu")
	)
	(gr_line
		(start 36.977828 -54.339998)
		(end 38.250114 -54.339998)
		(stroke
			(width 0.047498)
			(type default)
		)
		(layer "F.Cu")
	)
	(gr_arc
		(start 36.989258 -53.069998)
		(mid 36.927258 -53.082349)
		(end 36.874704 -53.117496)
		(stroke
			(width 0.047498)
			(type default)
		)
		(layer "F.Cu")
	)
	(gr_line
		(start 36.989258 -53.069998)
		(end 38.250114 -53.069998)
		(stroke
			(width 0.047498)
			(type default)
		)
		(layer "F.Cu")
	)
	(gr_line
		(start 36.997894 -161.118804)
		(end 37.032946 -161.133282)
		(stroke
			(width 0.047498)
			(type default)
		)
		(layer "F.Cu")
	)
	(gr_arc
		(start 37.001704 -370.5479)
		(mid 36.620091 -370.623808)
		(end 36.2966 -370.84)
		(stroke
			(width 0.047498)
			(type default)
		)
		(layer "F.Cu")
	)
	(gr_arc
		(start 37.00653 -259.070094)
		(mid 36.93792 -259.083759)
		(end 36.879784 -259.122672)
		(stroke
			(width 0.047498)
			(type default)
		)
		(layer "F.Cu")
	)
	(gr_line
		(start 37.00653 -259.070094)
		(end 38.250114 -259.070094)
		(stroke
			(width 0.047498)
			(type default)
		)
		(layer "F.Cu")
	)
	(gr_arc
		(start 37.009832 -262.880094)
		(mid 36.880786 -262.933599)
		(end 36.82746 -263.06272)
		(stroke
			(width 0.047498)
			(type default)
		)
		(layer "F.Cu")
	)
	(gr_line
		(start 37.009832 -262.880094)
		(end 38.250114 -262.880094)
		(stroke
			(width 0.047498)
			(type default)
		)
		(layer "F.Cu")
	)
	(gr_arc
		(start 37.009832 -56.879998)
		(mid 36.880786 -56.933503)
		(end 36.82746 -57.062624)
		(stroke
			(width 0.047498)
			(type default)
		)
		(layer "F.Cu")
	)
	(gr_line
		(start 37.009832 -56.879998)
		(end 38.250114 -56.879998)
		(stroke
			(width 0.047498)
			(type default)
		)
		(layer "F.Cu")
	)
	(gr_arc
		(start 37.011864 -468.88019)
		(mid 36.941364 -468.894178)
		(end 36.881562 -468.934038)
		(stroke
			(width 0.047498)
			(type default)
		)
		(layer "F.Cu")
	)
	(gr_line
		(start 37.011864 -468.88019)
		(end 38.250114 -468.88019)
		(stroke
			(width 0.047498)
			(type default)
		)
		(layer "F.Cu")
	)
	(gr_line
		(start 37.013388 -58.149998)
		(end 38.250114 -58.149998)
		(stroke
			(width 0.047498)
			(type default)
		)
		(layer "F.Cu")
	)
	(gr_arc
		(start 37.032946 -161.133282)
		(mid 37.074409 -161.145838)
		(end 37.117528 -161.150046)
		(stroke
			(width 0.047498)
			(type default)
		)
		(layer "F.Cu")
	)
	(gr_line
		(start 37.0332 -260.336792)
		(end 37.036502 -260.340094)
		(stroke
			(width 0.047498)
			(type default)
		)
		(layer "F.Cu")
	)
	(gr_line
		(start 37.036502 -260.340094)
		(end 38.250114 -260.340094)
		(stroke
			(width 0.047498)
			(type default)
		)
		(layer "F.Cu")
	)
	(gr_line
		(start 37.061394 -470.15019)
		(end 38.250114 -470.15019)
		(stroke
			(width 0.047498)
			(type default)
		)
		(layer "F.Cu")
	)
	(gr_arc
		(start 37.064696 -365.87684)
		(mid 36.898561 -365.945655)
		(end 36.829746 -366.11179)
		(stroke
			(width 0.047498)
			(type default)
		)
		(layer "F.Cu")
	)
	(gr_line
		(start 37.064696 -365.87684)
		(end 38.246812 -365.87684)
		(stroke
			(width 0.047498)
			(type default)
		)
		(layer "F.Cu")
	)
	(gr_line
		(start 37.09035 -157.334966)
		(end 38.245034 -157.334966)
		(stroke
			(width 0.047498)
			(type default)
		)
		(layer "F.Cu")
	)
	(gr_arc
		(start 37.096192 -465.07019)
		(mid 36.924228 -465.104378)
		(end 36.778438 -465.201762)
		(stroke
			(width 0.047498)
			(type default)
		)
		(layer "F.Cu")
	)
	(gr_line
		(start 37.096192 -465.07019)
		(end 38.250114 -465.07019)
		(stroke
			(width 0.047498)
			(type default)
		)
		(layer "F.Cu")
	)
	(gr_line
		(start 37.117528 -161.150046)
		(end 38.250114 -161.150046)
		(stroke
			(width 0.047498)
			(type default)
		)
		(layer "F.Cu")
	)
	(gr_line
		(start 37.173916 -466.34019)
		(end 38.250114 -466.34019)
		(stroke
			(width 0.047498)
			(type default)
		)
		(layer "F.Cu")
	)
	(gr_line
		(start 37.211508 -367.150142)
		(end 38.250114 -367.150142)
		(stroke
			(width 0.047498)
			(type default)
		)
		(layer "F.Cu")
	)
	(gr_line
		(start 37.269928 -363.33684)
		(end 37.280088 -363.33684)
		(stroke
			(width 0.047498)
			(type default)
		)
		(layer "F.Cu")
	)
	(gr_line
		(start 37.280088 -363.33684)
		(end 37.28339 -363.340142)
		(stroke
			(width 0.047498)
			(type default)
		)
		(layer "F.Cu")
	)
	(gr_line
		(start 37.28339 -363.340142)
		(end 38.250114 -363.340142)
		(stroke
			(width 0.047498)
			(type default)
		)
		(layer "F.Cu")
	)
	(gr_line
		(start 37.4142 -190.82385)
		(end 37.4142 -191.01689)
		(stroke
			(width 0.047498)
			(type default)
		)
		(layer "F.Cu")
	)
	(gr_line
		(start 37.5666 -362.06684)
		(end 37.569902 -362.070142)
		(stroke
			(width 0.047498)
			(type default)
		)
		(layer "F.Cu")
	)
	(gr_line
		(start 37.569902 -362.070142)
		(end 38.250114 -362.070142)
		(stroke
			(width 0.047498)
			(type default)
		)
		(layer "F.Cu")
	)
	(gr_line
		(start 37.744146 -191.15405)
		(end 37.744146 -191.34709)
		(stroke
			(width 0.047498)
			(type default)
		)
		(layer "F.Cu")
	)
	(gr_line
		(start 38.099746 -61.850016)
		(end 38.322504 -61.627258)
		(stroke
			(width 0.047498)
			(type default)
		)
		(layer "F.Cu")
	)
	(gr_line
		(start 38.099746 -60.891166)
		(end 38.371018 -61.162184)
		(stroke
			(width 0.047498)
			(type default)
		)
		(layer "F.Cu")
	)
	(gr_line
		(start 38.245034 -157.334966)
		(end 38.250114 -157.340046)
		(stroke
			(width 0.047498)
			(type default)
		)
		(layer "F.Cu")
	)
	(gr_line
		(start 38.245034 -156.064966)
		(end 38.250114 -156.070046)
		(stroke
			(width 0.047498)
			(type default)
		)
		(layer "F.Cu")
	)
	(gr_line
		(start 38.246812 -365.87684)
		(end 38.250114 -365.880142)
		(stroke
			(width 0.047498)
			(type default)
		)
		(layer "F.Cu")
	)
	(gr_arc
		(start 38.371018 -61.162184)
		(mid 38.436867 -61.206154)
		(end 38.514528 -61.22162)
		(stroke
			(width 0.047498)
			(type default)
		)
		(layer "F.Cu")
	)
	(gr_arc
		(start 38.490144 -61.552074)
		(mid 38.3994 -61.574225)
		(end 38.322504 -61.627258)
		(stroke
			(width 0.047498)
			(type default)
		)
		(layer "F.Cu")
	)
	(gr_arc
		(start 38.504622 -61.55182)
		(mid 38.497381 -61.551843)
		(end 38.490144 -61.552074)
		(stroke
			(width 0.047498)
			(type default)
		)
		(layer "F.Cu")
	)
	(gr_arc
		(start 38.622224 -372.62181)
		(mid 38.827596 -372.580928)
		(end 39.0017 -372.464584)
		(stroke
			(width 0.047498)
			(type default)
		)
		(layer "F.Cu")
	)
	(gr_arc
		(start 38.862 -63.542926)
		(mid 38.951203 -63.525127)
		(end 39.026846 -63.4746)
		(stroke
			(width 0.047498)
			(type default)
		)
		(layer "F.Cu")
	)
	(gr_arc
		(start 38.866826 -370.2177)
		(mid 39.000853 -370.19101)
		(end 39.114476 -370.115084)
		(stroke
			(width 0.047498)
			(type default)
		)
		(layer "F.Cu")
	)
	(gr_arc
		(start 38.870636 -475.621604)
		(mid 39.049466 -475.585992)
		(end 39.20109 -475.484698)
		(stroke
			(width 0.047498)
			(type default)
		)
		(layer "F.Cu")
	)
	(gr_arc
		(start 38.912546 -164.2237)
		(mid 39.100202 -164.186307)
		(end 39.259256 -164.079936)
		(stroke
			(width 0.047498)
			(type default)
		)
		(layer "F.Cu")
	)
	(gr_arc
		(start 38.912546 -61.22162)
		(mid 39.05262 -61.193771)
		(end 39.171372 -61.114432)
		(stroke
			(width 0.047498)
			(type default)
		)
		(layer "F.Cu")
	)
	(gr_arc
		(start 38.93312 -473.221558)
		(mid 39.054212 -473.197432)
		(end 39.156894 -473.128848)
		(stroke
			(width 0.047498)
			(type default)
		)
		(layer "F.Cu")
	)
	(gr_arc
		(start 39.003478 -63.932308)
		(mid 38.904378 -63.888245)
		(end 38.796976 -63.873126)
		(stroke
			(width 0.047498)
			(type default)
		)
		(layer "F.Cu")
	)
	(gr_arc
		(start 39.010082 -269.605506)
		(mid 39.107691 -269.586126)
		(end 39.190422 -269.53083)
		(stroke
			(width 0.047498)
			(type default)
		)
		(layer "F.Cu")
	)
	(gr_arc
		(start 39.04234 -370.594128)
		(mid 38.96904 -370.559701)
		(end 38.888924 -370.5479)
		(stroke
			(width 0.047498)
			(type default)
		)
		(layer "F.Cu")
	)
	(gr_arc
		(start 39.064946 -373.0879)
		(mid 38.914381 -372.987296)
		(end 38.736778 -372.95201)
		(stroke
			(width 0.047498)
			(type default)
		)
		(layer "F.Cu")
	)
	(gr_arc
		(start 39.064946 -373.0879)
		(mid 39.174371 -373.161023)
		(end 39.303452 -373.186706)
		(stroke
			(width 0.047498)
			(type default)
		)
		(layer "F.Cu")
	)
	(gr_arc
		(start 39.07282 -63.987426)
		(mid 39.039719 -63.957892)
		(end 39.003478 -63.932308)
		(stroke
			(width 0.047498)
			(type default)
		)
		(layer "F.Cu")
	)
	(gr_line
		(start 39.07282 -63.987426)
		(end 39.14902 -64.063626)
		(stroke
			(width 0.047498)
			(type default)
		)
		(layer "F.Cu")
	)
	(gr_arc
		(start 39.085266 -370.62918)
		(mid 39.06468 -370.61058)
		(end 39.04234 -370.594128)
		(stroke
			(width 0.047498)
			(type default)
		)
		(layer "F.Cu")
	)
	(gr_line
		(start 39.085266 -370.62918)
		(end 39.148766 -370.69268)
		(stroke
			(width 0.047498)
			(type default)
		)
		(layer "F.Cu")
	)
	(gr_arc
		(start 39.088568 -270.016478)
		(mid 38.999068 -269.956676)
		(end 38.893496 -269.935706)
		(stroke
			(width 0.047498)
			(type default)
		)
		(layer "F.Cu")
	)
	(gr_line
		(start 39.088568 -270.016478)
		(end 39.177468 -270.105378)
		(stroke
			(width 0.047498)
			(type default)
		)
		(layer "F.Cu")
	)
	(gr_arc
		(start 39.115746 -166.6367)
		(mid 39.127101 -166.636074)
		(end 39.138352 -166.634414)
		(stroke
			(width 0.047498)
			(type default)
		)
		(layer "F.Cu")
	)
	(gr_arc
		(start 39.138098 -166.969186)
		(mid 39.126985 -166.967436)
		(end 39.115746 -166.9669)
		(stroke
			(width 0.047498)
			(type default)
		)
		(layer "F.Cu")
	)
	(gr_arc
		(start 39.138352 -166.634414)
		(mid 39.213228 -166.591032)
		(end 39.242746 -166.5097)
		(stroke
			(width 0.047498)
			(type default)
		)
		(layer "F.Cu")
	)
	(gr_arc
		(start 39.143686 -476.031306)
		(mid 39.055585 -475.972439)
		(end 38.951662 -475.951804)
		(stroke
			(width 0.047498)
			(type default)
		)
		(layer "F.Cu")
	)
	(gr_line
		(start 39.143686 -476.031306)
		(end 39.219886 -476.107506)
		(stroke
			(width 0.047498)
			(type default)
		)
		(layer "F.Cu")
	)
	(gr_arc
		(start 39.148766 -370.69268)
		(mid 39.252824 -370.762249)
		(end 39.375588 -370.78666)
		(stroke
			(width 0.047498)
			(type default)
		)
		(layer "F.Cu")
	)
	(gr_line
		(start 39.14902 -64.063626)
		(end 39.167054 -64.081406)
		(stroke
			(width 0.047498)
			(type default)
		)
		(layer "F.Cu")
	)
	(gr_arc
		(start 39.155878 -61.643514)
		(mid 39.054258 -61.575614)
		(end 38.93439 -61.55182)
		(stroke
			(width 0.047498)
			(type default)
		)
		(layer "F.Cu")
	)
	(gr_line
		(start 39.155878 -61.643514)
		(end 39.232078 -61.719714)
		(stroke
			(width 0.047498)
			(type default)
		)
		(layer "F.Cu")
	)
	(gr_arc
		(start 39.162736 -473.65031)
		(mid 39.053542 -473.577349)
		(end 38.924738 -473.551758)
		(stroke
			(width 0.047498)
			(type default)
		)
		(layer "F.Cu")
	)
	(gr_line
		(start 39.162736 -473.65031)
		(end 39.213536 -473.70111)
		(stroke
			(width 0.047498)
			(type default)
		)
		(layer "F.Cu")
	)
	(gr_arc
		(start 39.167054 -64.081406)
		(mid 39.283348 -64.159176)
		(end 39.420546 -64.186562)
		(stroke
			(width 0.047498)
			(type default)
		)
		(layer "F.Cu")
	)
	(gr_line
		(start 39.171372 -61.114432)
		(end 39.226998 -61.058806)
		(stroke
			(width 0.047498)
			(type default)
		)
		(layer "F.Cu")
	)
	(gr_arc
		(start 39.177468 -270.105378)
		(mid 39.267564 -270.165528)
		(end 39.37381 -270.186658)
		(stroke
			(width 0.047498)
			(type default)
		)
		(layer "F.Cu")
	)
	(gr_arc
		(start 39.189406 -372.38686)
		(mid 39.08783 -372.407065)
		(end 39.0017 -372.464584)
		(stroke
			(width 0.047498)
			(type default)
		)
		(layer "F.Cu")
	)
	(gr_line
		(start 39.189406 -372.38686)
		(end 39.192708 -372.390162)
		(stroke
			(width 0.047498)
			(type default)
		)
		(layer "F.Cu")
	)
	(gr_line
		(start 39.190422 -269.53083)
		(end 39.253922 -269.46733)
		(stroke
			(width 0.047498)
			(type default)
		)
		(layer "F.Cu")
	)
	(gr_line
		(start 39.192708 -372.390162)
		(end 40.39997 -372.390162)
		(stroke
			(width 0.047498)
			(type default)
		)
		(layer "F.Cu")
	)
	(gr_arc
		(start 39.213536 -473.70111)
		(mid 39.30841 -473.764443)
		(end 39.420292 -473.786708)
		(stroke
			(width 0.047498)
			(type default)
		)
		(layer "F.Cu")
	)
	(gr_arc
		(start 39.217346 -167.0685)
		(mid 39.195106 -167.004972)
		(end 39.138098 -166.969186)
		(stroke
			(width 0.047498)
			(type default)
		)
		(layer "F.Cu")
	)
	(gr_arc
		(start 39.217346 -167.0685)
		(mid 39.251937 -167.152032)
		(end 39.335456 -167.18661)
		(stroke
			(width 0.047498)
			(type default)
		)
		(layer "F.Cu")
	)
	(gr_arc
		(start 39.219886 -476.107506)
		(mid 39.307632 -476.166157)
		(end 39.411148 -476.186754)
		(stroke
			(width 0.047498)
			(type default)
		)
		(layer "F.Cu")
	)
	(gr_arc
		(start 39.226744 -370.033804)
		(mid 39.167366 -370.069965)
		(end 39.114476 -370.115084)
		(stroke
			(width 0.047498)
			(type default)
		)
		(layer "F.Cu")
	)
	(gr_arc
		(start 39.232078 -61.719714)
		(mid 39.306078 -61.769165)
		(end 39.393368 -61.786516)
		(stroke
			(width 0.047498)
			(type default)
		)
		(layer "F.Cu")
	)
	(gr_arc
		(start 39.238936 -63.386716)
		(mid 39.124141 -63.40955)
		(end 39.026846 -63.4746)
		(stroke
			(width 0.047498)
			(type default)
		)
		(layer "F.Cu")
	)
	(gr_line
		(start 39.238936 -63.386716)
		(end 39.242238 -63.390018)
		(stroke
			(width 0.047498)
			(type default)
		)
		(layer "F.Cu")
	)
	(gr_line
		(start 39.242238 -63.390018)
		(end 40.39997 -63.390018)
		(stroke
			(width 0.047498)
			(type default)
		)
		(layer "F.Cu")
	)
	(gr_arc
		(start 39.268146 -164.6555)
		(mid 39.155572 -164.58028)
		(end 39.022782 -164.5539)
		(stroke
			(width 0.047498)
			(type default)
		)
		(layer "F.Cu")
	)
	(gr_arc
		(start 39.268146 -164.6555)
		(mid 39.413358 -164.752499)
		(end 39.58463 -164.786564)
		(stroke
			(width 0.047498)
			(type default)
		)
		(layer "F.Cu")
	)
	(gr_line
		(start 39.303452 -373.186706)
		(end 39.306754 -373.190008)
		(stroke
			(width 0.047498)
			(type default)
		)
		(layer "F.Cu")
	)
	(gr_line
		(start 39.306754 -373.190008)
		(end 40.39997 -373.190008)
		(stroke
			(width 0.047498)
			(type default)
		)
		(layer "F.Cu")
	)
	(gr_line
		(start 39.335456 -167.18661)
		(end 39.338758 -167.189912)
		(stroke
			(width 0.047498)
			(type default)
		)
		(layer "F.Cu")
	)
	(gr_line
		(start 39.338758 -167.189912)
		(end 40.39997 -167.189912)
		(stroke
			(width 0.047498)
			(type default)
		)
		(layer "F.Cu")
	)
	(gr_arc
		(start 39.340282 -369.986814)
		(mid 39.278851 -369.999033)
		(end 39.226744 -370.033804)
		(stroke
			(width 0.047498)
			(type default)
		)
		(layer "F.Cu")
	)
	(gr_line
		(start 39.340282 -369.986814)
		(end 39.343584 -369.990116)
		(stroke
			(width 0.047498)
			(type default)
		)
		(layer "F.Cu")
	)
	(gr_line
		(start 39.343584 -369.990116)
		(end 40.39997 -369.990116)
		(stroke
			(width 0.047498)
			(type default)
		)
		(layer "F.Cu")
	)
	(gr_arc
		(start 39.365682 -166.386764)
		(mid 39.278753 -166.422771)
		(end 39.242746 -166.5097)
		(stroke
			(width 0.047498)
			(type default)
		)
		(layer "F.Cu")
	)
	(gr_line
		(start 39.365682 -166.386764)
		(end 39.368984 -166.390066)
		(stroke
			(width 0.047498)
			(type default)
		)
		(layer "F.Cu")
	)
	(gr_line
		(start 39.368984 -166.390066)
		(end 40.39997 -166.390066)
		(stroke
			(width 0.047498)
			(type default)
		)
		(layer "F.Cu")
	)
	(gr_line
		(start 39.37381 -270.186658)
		(end 39.377112 -270.18996)
		(stroke
			(width 0.047498)
			(type default)
		)
		(layer "F.Cu")
	)
	(gr_line
		(start 39.375588 -370.78666)
		(end 39.37889 -370.789962)
		(stroke
			(width 0.047498)
			(type default)
		)
		(layer "F.Cu")
	)
	(gr_line
		(start 39.377112 -270.18996)
		(end 40.39997 -270.18996)
		(stroke
			(width 0.047498)
			(type default)
		)
		(layer "F.Cu")
	)
	(gr_line
		(start 39.37889 -370.789962)
		(end 40.39997 -370.789962)
		(stroke
			(width 0.047498)
			(type default)
		)
		(layer "F.Cu")
	)
	(gr_line
		(start 39.393368 -61.786516)
		(end 39.39667 -61.789818)
		(stroke
			(width 0.047498)
			(type default)
		)
		(layer "F.Cu")
	)
	(gr_line
		(start 39.39667 -61.789818)
		(end 40.39997 -61.789818)
		(stroke
			(width 0.047498)
			(type default)
		)
		(layer "F.Cu")
	)
	(gr_arc
		(start 39.401242 -60.98667)
		(mid 39.306956 -61.005425)
		(end 39.226998 -61.058806)
		(stroke
			(width 0.047498)
			(type default)
		)
		(layer "F.Cu")
	)
	(gr_line
		(start 39.401242 -60.98667)
		(end 39.404544 -60.989972)
		(stroke
			(width 0.047498)
			(type default)
		)
		(layer "F.Cu")
	)
	(gr_line
		(start 39.404544 -60.989972)
		(end 40.39997 -60.989972)
		(stroke
			(width 0.047498)
			(type default)
		)
		(layer "F.Cu")
	)
	(gr_line
		(start 39.411148 -476.186754)
		(end 39.41445 -476.190056)
		(stroke
			(width 0.047498)
			(type default)
		)
		(layer "F.Cu")
	)
	(gr_line
		(start 39.41445 -476.190056)
		(end 40.39997 -476.190056)
		(stroke
			(width 0.047498)
			(type default)
		)
		(layer "F.Cu")
	)
	(gr_line
		(start 39.420292 -473.786708)
		(end 39.423594 -473.79001)
		(stroke
			(width 0.047498)
			(type default)
		)
		(layer "F.Cu")
	)
	(gr_line
		(start 39.420546 -64.186562)
		(end 39.423848 -64.189864)
		(stroke
			(width 0.047498)
			(type default)
		)
		(layer "F.Cu")
	)
	(gr_line
		(start 39.423594 -473.79001)
		(end 40.39997 -473.79001)
		(stroke
			(width 0.047498)
			(type default)
		)
		(layer "F.Cu")
	)
	(gr_line
		(start 39.423848 -64.189864)
		(end 40.39997 -64.189864)
		(stroke
			(width 0.047498)
			(type default)
		)
		(layer "F.Cu")
	)
	(gr_arc
		(start 39.437056 -475.386908)
		(mid 39.309333 -475.412314)
		(end 39.20109 -475.484698)
		(stroke
			(width 0.047498)
			(type default)
		)
		(layer "F.Cu")
	)
	(gr_line
		(start 39.437056 -475.386908)
		(end 39.440358 -475.39021)
		(stroke
			(width 0.047498)
			(type default)
		)
		(layer "F.Cu")
	)
	(gr_line
		(start 39.440358 -475.39021)
		(end 40.39997 -475.39021)
		(stroke
			(width 0.047498)
			(type default)
		)
		(layer "F.Cu")
	)
	(gr_arc
		(start 39.448232 -269.386812)
		(mid 39.34306 -269.407732)
		(end 39.253922 -269.46733)
		(stroke
			(width 0.047498)
			(type default)
		)
		(layer "F.Cu")
	)
	(gr_line
		(start 39.448232 -269.386812)
		(end 39.451534 -269.390114)
		(stroke
			(width 0.047498)
			(type default)
		)
		(layer "F.Cu")
	)
	(gr_line
		(start 39.451534 -269.390114)
		(end 40.39997 -269.390114)
		(stroke
			(width 0.047498)
			(type default)
		)
		(layer "F.Cu")
	)
	(gr_arc
		(start 39.4843 -163.986718)
		(mid 39.362506 -164.010944)
		(end 39.259256 -164.079936)
		(stroke
			(width 0.047498)
			(type default)
		)
		(layer "F.Cu")
	)
	(gr_line
		(start 39.4843 -163.986718)
		(end 39.487602 -163.99002)
		(stroke
			(width 0.047498)
			(type default)
		)
		(layer "F.Cu")
	)
	(gr_line
		(start 39.487602 -163.99002)
		(end 40.39997 -163.99002)
		(stroke
			(width 0.047498)
			(type default)
		)
		(layer "F.Cu")
	)
	(gr_arc
		(start 39.499794 -472.986862)
		(mid 39.314236 -473.023772)
		(end 39.156894 -473.128848)
		(stroke
			(width 0.047498)
			(type default)
		)
		(layer "F.Cu")
	)
	(gr_line
		(start 39.499794 -472.986862)
		(end 39.503096 -472.990164)
		(stroke
			(width 0.047498)
			(type default)
		)
		(layer "F.Cu")
	)
	(gr_line
		(start 39.503096 -472.990164)
		(end 40.39997 -472.990164)
		(stroke
			(width 0.047498)
			(type default)
		)
		(layer "F.Cu")
	)
	(gr_line
		(start 39.58463 -164.786564)
		(end 39.587932 -164.789866)
		(stroke
			(width 0.047498)
			(type default)
		)
		(layer "F.Cu")
	)
	(gr_line
		(start 39.587932 -164.789866)
		(end 40.39997 -164.789866)
		(stroke
			(width 0.047498)
			(type default)
		)
		(layer "F.Cu")
	)
	(gr_line
		(start 40.39997 -267.789914)
		(end 41.39565 -267.789914)
		(stroke
			(width 0.047498)
			(type default)
		)
		(layer "F.Cu")
	)
	(gr_line
		(start 40.39997 -266.990068)
		(end 41.302686 -266.990068)
		(stroke
			(width 0.047498)
			(type default)
		)
		(layer "F.Cu")
	)
	(gr_line
		(start 41.302686 -266.990068)
		(end 41.305988 -266.986766)
		(stroke
			(width 0.047498)
			(type default)
		)
		(layer "F.Cu")
	)
	(gr_line
		(start 41.39565 -267.789914)
		(end 41.398952 -267.786612)
		(stroke
			(width 0.047498)
			(type default)
		)
		(layer "F.Cu")
	)
	(gr_arc
		(start 41.398952 -267.786612)
		(mid 41.441721 -267.778105)
		(end 41.477946 -267.753846)
		(stroke
			(width 0.047498)
			(type default)
		)
		(layer "F.Cu")
	)
	(gr_arc
		(start 41.477946 -267.753846)
		(mid 41.525047 -267.725949)
		(end 41.566846 -267.6906)
		(stroke
			(width 0.047498)
			(type default)
		)
		(layer "F.Cu")
	)
	(gr_arc
		(start 41.521126 -267.07592)
		(mid 41.422434 -267.009916)
		(end 41.305988 -266.986766)
		(stroke
			(width 0.047498)
			(type default)
		)
		(layer "F.Cu")
	)
	(gr_line
		(start 41.521126 -267.07592)
		(end 41.635426 -267.19022)
		(stroke
			(width 0.047498)
			(type default)
		)
		(layer "F.Cu")
	)
	(gr_arc
		(start 41.635426 -267.19022)
		(mid 41.725508 -267.250411)
		(end 41.831768 -267.2715)
		(stroke
			(width 0.047498)
			(type default)
		)
		(layer "F.Cu")
	)
	(gr_arc
		(start 41.781476 -267.6017)
		(mid 41.665327 -267.624814)
		(end 41.566846 -267.6906)
		(stroke
			(width 0.047498)
			(type default)
		)
		(layer "F.Cu")
	)
	(gr_arc
		(start 53.845714 -328.813668)
		(mid 53.849203 -328.810558)
		(end 53.852572 -328.807318)
		(stroke
			(width 0.047498)
			(type default)
		)
		(layer "F.Cu")
	)
	(gr_arc
		(start 63.721996 -322.556632)
		(mid 63.722636 -322.555874)
		(end 63.723266 -322.555108)
		(stroke
			(width 0.047498)
			(type default)
		)
		(layer "F.Cu")
	)
	(gr_line
		(start 64.996314 -323.079618)
		(end 65.22974 -322.846192)
		(stroke
			(width 0.047498)
			(type default)
		)
		(layer "F.Cu")
	)
	(gr_arc
		(start 66.026538 -321.886326)
		(mid 65.998517 -321.897488)
		(end 65.971166 -321.910202)
		(stroke
			(width 0.047498)
			(type default)
		)
		(layer "F.Cu")
	)
	(gr_line
		(start 74.285602 -465.868258)
		(end 74.412094 -465.868258)
		(stroke
			(width 0.047498)
			(type default)
		)
		(layer "F.Cu")
	)
	(gr_line
		(start 74.28992 -465.539582)
		(end 74.742294 -465.539582)
		(stroke
			(width 0.047498)
			(type default)
		)
		(layer "F.Cu")
	)
	(gr_arc
		(start 83.10245 -407.970482)
		(mid 83.118988 -407.964976)
		(end 83.13547 -407.959306)
		(stroke
			(width 0.047498)
			(type default)
		)
		(layer "F.Cu")
	)
	(gr_line
		(start 105.325164 -270.921226)
		(end 105.312972 -270.936212)
		(stroke
			(width 0.047498)
			(type default)
		)
		(layer "F.Cu")
	)
	(gr_line
		(start 105.325164 -270.921226)
		(end 105.339388 -270.903446)
		(stroke
			(width 0.047498)
			(type default)
		)
		(layer "F.Cu")
	)
	(gr_line
		(start 105.57002 -271.143476)
		(end 105.582212 -271.12849)
		(stroke
			(width 0.047498)
			(type default)
		)
		(layer "F.Cu")
	)
	(gr_line
		(start 105.582212 -271.12849)
		(end 105.582466 -271.128236)
		(stroke
			(width 0.047498)
			(type default)
		)
		(layer "F.Cu")
	)
	(gr_line
		(start 195.730622 -67.605148)
		(end 195.738242 -67.591178)
		(stroke
			(width 0.047498)
			(type default)
		)
		(layer "F.Cu")
	)
	(gr_line
		(start 196.358764 -65.464182)
		(end 196.36105 -65.462912)
		(stroke
			(width 0.047498)
			(type default)
		)
		(layer "F.Cu")
	)
	(gr_line
		(start 196.518022 -66.73215)
		(end 196.54647 -66.71818)
		(stroke
			(width 0.047498)
			(type default)
		)
		(layer "F.Cu")
	)
	(gr_line
		(start 196.79539 -156.538676)
		(end 196.847968 -156.538676)
		(stroke
			(width 0.047498)
			(type default)
		)
		(layer "F.Cu")
	)
	(gr_line
		(start 196.885814 -156.866844)
		(end 197.178168 -156.866844)
		(stroke
			(width 0.047498)
			(type default)
		)
		(layer "F.Cu")
	)
	(gr_line
		(start 210.312 -466.809582)
		(end 210.6422 -466.809582)
		(stroke
			(width 0.047498)
			(type default)
		)
		(layer "F.Cu")
	)
	(gr_line
		(start 210.6422 -466.479382)
		(end 210.6422 -466.479636)
		(stroke
			(width 0.047498)
			(type default)
		)
		(layer "F.Cu")
	)
	(gr_line
		(start 212.812884 -263.591548)
		(end 212.813138 -263.591802)
		(stroke
			(width 0.047498)
			(type default)
		)
		(layer "F.Cu")
	)
	(gr_line
		(start 212.926168 -263.90219)
		(end 212.93709 -263.897618)
		(stroke
			(width 0.047498)
			(type default)
		)
		(layer "F.Cu")
	)
	(gr_line
		(start 213.944962 -263.726168)
		(end 214.291164 -263.726168)
		(stroke
			(width 0.047498)
			(type default)
		)
		(layer "F.Cu")
	)
	(gr_line
		(start 213.960964 -263.395968)
		(end 213.960964 -263.396222)
		(stroke
			(width 0.047498)
			(type default)
		)
		(layer "F.Cu")
	)
	(gr_line
		(start 214.041736 -58.210958)
		(end 214.04199 -58.210704)
		(stroke
			(width 0.047498)
			(type default)
		)
		(layer "F.Cu")
	)
	(gr_arc
		(start 214.813896 -57.659778)
		(mid 214.781992 -57.665215)
		(end 214.750396 -57.672224)
		(stroke
			(width 0.047498)
			(type default)
		)
		(layer "F.Cu")
	)
	(gr_line
		(start 214.829898 -57.992772)
		(end 214.834724 -57.991756)
		(stroke
			(width 0.047498)
			(type default)
		)
		(layer "F.Cu")
	)
	(gr_line
		(start 215.197182 -269.618968)
		(end 215.409018 -269.830804)
		(stroke
			(width 0.047498)
			(type default)
		)
		(layer "F.Cu")
	)
	(gr_line
		(start 215.334088 -166.46398)
		(end 215.65235 -166.782242)
		(stroke
			(width 0.047498)
			(type default)
		)
		(layer "F.Cu")
	)
	(gr_arc
		(start 215.361012 -63.51016)
		(mid 216.172463 -64.052321)
		(end 217.129614 -64.242696)
		(stroke
			(width 0.047498)
			(type default)
		)
		(layer "F.Cu")
	)
	(gr_arc
		(start 215.409018 -269.830804)
		(mid 215.680776 -270.012401)
		(end 216.001346 -270.076168)
		(stroke
			(width 0.047498)
			(type default)
		)
		(layer "F.Cu")
	)
	(gr_line
		(start 215.617552 -372.466108)
		(end 215.703658 -372.552468)
		(stroke
			(width 0.047498)
			(type default)
		)
		(layer "F.Cu")
	)
	(gr_arc
		(start 215.65235 -166.782242)
		(mid 215.84474 -166.910844)
		(end 216.071704 -166.955978)
		(stroke
			(width 0.047498)
			(type default)
		)
		(layer "F.Cu")
	)
	(gr_arc
		(start 215.703658 -372.552468)
		(mid 216.119933 -372.830542)
		(end 216.610946 -372.928134)
		(stroke
			(width 0.047498)
			(type default)
		)
		(layer "F.Cu")
	)
	(gr_line
		(start 215.925146 -475.248224)
		(end 216.28989 -475.613222)
		(stroke
			(width 0.047498)
			(type default)
		)
		(layer "F.Cu")
	)
	(gr_line
		(start 216.071704 -166.955978)
		(end 216.2175 -166.955978)
		(stroke
			(width 0.047498)
			(type default)
		)
		(layer "F.Cu")
	)
	(gr_arc
		(start 216.111582 -269.606014)
		(mid 216.152581 -269.704955)
		(end 216.251536 -269.745968)
		(stroke
			(width 0.047498)
			(type default)
		)
		(layer "F.Cu")
	)
	(gr_arc
		(start 216.153746 -263.395968)
		(mid 216.265868 -263.393465)
		(end 216.377774 -263.386062)
		(stroke
			(width 0.047498)
			(type default)
		)
		(layer "F.Cu")
	)
	(gr_arc
		(start 216.175082 -57.410096)
		(mid 216.153786 -57.411028)
		(end 216.132664 -57.413906)
		(stroke
			(width 0.047498)
			(type default)
		)
		(layer "F.Cu")
	)
	(gr_arc
		(start 216.197688 -166.479728)
		(mid 216.359436 -166.587821)
		(end 216.55024 -166.625778)
		(stroke
			(width 0.047498)
			(type default)
		)
		(layer "F.Cu")
	)
	(gr_line
		(start 216.224612 -63.493396)
		(end 217.0176 -63.493396)
		(stroke
			(width 0.047498)
			(type default)
		)
		(layer "F.Cu")
	)
	(gr_arc
		(start 216.28989 -475.613222)
		(mid 216.577042 -475.805034)
		(end 216.915746 -475.872302)
		(stroke
			(width 0.047498)
			(type default)
		)
		(layer "F.Cu")
	)
	(gr_arc
		(start 216.377774 -263.386062)
		(mid 216.860891 -263.296543)
		(end 217.318082 -263.116568)
		(stroke
			(width 0.047498)
			(type default)
		)
		(layer "F.Cu")
	)
	(gr_line
		(start 216.438226 -57.407556)
		(end 216.450418 -57.40654)
		(stroke
			(width 0.047498)
			(type default)
		)
		(layer "F.Cu")
	)
	(gr_arc
		(start 216.450418 -57.40654)
		(mid 216.4921 -57.398911)
		(end 216.531444 -57.383172)
		(stroke
			(width 0.047498)
			(type default)
		)
		(layer "F.Cu")
	)
	(gr_arc
		(start 216.481152 -372.451884)
		(mid 216.642895 -372.559998)
		(end 216.833704 -372.597934)
		(stroke
			(width 0.047498)
			(type default)
		)
		(layer "F.Cu")
	)
	(gr_line
		(start 216.531444 -57.383172)
		(end 216.631012 -57.330848)
		(stroke
			(width 0.047498)
			(type default)
		)
		(layer "F.Cu")
	)
	(gr_arc
		(start 216.661746 -160.396428)
		(mid 217.061239 -160.324299)
		(end 217.410284 -160.117028)
		(stroke
			(width 0.047498)
			(type default)
		)
		(layer "F.Cu")
	)
	(gr_arc
		(start 216.737946 -269.745968)
		(mid 217.015772 -269.69075)
		(end 217.25128 -269.53337)
		(stroke
			(width 0.047498)
			(type default)
		)
		(layer "F.Cu")
	)
	(gr_arc
		(start 216.788746 -475.243144)
		(mid 216.876325 -475.454509)
		(end 217.087704 -475.542102)
		(stroke
			(width 0.047498)
			(type default)
		)
		(layer "F.Cu")
	)
	(gr_arc
		(start 216.842086 -57.889902)
		(mid 216.676371 -57.779178)
		(end 216.480898 -57.740296)
		(stroke
			(width 0.047498)
			(type default)
		)
		(layer "F.Cu")
	)
	(gr_arc
		(start 216.842086 -57.889902)
		(mid 216.985892 -57.98599)
		(end 217.155522 -58.019696)
		(stroke
			(width 0.047498)
			(type default)
		)
		(layer "F.Cu")
	)
	(gr_arc
		(start 216.920572 -57.225438)
		(mid 216.77225 -57.268411)
		(end 216.631012 -57.330848)
		(stroke
			(width 0.047498)
			(type default)
		)
		(layer "F.Cu")
	)
	(gr_line
		(start 216.920572 -57.225438)
		(end 217.354912 -57.130696)
		(stroke
			(width 0.047498)
			(type default)
		)
		(layer "F.Cu")
	)
	(gr_arc
		(start 216.952576 -366.241584)
		(mid 217.350402 -366.169438)
		(end 217.697558 -365.962184)
		(stroke
			(width 0.047498)
			(type default)
		)
		(layer "F.Cu")
	)
	(gr_arc
		(start 216.966546 -166.625778)
		(mid 217.112521 -166.5967)
		(end 217.236294 -166.514018)
		(stroke
			(width 0.047498)
			(type default)
		)
		(layer "F.Cu")
	)
	(gr_arc
		(start 217.0176 -63.493396)
		(mid 217.200159 -63.457111)
		(end 217.354912 -63.353696)
		(stroke
			(width 0.047498)
			(type default)
		)
		(layer "F.Cu")
	)
	(gr_arc
		(start 217.042746 -469.598502)
		(mid 217.597821 -469.488184)
		(end 218.068398 -469.173814)
		(stroke
			(width 0.047498)
			(type default)
		)
		(layer "F.Cu")
	)
	(gr_arc
		(start 217.068146 -372.597934)
		(mid 217.385563 -372.534726)
		(end 217.654632 -372.354856)
		(stroke
			(width 0.047498)
			(type default)
		)
		(layer "F.Cu")
	)
	(gr_line
		(start 217.129614 -64.242696)
		(end 217.354912 -64.242696)
		(stroke
			(width 0.047498)
			(type default)
		)
		(layer "F.Cu")
	)
	(gr_line
		(start 217.155522 -58.019696)
		(end 217.354912 -58.019696)
		(stroke
			(width 0.047498)
			(type default)
		)
		(layer "F.Cu")
	)
	(gr_arc
		(start 217.197432 -270.234918)
		(mid 217.021579 -270.117417)
		(end 216.814146 -270.076168)
		(stroke
			(width 0.047498)
			(type default)
		)
		(layer "F.Cu")
	)
	(gr_line
		(start 217.197432 -270.234918)
		(end 217.318082 -270.355568)
		(stroke
			(width 0.047498)
			(type default)
		)
		(layer "F.Cu")
	)
	(gr_line
		(start 217.236294 -166.514018)
		(end 217.410284 -166.340028)
		(stroke
			(width 0.047498)
			(type default)
		)
		(layer "F.Cu")
	)
	(gr_line
		(start 217.25128 -269.53337)
		(end 217.318082 -269.466568)
		(stroke
			(width 0.047498)
			(type default)
		)
		(layer "F.Cu")
	)
	(gr_arc
		(start 217.275918 -167.094662)
		(mid 217.122323 -166.992033)
		(end 216.941146 -166.955978)
		(stroke
			(width 0.047498)
			(type default)
		)
		(layer "F.Cu")
	)
	(gr_line
		(start 217.275918 -167.094662)
		(end 217.410284 -167.229028)
		(stroke
			(width 0.047498)
			(type default)
		)
		(layer "F.Cu")
	)
	(gr_arc
		(start 217.318082 -264.005568)
		(mid 216.883868 -263.797601)
		(end 216.407746 -263.726168)
		(stroke
			(width 0.047498)
			(type default)
		)
		(layer "F.Cu")
	)
	(gr_arc
		(start 217.362024 -475.542102)
		(mid 217.449998 -475.524619)
		(end 217.524584 -475.474792)
		(stroke
			(width 0.047498)
			(type default)
		)
		(layer "F.Cu")
	)
	(gr_line
		(start 217.375486 -469.928702)
		(end 218.202256 -469.928702)
		(stroke
			(width 0.047498)
			(type default)
		)
		(layer "F.Cu")
	)
	(gr_arc
		(start 217.410284 -161.006028)
		(mid 217.061233 -160.798771)
		(end 216.661746 -160.726628)
		(stroke
			(width 0.047498)
			(type default)
		)
		(layer "F.Cu")
	)
	(gr_line
		(start 217.524584 -475.474792)
		(end 217.598752 -475.400624)
		(stroke
			(width 0.047498)
			(type default)
		)
		(layer "F.Cu")
	)
	(gr_arc
		(start 217.570812 -475.98584)
		(mid 217.445069 -475.901822)
		(end 217.296746 -475.872302)
		(stroke
			(width 0.047498)
			(type default)
		)
		(layer "F.Cu")
	)
	(gr_line
		(start 217.570812 -475.98584)
		(end 217.644726 -476.059754)
		(stroke
			(width 0.047498)
			(type default)
		)
		(layer "F.Cu")
	)
	(gr_arc
		(start 217.644726 -476.059754)
		(mid 217.746583 -476.12779)
		(end 217.866722 -476.151702)
		(stroke
			(width 0.047498)
			(type default)
		)
		(layer "F.Cu")
	)
	(gr_line
		(start 217.654632 -372.354856)
		(end 217.697558 -372.312184)
		(stroke
			(width 0.047498)
			(type default)
		)
		(layer "F.Cu")
	)
	(gr_arc
		(start 217.676476 -373.180102)
		(mid 217.397372 -372.993611)
		(end 217.068146 -372.928134)
		(stroke
			(width 0.047498)
			(type default)
		)
		(layer "F.Cu")
	)
	(gr_line
		(start 217.676476 -373.180102)
		(end 217.697558 -373.201184)
		(stroke
			(width 0.047498)
			(type default)
		)
		(layer "F.Cu")
	)
	(gr_arc
		(start 217.697558 -366.851184)
		(mid 217.350405 -366.643921)
		(end 216.952576 -366.571784)
		(stroke
			(width 0.047498)
			(type default)
		)
		(layer "F.Cu")
	)
	(gr_line
		(start 217.828876 -259.656072)
		(end 217.842084 -259.650738)
		(stroke
			(width 0.047498)
			(type default)
		)
		(layer "F.Cu")
	)
	(gr_line
		(start 217.866722 -476.151702)
		(end 218.202256 -476.151702)
		(stroke
			(width 0.047498)
			(type default)
		)
		(layer "F.Cu")
	)
	(gr_arc
		(start 217.931746 -475.262702)
		(mid 217.751534 -475.298548)
		(end 217.598752 -475.400624)
		(stroke
			(width 0.047498)
			(type default)
		)
		(layer "F.Cu")
	)
	(gr_line
		(start 217.931746 -475.262702)
		(end 218.202256 -475.262702)
		(stroke
			(width 0.047498)
			(type default)
		)
		(layer "F.Cu")
	)
	(gr_line
		(start 217.967052 -259.956046)
		(end 217.967306 -259.9563)
		(stroke
			(width 0.047498)
			(type default)
		)
		(layer "F.Cu")
	)
	(gr_line
		(start 218.068398 -469.173814)
		(end 218.202256 -469.039702)
		(stroke
			(width 0.047498)
			(type default)
		)
		(layer "F.Cu")
	)
	(gr_arc
		(start 218.207082 -269.466568)
		(mid 218.37897 -269.581429)
		(end 218.581732 -269.621762)
		(stroke
			(width 0.047498)
			(type default)
		)
		(layer "F.Cu")
	)
	(gr_line
		(start 218.207082 -264.005568)
		(end 218.52382 -264.005568)
		(stroke
			(width 0.047498)
			(type default)
		)
		(layer "F.Cu")
	)
	(gr_line
		(start 218.207082 -263.116568)
		(end 218.468956 -263.116568)
		(stroke
			(width 0.047498)
			(type default)
		)
		(layer "F.Cu")
	)
	(gr_line
		(start 218.243912 -64.242696)
		(end 218.267026 -64.219582)
		(stroke
			(width 0.047498)
			(type default)
		)
		(layer "F.Cu")
	)
	(gr_arc
		(start 218.243912 -63.353696)
		(mid 218.525003 -63.541493)
		(end 218.85656 -63.607442)
		(stroke
			(width 0.047498)
			(type default)
		)
		(layer "F.Cu")
	)
	(gr_line
		(start 218.243912 -58.019696)
		(end 218.623388 -58.019696)
		(stroke
			(width 0.047498)
			(type default)
		)
		(layer "F.Cu")
	)
	(gr_line
		(start 218.243912 -57.130696)
		(end 218.477084 -57.130696)
		(stroke
			(width 0.047498)
			(type default)
		)
		(layer "F.Cu")
	)
	(gr_line
		(start 218.299284 -167.229028)
		(end 218.306142 -167.22217)
		(stroke
			(width 0.047498)
			(type default)
		)
		(layer "F.Cu")
	)
	(gr_line
		(start 218.299284 -166.340028)
		(end 218.365324 -166.405814)
		(stroke
			(width 0.047498)
			(type default)
		)
		(layer "F.Cu")
	)
	(gr_arc
		(start 218.299284 -160.117028)
		(mid 218.535855 -160.286714)
		(end 218.820746 -160.346644)
		(stroke
			(width 0.047498)
			(type default)
		)
		(layer "F.Cu")
	)
	(gr_arc
		(start 218.365324 -166.405814)
		(mid 218.620878 -166.57664)
		(end 218.922346 -166.6367)
		(stroke
			(width 0.047498)
			(type default)
		)
		(layer "F.Cu")
	)
	(gr_arc
		(start 218.52382 -264.005568)
		(mid 218.706373 -263.969275)
		(end 218.861132 -263.865868)
		(stroke
			(width 0.047498)
			(type default)
		)
		(layer "F.Cu")
	)
	(gr_line
		(start 218.581732 -269.621762)
		(end 218.848686 -269.621762)
		(stroke
			(width 0.047498)
			(type default)
		)
		(layer "F.Cu")
	)
	(gr_line
		(start 218.586558 -373.201184)
		(end 218.595448 -373.192548)
		(stroke
			(width 0.047498)
			(type default)
		)
		(layer "F.Cu")
	)
	(gr_line
		(start 218.586558 -372.312184)
		(end 218.607894 -372.33352)
		(stroke
			(width 0.047498)
			(type default)
		)
		(layer "F.Cu")
	)
	(gr_line
		(start 218.586558 -365.962184)
		(end 218.628468 -366.004094)
		(stroke
			(width 0.047498)
			(type default)
		)
		(layer "F.Cu")
	)
	(gr_arc
		(start 218.607894 -372.33352)
		(mid 218.926976 -372.546702)
		(end 219.303346 -372.621556)
		(stroke
			(width 0.047498)
			(type default)
		)
		(layer "F.Cu")
	)
	(gr_arc
		(start 218.623388 -58.019696)
		(mid 218.80595 -57.983415)
		(end 218.9607 -57.879996)
		(stroke
			(width 0.047498)
			(type default)
		)
		(layer "F.Cu")
	)
	(gr_arc
		(start 218.628468 -366.004094)
		(mid 219.00803 -366.2577)
		(end 219.455746 -366.34674)
		(stroke
			(width 0.047498)
			(type default)
		)
		(layer "F.Cu")
	)
	(gr_arc
		(start 218.806268 -263.256268)
		(mid 218.651508 -263.152861)
		(end 218.468956 -263.116568)
		(stroke
			(width 0.047498)
			(type default)
		)
		(layer "F.Cu")
	)
	(gr_arc
		(start 218.806268 -263.256268)
		(mid 218.961036 -263.359649)
		(end 219.14358 -263.395968)
		(stroke
			(width 0.047498)
			(type default)
		)
		(layer "F.Cu")
	)
	(gr_arc
		(start 218.814396 -57.270396)
		(mid 218.65963 -57.167013)
		(end 218.477084 -57.130696)
		(stroke
			(width 0.047498)
			(type default)
		)
		(layer "F.Cu")
	)
	(gr_arc
		(start 218.814396 -57.270396)
		(mid 218.969156 -57.373803)
		(end 219.151708 -57.410096)
		(stroke
			(width 0.047498)
			(type default)
		)
		(layer "F.Cu")
	)
	(gr_arc
		(start 218.820746 -160.676844)
		(mid 218.512413 -160.766026)
		(end 218.299284 -161.006028)
		(stroke
			(width 0.047498)
			(type default)
		)
		(layer "F.Cu")
	)
	(gr_arc
		(start 218.9099 -63.93815)
		(mid 218.561898 -64.018195)
		(end 218.267026 -64.219582)
		(stroke
			(width 0.047498)
			(type default)
		)
		(layer "F.Cu")
	)
	(gr_arc
		(start 218.922346 -166.9669)
		(mid 218.588847 -167.033237)
		(end 218.306142 -167.22217)
		(stroke
			(width 0.047498)
			(type default)
		)
		(layer "F.Cu")
	)
	(gr_arc
		(start 218.947746 -63.937642)
		(mid 218.92882 -63.937708)
		(end 218.9099 -63.93815)
		(stroke
			(width 0.047498)
			(type default)
		)
		(layer "F.Cu")
	)
	(gr_arc
		(start 219.091256 -475.262702)
		(mid 219.488753 -475.528331)
		(end 219.95765 -475.621604)
		(stroke
			(width 0.047498)
			(type default)
		)
		(layer "F.Cu")
	)
	(gr_arc
		(start 219.091256 -469.039702)
		(mid 219.431434 -469.266964)
		(end 219.832682 -469.346788)
		(stroke
			(width 0.047498)
			(type default)
		)
		(layer "F.Cu")
	)
	(gr_arc
		(start 219.176346 -372.951756)
		(mid 218.861953 -373.014386)
		(end 218.595448 -373.192548)
		(stroke
			(width 0.047498)
			(type default)
		)
		(layer "F.Cu")
	)
	(gr_arc
		(start 219.181426 -269.951962)
		(mid 218.654107 -270.056852)
		(end 218.207082 -270.355568)
		(stroke
			(width 0.047498)
			(type default)
		)
		(layer "F.Cu")
	)
	(gr_arc
		(start 219.198444 -263.726168)
		(mid 219.015899 -263.762478)
		(end 218.861132 -263.865868)
		(stroke
			(width 0.047498)
			(type default)
		)
		(layer "F.Cu")
	)
	(gr_arc
		(start 219.201746 -366.67694)
		(mid 218.88205 -366.721338)
		(end 218.586558 -366.851184)
		(stroke
			(width 0.047498)
			(type default)
		)
		(layer "F.Cu")
	)
	(gr_arc
		(start 219.291154 -475.951804)
		(mid 219.149805 -476.010353)
		(end 219.091256 -476.151702)
		(stroke
			(width 0.047498)
			(type default)
		)
		(layer "F.Cu")
	)
	(gr_line
		(start 219.291154 -475.951804)
		(end 219.62491 -475.951804)
		(stroke
			(width 0.047498)
			(type default)
		)
		(layer "F.Cu")
	)
	(gr_arc
		(start 219.298012 -57.740296)
		(mid 219.115467 -57.776606)
		(end 218.9607 -57.879996)
		(stroke
			(width 0.047498)
			(type default)
		)
		(layer "F.Cu")
	)
	(gr_arc
		(start 219.698824 -469.676988)
		(mid 219.369991 -469.742397)
		(end 219.091256 -469.928702)
		(stroke
			(width 0.047498)
			(type default)
		)
		(layer "F.Cu")
	)
	(gr_arc
		(start 220.196156 -472.90736)
		(mid 220.288166 -473.129574)
		(end 220.510354 -473.221558)
		(stroke
			(width 0.047498)
			(type default)
		)
		(layer "F.Cu")
	)
	(gr_arc
		(start 220.751146 -473.551758)
		(mid 220.432211 -473.635838)
		(end 220.196156 -473.86621)
		(stroke
			(width 0.047498)
			(type default)
		)
		(layer "F.Cu")
	)
	(gr_line
		(start 221.153228 -53.624226)
		(end 221.154244 -53.623718)
		(stroke
			(width 0.047498)
			(type default)
		)
		(layer "F.Cu")
	)
	(gr_line
		(start 221.24035 -53.587142)
		(end 221.40672 -53.51653)
		(stroke
			(width 0.047498)
			(type default)
		)
		(layer "F.Cu")
	)
	(gr_arc
		(start 221.27972 -263.395968)
		(mid 221.474106 -263.357279)
		(end 221.638876 -263.247124)
		(stroke
			(width 0.047498)
			(type default)
		)
		(layer "F.Cu")
	)
	(gr_line
		(start 221.282514 -53.928518)
		(end 221.28353 -53.92801)
		(stroke
			(width 0.047498)
			(type default)
		)
		(layer "F.Cu")
	)
	(gr_arc
		(start 221.288864 -465.539582)
		(mid 221.302234 -465.539022)
		(end 221.315534 -465.53755)
		(stroke
			(width 0.047498)
			(type default)
		)
		(layer "F.Cu")
	)
	(gr_arc
		(start 221.315534 -465.53755)
		(mid 221.361999 -465.525441)
		(end 221.40418 -465.502498)
		(stroke
			(width 0.047498)
			(type default)
		)
		(layer "F.Cu")
	)
	(gr_arc
		(start 221.40418 -465.502498)
		(mid 221.465612 -465.431749)
		(end 221.487746 -465.3407)
		(stroke
			(width 0.047498)
			(type default)
		)
		(layer "F.Cu")
	)
	(gr_arc
		(start 221.40672 -53.51653)
		(mid 221.481593 -53.482428)
		(end 221.554548 -53.444394)
		(stroke
			(width 0.047498)
			(type default)
		)
		(layer "F.Cu")
	)
	(gr_arc
		(start 221.420182 -53.888386)
		(mid 221.375972 -53.893253)
		(end 221.333568 -53.906674)
		(stroke
			(width 0.047498)
			(type default)
		)
		(layer "F.Cu")
	)
	(gr_arc
		(start 221.4372 -259.536692)
		(mid 221.505861 -259.528121)
		(end 221.570296 -259.50291)
		(stroke
			(width 0.047498)
			(type default)
		)
		(layer "F.Cu")
	)
	(gr_arc
		(start 221.474792 -160.346644)
		(mid 221.56071 -160.329534)
		(end 221.633542 -160.280858)
		(stroke
			(width 0.047498)
			(type default)
		)
		(layer "F.Cu")
	)
	(gr_arc
		(start 221.487746 -466.158072)
		(mid 221.541075 -466.28688)
		(end 221.669864 -466.34019)
		(stroke
			(width 0.047498)
			(type default)
		)
		(layer "F.Cu")
	)
	(gr_arc
		(start 221.487746 -465.9757)
		(mid 221.456723 -465.900805)
		(end 221.381828 -465.869782)
		(stroke
			(width 0.047498)
			(type default)
		)
		(layer "F.Cu")
	)
	(gr_line
		(start 221.487746 -465.9757)
		(end 221.487746 -466.158072)
		(stroke
			(width 0.047498)
			(type default)
		)
		(layer "F.Cu")
	)
	(gr_arc
		(start 221.488254 -57.740042)
		(mid 221.487619 -57.740169)
		(end 221.486984 -57.740296)
		(stroke
			(width 0.047498)
			(type default)
		)
		(layer "F.Cu")
	)
	(gr_arc
		(start 221.493842 -53.90007)
		(mid 221.457497 -53.89117)
		(end 221.420182 -53.888386)
		(stroke
			(width 0.047498)
			(type default)
		)
		(layer "F.Cu")
	)
	(gr_arc
		(start 221.495874 -57.410096)
		(mid 221.61203 -57.386991)
		(end 221.710504 -57.321196)
		(stroke
			(width 0.047498)
			(type default)
		)
		(layer "F.Cu")
	)
	(gr_arc
		(start 221.49816 -53.901594)
		(mid 221.496005 -53.900821)
		(end 221.493842 -53.90007)
		(stroke
			(width 0.047498)
			(type default)
		)
		(layer "F.Cu")
	)
	(gr_arc
		(start 221.498414 -160.708848)
		(mid 221.441229 -160.684985)
		(end 221.379796 -160.676844)
		(stroke
			(width 0.047498)
			(type default)
		)
		(layer "F.Cu")
	)
	(gr_arc
		(start 221.507304 -160.714436)
		(mid 221.502891 -160.711591)
		(end 221.498414 -160.708848)
		(stroke
			(width 0.047498)
			(type default)
		)
		(layer "F.Cu")
	)
	(gr_arc
		(start 221.509336 -156.866844)
		(mid 221.508066 -156.866841)
		(end 221.506796 -156.866844)
		(stroke
			(width 0.047498)
			(type default)
		)
		(layer "F.Cu")
	)
	(gr_arc
		(start 221.52737 -53.914294)
		(mid 221.51299 -53.907427)
		(end 221.49816 -53.901594)
		(stroke
			(width 0.047498)
			(type default)
		)
		(layer "F.Cu")
	)
	(gr_arc
		(start 221.534736 -53.918358)
		(mid 221.531072 -53.916291)
		(end 221.52737 -53.914294)
		(stroke
			(width 0.047498)
			(type default)
		)
		(layer "F.Cu")
	)
	(gr_arc
		(start 221.54896 -57.743852)
		(mid 221.518664 -57.741031)
		(end 221.488254 -57.740042)
		(stroke
			(width 0.047498)
			(type default)
		)
		(layer "F.Cu")
	)
	(gr_arc
		(start 221.554548 -53.444394)
		(mid 221.585988 -53.39732)
		(end 221.596966 -53.341778)
		(stroke
			(width 0.047498)
			(type default)
		)
		(layer "F.Cu")
	)
	(gr_arc
		(start 221.555056 -156.536644)
		(mid 221.636976 -156.520307)
		(end 221.70644 -156.473906)
		(stroke
			(width 0.047498)
			(type default)
		)
		(layer "F.Cu")
	)
	(gr_arc
		(start 221.558612 -469.346788)
		(mid 221.670319 -469.30051)
		(end 221.7166 -469.1888)
		(stroke
			(width 0.047498)
			(type default)
		)
		(layer "F.Cu")
	)
	(gr_arc
		(start 221.570296 -259.50291)
		(mid 221.677259 -259.40024)
		(end 221.7166 -259.257292)
		(stroke
			(width 0.047498)
			(type default)
		)
		(layer "F.Cu")
	)
	(gr_arc
		(start 221.572836 -259.87629)
		(mid 221.540151 -259.869235)
		(end 221.506796 -259.866892)
		(stroke
			(width 0.047498)
			(type default)
		)
		(layer "F.Cu")
	)
	(gr_arc
		(start 221.582234 -53.954934)
		(mid 221.559707 -53.935057)
		(end 221.534736 -53.918358)
		(stroke
			(width 0.047498)
			(type default)
		)
		(layer "F.Cu")
	)
	(gr_line
		(start 221.582234 -53.954934)
		(end 221.614746 -53.9877)
		(stroke
			(width 0.047498)
			(type default)
		)
		(layer "F.Cu")
	)
	(gr_arc
		(start 221.589346 -366.34674)
		(mid 221.619817 -366.343517)
		(end 221.649036 -366.334294)
		(stroke
			(width 0.047498)
			(type default)
		)
		(layer "F.Cu")
	)
	(gr_arc
		(start 221.589346 -362.53674)
		(mid 221.697093 -362.492089)
		(end 221.741746 -362.38434)
		(stroke
			(width 0.047498)
			(type default)
		)
		(layer "F.Cu")
	)
	(gr_arc
		(start 221.590108 -259.882132)
		(mid 221.581528 -259.879044)
		(end 221.572836 -259.87629)
		(stroke
			(width 0.047498)
			(type default)
		)
		(layer "F.Cu")
	)
	(gr_arc
		(start 221.593918 -263.875012)
		(mid 221.42915 -263.764854)
		(end 221.234762 -263.726168)
		(stroke
			(width 0.047498)
			(type default)
		)
		(layer "F.Cu")
	)
	(gr_line
		(start 221.593918 -263.875012)
		(end 221.729046 -264.01014)
		(stroke
			(width 0.047498)
			(type default)
		)
		(layer "F.Cu")
	)
	(gr_arc
		(start 221.614746 -160.96107)
		(mid 221.623759 -161.006581)
		(end 221.649544 -161.045144)
		(stroke
			(width 0.047498)
			(type default)
		)
		(layer "F.Cu")
	)
	(gr_arc
		(start 221.614746 -160.911794)
		(mid 221.586142 -160.799443)
		(end 221.507304 -160.714436)
		(stroke
			(width 0.047498)
			(type default)
		)
		(layer "F.Cu")
	)
	(gr_line
		(start 221.614746 -160.911794)
		(end 221.614746 -160.96107)
		(stroke
			(width 0.047498)
			(type default)
		)
		(layer "F.Cu")
	)
	(gr_line
		(start 221.614746 -53.9877)
		(end 221.790768 -54.163976)
		(stroke
			(width 0.047498)
			(type default)
		)
		(layer "F.Cu")
	)
	(gr_arc
		(start 221.621096 -57.758076)
		(mid 221.585286 -57.749655)
		(end 221.54896 -57.743852)
		(stroke
			(width 0.047498)
			(type default)
		)
		(layer "F.Cu")
	)
	(gr_arc
		(start 221.633542 -160.280858)
		(mid 221.682255 -160.208035)
		(end 221.699328 -160.122108)
		(stroke
			(width 0.047498)
			(type default)
		)
		(layer "F.Cu")
	)
	(gr_arc
		(start 221.638114 -57.763156)
		(mid 221.629627 -57.760543)
		(end 221.621096 -57.758076)
		(stroke
			(width 0.047498)
			(type default)
		)
		(layer "F.Cu")
	)
	(gr_line
		(start 221.638876 -263.247124)
		(end 221.825058 -263.060942)
		(stroke
			(width 0.047498)
			(type default)
		)
		(layer "F.Cu")
	)
	(gr_arc
		(start 221.639384 -53.239416)
		(mid 221.607974 -53.286379)
		(end 221.596966 -53.341778)
		(stroke
			(width 0.047498)
			(type default)
		)
		(layer "F.Cu")
	)
	(gr_line
		(start 221.639384 -53.239416)
		(end 221.6658 -53.213)
		(stroke
			(width 0.047498)
			(type default)
		)
		(layer "F.Cu")
	)
	(gr_arc
		(start 221.646496 -57.765696)
		(mid 221.64231 -57.764408)
		(end 221.638114 -57.763156)
		(stroke
			(width 0.047498)
			(type default)
		)
		(layer "F.Cu")
	)
	(gr_arc
		(start 221.649544 -366.333786)
		(mid 221.64929 -366.33404)
		(end 221.649036 -366.334294)
		(stroke
			(width 0.047498)
			(type default)
		)
		(layer "F.Cu")
	)
	(gr_arc
		(start 221.649544 -366.333786)
		(mid 221.716482 -366.277832)
		(end 221.741746 -366.19434)
		(stroke
			(width 0.047498)
			(type default)
		)
		(layer "F.Cu")
	)
	(gr_line
		(start 221.649544 -161.045144)
		(end 221.684596 -161.080196)
		(stroke
			(width 0.047498)
			(type default)
		)
		(layer "F.Cu")
	)
	(gr_arc
		(start 221.65691 -57.769252)
		(mid 221.651713 -57.767445)
		(end 221.646496 -57.765696)
		(stroke
			(width 0.047498)
			(type default)
		)
		(layer "F.Cu")
	)
	(gr_line
		(start 221.669864 -466.34019)
		(end 223.249998 -466.34019)
		(stroke
			(width 0.047498)
			(type default)
		)
		(layer "F.Cu")
	)
	(gr_arc
		(start 221.680024 -469.68156)
		(mid 221.657024 -469.678119)
		(end 221.633796 -469.676988)
		(stroke
			(width 0.047498)
			(type default)
		)
		(layer "F.Cu")
	)
	(gr_arc
		(start 221.684596 -161.080196)
		(mid 221.761975 -161.131907)
		(end 221.853252 -161.150046)
		(stroke
			(width 0.047498)
			(type default)
		)
		(layer "F.Cu")
	)
	(gr_line
		(start 221.699328 -160.100518)
		(end 221.699328 -160.122108)
		(stroke
			(width 0.047498)
			(type default)
		)
		(layer "F.Cu")
	)
	(gr_arc
		(start 221.70644 -156.473906)
		(mid 221.752877 -156.404598)
		(end 221.769178 -156.322776)
		(stroke
			(width 0.047498)
			(type default)
		)
		(layer "F.Cu")
	)
	(gr_arc
		(start 221.710504 -57.321196)
		(mid 221.732124 -57.298549)
		(end 221.750128 -57.272936)
		(stroke
			(width 0.047498)
			(type default)
		)
		(layer "F.Cu")
	)
	(gr_line
		(start 221.7166 -469.093296)
		(end 221.7166 -469.1888)
		(stroke
			(width 0.047498)
			(type default)
		)
		(layer "F.Cu")
	)
	(gr_arc
		(start 221.724728 -259.22097)
		(mid 221.718646 -259.238678)
		(end 221.7166 -259.257292)
		(stroke
			(width 0.047498)
			(type default)
		)
		(layer "F.Cu")
	)
	(gr_line
		(start 221.724728 -259.22097)
		(end 221.734888 -259.199634)
		(stroke
			(width 0.047498)
			(type default)
		)
		(layer "F.Cu")
	)
	(gr_arc
		(start 221.729046 -264.01014)
		(mid 221.878583 -264.10997)
		(end 222.054928 -264.145014)
		(stroke
			(width 0.047498)
			(type default)
		)
		(layer "F.Cu")
	)
	(gr_arc
		(start 221.741746 -367.019332)
		(mid 221.751743 -367.069482)
		(end 221.7801 -367.112042)
		(stroke
			(width 0.047498)
			(type default)
		)
		(layer "F.Cu")
	)
	(gr_arc
		(start 221.741746 -366.82934)
		(mid 221.697109 -366.721577)
		(end 221.589346 -366.67694)
		(stroke
			(width 0.047498)
			(type default)
		)
		(layer "F.Cu")
	)
	(gr_line
		(start 221.741746 -366.82934)
		(end 221.741746 -367.019332)
		(stroke
			(width 0.047498)
			(type default)
		)
		(layer "F.Cu")
	)
	(gr_line
		(start 221.741746 -366.065816)
		(end 221.741746 -366.19434)
		(stroke
			(width 0.047498)
			(type default)
		)
		(layer "F.Cu")
	)
	(gr_arc
		(start 221.741746 -363.179868)
		(mid 221.788679 -363.293212)
		(end 221.90202 -363.340142)
		(stroke
			(width 0.047498)
			(type default)
		)
		(layer "F.Cu")
	)
	(gr_arc
		(start 221.741746 -363.01934)
		(mid 221.697109 -362.911577)
		(end 221.589346 -362.86694)
		(stroke
			(width 0.047498)
			(type default)
		)
		(layer "F.Cu")
	)
	(gr_line
		(start 221.741746 -363.01934)
		(end 221.741746 -363.179868)
		(stroke
			(width 0.047498)
			(type default)
		)
		(layer "F.Cu")
	)
	(gr_line
		(start 221.741746 -362.227368)
		(end 221.741746 -362.38434)
		(stroke
			(width 0.047498)
			(type default)
		)
		(layer "F.Cu")
	)
	(gr_arc
		(start 221.741746 -260.162294)
		(mid 221.752848 -260.218093)
		(end 221.784418 -260.265418)
		(stroke
			(width 0.047498)
			(type default)
		)
		(layer "F.Cu")
	)
	(gr_arc
		(start 221.741746 -260.101842)
		(mid 221.700153 -259.96837)
		(end 221.590108 -259.882132)
		(stroke
			(width 0.047498)
			(type default)
		)
		(layer "F.Cu")
	)
	(gr_line
		(start 221.741746 -260.101842)
		(end 221.741746 -260.162294)
		(stroke
			(width 0.047498)
			(type default)
		)
		(layer "F.Cu")
	)
	(gr_arc
		(start 221.741746 -157.15107)
		(mid 221.750759 -157.196581)
		(end 221.776544 -157.235144)
		(stroke
			(width 0.047498)
			(type default)
		)
		(layer "F.Cu")
	)
	(gr_arc
		(start 221.741746 -157.101794)
		(mid 221.673826 -156.93656)
		(end 221.509336 -156.866844)
		(stroke
			(width 0.047498)
			(type default)
		)
		(layer "F.Cu")
	)
	(gr_line
		(start 221.741746 -157.101794)
		(end 221.741746 -157.15107)
		(stroke
			(width 0.047498)
			(type default)
		)
		(layer "F.Cu")
	)
	(gr_line
		(start 221.750128 -57.272936)
		(end 221.76105 -57.254648)
		(stroke
			(width 0.047498)
			(type default)
		)
		(layer "F.Cu")
	)
	(gr_arc
		(start 221.758256 -465.07019)
		(mid 221.566977 -465.149421)
		(end 221.487746 -465.3407)
		(stroke
			(width 0.047498)
			(type default)
		)
		(layer "F.Cu")
	)
	(gr_line
		(start 221.758256 -465.07019)
		(end 223.249998 -465.07019)
		(stroke
			(width 0.047498)
			(type default)
		)
		(layer "F.Cu")
	)
	(gr_arc
		(start 221.76105 -57.254648)
		(mid 221.784474 -57.211879)
		(end 221.804738 -57.167526)
		(stroke
			(width 0.047498)
			(type default)
		)
		(layer "F.Cu")
	)
	(gr_arc
		(start 221.762066 -259.161534)
		(mid 221.746869 -259.179437)
		(end 221.734888 -259.199634)
		(stroke
			(width 0.047498)
			(type default)
		)
		(layer "F.Cu")
	)
	(gr_line
		(start 221.762066 -259.161534)
		(end 221.795848 -259.127752)
		(stroke
			(width 0.047498)
			(type default)
		)
		(layer "F.Cu")
	)
	(gr_line
		(start 221.769178 -156.22905)
		(end 221.769178 -156.322776)
		(stroke
			(width 0.047498)
			(type default)
		)
		(layer "F.Cu")
	)
	(gr_line
		(start 221.776544 -157.235144)
		(end 221.811596 -157.270196)
		(stroke
			(width 0.047498)
			(type default)
		)
		(layer "F.Cu")
	)
	(gr_arc
		(start 221.7801 -367.112042)
		(mid 221.822422 -367.140235)
		(end 221.872302 -367.150142)
		(stroke
			(width 0.047498)
			(type default)
		)
		(layer "F.Cu")
	)
	(gr_line
		(start 221.784418 -260.265418)
		(end 221.821756 -260.302756)
		(stroke
			(width 0.047498)
			(type default)
		)
		(layer "F.Cu")
	)
	(gr_arc
		(start 221.790768 -54.163976)
		(mid 221.985986 -54.294305)
		(end 222.216218 -54.339998)
		(stroke
			(width 0.047498)
			(type default)
		)
		(layer "F.Cu")
	)
	(gr_arc
		(start 221.7928 -468.9094)
		(mid 221.736424 -468.993772)
		(end 221.7166 -469.093296)
		(stroke
			(width 0.047498)
			(type default)
		)
		(layer "F.Cu")
	)
	(gr_arc
		(start 221.796102 -365.934498)
		(mid 221.755898 -365.994761)
		(end 221.741746 -366.065816)
		(stroke
			(width 0.047498)
			(type default)
		)
		(layer "F.Cu")
	)
	(gr_line
		(start 221.804738 -57.167526)
		(end 221.82328 -57.122568)
		(stroke
			(width 0.047498)
			(type default)
		)
		(layer "F.Cu")
	)
	(gr_arc
		(start 221.811596 -157.270196)
		(mid 221.888975 -157.321907)
		(end 221.980252 -157.340046)
		(stroke
			(width 0.047498)
			(type default)
		)
		(layer "F.Cu")
	)
	(gr_arc
		(start 221.821756 -260.302756)
		(mid 221.863133 -260.330372)
		(end 221.911926 -260.340094)
		(stroke
			(width 0.047498)
			(type default)
		)
		(layer "F.Cu")
	)
	(gr_arc
		(start 221.837504 -159.893762)
		(mid 221.737051 -159.976179)
		(end 221.699328 -160.100518)
		(stroke
			(width 0.047498)
			(type default)
		)
		(layer "F.Cu")
	)
	(gr_line
		(start 221.837504 -159.893762)
		(end 221.854522 -159.88665)
		(stroke
			(width 0.047498)
			(type default)
		)
		(layer "F.Cu")
	)
	(gr_arc
		(start 221.84614 -57.88914)
		(mid 221.75822 -57.818629)
		(end 221.65691 -57.769252)
		(stroke
			(width 0.047498)
			(type default)
		)
		(layer "F.Cu")
	)
	(gr_line
		(start 221.84614 -57.88914)
		(end 222.0087 -58.0517)
		(stroke
			(width 0.047498)
			(type default)
		)
		(layer "F.Cu")
	)
	(gr_line
		(start 221.853252 -161.150046)
		(end 223.249998 -161.150046)
		(stroke
			(width 0.047498)
			(type default)
		)
		(layer "F.Cu")
	)
	(gr_arc
		(start 221.863412 -468.88019)
		(mid 221.825212 -468.887788)
		(end 221.7928 -468.9094)
		(stroke
			(width 0.047498)
			(type default)
		)
		(layer "F.Cu")
	)
	(gr_line
		(start 221.863412 -468.88019)
		(end 223.249998 -468.88019)
		(stroke
			(width 0.047498)
			(type default)
		)
		(layer "F.Cu")
	)
	(gr_arc
		(start 221.868746 -470.034112)
		(mid 221.87606 -470.070725)
		(end 221.89694 -470.101676)
		(stroke
			(width 0.047498)
			(type default)
		)
		(layer "F.Cu")
	)
	(gr_arc
		(start 221.868746 -469.911938)
		(mid 221.81554 -469.76304)
		(end 221.680024 -469.68156)
		(stroke
			(width 0.047498)
			(type default)
		)
		(layer "F.Cu")
	)
	(gr_line
		(start 221.868746 -469.911938)
		(end 221.868746 -470.034112)
		(stroke
			(width 0.047498)
			(type default)
		)
		(layer "F.Cu")
	)
	(gr_arc
		(start 221.868746 -156.09189)
		(mid 221.796702 -156.144308)
		(end 221.769178 -156.22905)
		(stroke
			(width 0.047498)
			(type default)
		)
		(layer "F.Cu")
	)
	(gr_line
		(start 221.868746 -156.09189)
		(end 221.910656 -156.078428)
		(stroke
			(width 0.047498)
			(type default)
		)
		(layer "F.Cu")
	)
	(gr_line
		(start 221.872302 -367.150142)
		(end 223.249998 -367.150142)
		(stroke
			(width 0.047498)
			(type default)
		)
		(layer "F.Cu")
	)
	(gr_arc
		(start 221.880938 -57.036462)
		(mid 221.847858 -57.076668)
		(end 221.82328 -57.122568)
		(stroke
			(width 0.047498)
			(type default)
		)
		(layer "F.Cu")
	)
	(gr_line
		(start 221.880938 -57.036462)
		(end 221.8944 -57.023)
		(stroke
			(width 0.047498)
			(type default)
		)
		(layer "F.Cu")
	)
	(gr_arc
		(start 221.887796 -159.880046)
		(mid 221.870826 -159.881679)
		(end 221.854522 -159.88665)
		(stroke
			(width 0.047498)
			(type default)
		)
		(layer "F.Cu")
	)
	(gr_line
		(start 221.887796 -159.880046)
		(end 223.249998 -159.880046)
		(stroke
			(width 0.047498)
			(type default)
		)
		(layer "F.Cu")
	)
	(gr_line
		(start 221.89694 -470.101676)
		(end 221.9071 -470.111836)
		(stroke
			(width 0.047498)
			(type default)
		)
		(layer "F.Cu")
	)
	(gr_arc
		(start 221.898972 -362.070142)
		(mid 221.787796 -362.116192)
		(end 221.741746 -362.227368)
		(stroke
			(width 0.047498)
			(type default)
		)
		(layer "F.Cu")
	)
	(gr_line
		(start 221.898972 -362.070142)
		(end 223.249998 -362.070142)
		(stroke
			(width 0.047498)
			(type default)
		)
		(layer "F.Cu")
	)
	(gr_line
		(start 221.90202 -363.340142)
		(end 223.249998 -363.340142)
		(stroke
			(width 0.047498)
			(type default)
		)
		(layer "F.Cu")
	)
	(gr_arc
		(start 221.9071 -470.111836)
		(mid 221.949393 -470.140171)
		(end 221.999302 -470.15019)
		(stroke
			(width 0.047498)
			(type default)
		)
		(layer "F.Cu")
	)
	(gr_line
		(start 221.911926 -260.340094)
		(end 223.249998 -260.340094)
		(stroke
			(width 0.047498)
			(type default)
		)
		(layer "F.Cu")
	)
	(gr_arc
		(start 221.918276 -259.076952)
		(mid 221.851999 -259.090153)
		(end 221.795848 -259.127752)
		(stroke
			(width 0.047498)
			(type default)
		)
		(layer "F.Cu")
	)
	(gr_line
		(start 221.918276 -259.076952)
		(end 223.24314 -259.076952)
		(stroke
			(width 0.047498)
			(type default)
		)
		(layer "F.Cu")
	)
	(gr_arc
		(start 221.92742 -365.880142)
		(mid 221.856351 -365.894261)
		(end 221.796102 -365.934498)
		(stroke
			(width 0.047498)
			(type default)
		)
		(layer "F.Cu")
	)
	(gr_line
		(start 221.92742 -365.880142)
		(end 223.249998 -365.880142)
		(stroke
			(width 0.047498)
			(type default)
		)
		(layer "F.Cu")
	)
	(gr_arc
		(start 221.963234 -156.070046)
		(mid 221.936613 -156.072165)
		(end 221.910656 -156.078428)
		(stroke
			(width 0.047498)
			(type default)
		)
		(layer "F.Cu")
	)
	(gr_line
		(start 221.963234 -156.070046)
		(end 223.249998 -156.070046)
		(stroke
			(width 0.047498)
			(type default)
		)
		(layer "F.Cu")
	)
	(gr_line
		(start 221.980252 -157.340046)
		(end 223.249998 -157.340046)
		(stroke
			(width 0.047498)
			(type default)
		)
		(layer "F.Cu")
	)
	(gr_line
		(start 221.999302 -470.15019)
		(end 223.249998 -470.15019)
		(stroke
			(width 0.047498)
			(type default)
		)
		(layer "F.Cu")
	)
	(gr_arc
		(start 222.0087 -58.0517)
		(mid 222.117534 -58.124466)
		(end 222.245936 -58.149998)
		(stroke
			(width 0.047498)
			(type default)
		)
		(layer "F.Cu")
	)
	(gr_arc
		(start 222.010986 -53.069998)
		(mid 221.824165 -53.107159)
		(end 221.6658 -53.213)
		(stroke
			(width 0.047498)
			(type default)
		)
		(layer "F.Cu")
	)
	(gr_line
		(start 222.010986 -53.069998)
		(end 223.249998 -53.069998)
		(stroke
			(width 0.047498)
			(type default)
		)
		(layer "F.Cu")
	)
	(gr_line
		(start 222.054928 -264.145014)
		(end 222.060008 -264.150094)
		(stroke
			(width 0.047498)
			(type default)
		)
		(layer "F.Cu")
	)
	(gr_line
		(start 222.060008 -264.150094)
		(end 223.249998 -264.150094)
		(stroke
			(width 0.047498)
			(type default)
		)
		(layer "F.Cu")
	)
	(gr_line
		(start 222.216218 -54.339998)
		(end 223.249998 -54.339998)
		(stroke
			(width 0.047498)
			(type default)
		)
		(layer "F.Cu")
	)
	(gr_arc
		(start 222.239586 -56.879998)
		(mid 222.052782 -56.91719)
		(end 221.8944 -57.023)
		(stroke
			(width 0.047498)
			(type default)
		)
		(layer "F.Cu")
	)
	(gr_line
		(start 222.239586 -56.879998)
		(end 223.249998 -56.879998)
		(stroke
			(width 0.047498)
			(type default)
		)
		(layer "F.Cu")
	)
	(gr_line
		(start 222.245936 -58.149998)
		(end 223.249998 -58.149998)
		(stroke
			(width 0.047498)
			(type default)
		)
		(layer "F.Cu")
	)
	(gr_arc
		(start 222.27413 -262.875014)
		(mid 222.031112 -262.923335)
		(end 221.825058 -263.060942)
		(stroke
			(width 0.047498)
			(type default)
		)
		(layer "F.Cu")
	)
	(gr_line
		(start 222.27413 -262.875014)
		(end 223.244918 -262.875014)
		(stroke
			(width 0.047498)
			(type default)
		)
		(layer "F.Cu")
	)
	(gr_line
		(start 223.002856 -267.83919)
		(end 223.098106 -267.744194)
		(stroke
			(width 0.047498)
			(type default)
		)
		(layer "F.Cu")
	)
	(gr_arc
		(start 223.025716 -369.9383)
		(mid 223.108739 -370.138746)
		(end 223.30918 -370.221764)
		(stroke
			(width 0.047498)
			(type default)
		)
		(layer "F.Cu")
	)
	(gr_line
		(start 223.031812 -61.945012)
		(end 223.314768 -61.662056)
		(stroke
			(width 0.047498)
			(type default)
		)
		(layer "F.Cu")
	)
	(gr_line
		(start 223.031812 -60.986162)
		(end 223.05264 -61.007244)
		(stroke
			(width 0.047498)
			(type default)
		)
		(layer "F.Cu")
	)
	(gr_arc
		(start 223.05264 -61.007244)
		(mid 223.290263 -61.165969)
		(end 223.570546 -61.22162)
		(stroke
			(width 0.047498)
			(type default)
		)
		(layer "F.Cu")
	)
	(gr_arc
		(start 223.071182 -266.97813)
		(mid 223.255415 -267.101271)
		(end 223.472756 -267.1445)
		(stroke
			(width 0.047498)
			(type default)
		)
		(layer "F.Cu")
	)
	(gr_line
		(start 223.163384 -164.934392)
		(end 223.391984 -164.705792)
		(stroke
			(width 0.047498)
			(type default)
		)
		(layer "F.Cu")
	)
	(gr_line
		(start 223.163384 -163.975542)
		(end 223.376744 -164.188902)
		(stroke
			(width 0.047498)
			(type default)
		)
		(layer "F.Cu")
	)
	(gr_line
		(start 223.24314 -259.076952)
		(end 223.249998 -259.070094)
		(stroke
			(width 0.047498)
			(type default)
		)
		(layer "F.Cu")
	)
	(gr_line
		(start 223.244918 -262.875014)
		(end 223.249998 -262.880094)
		(stroke
			(width 0.047498)
			(type default)
		)
		(layer "F.Cu")
	)
	(gr_arc
		(start 223.260412 -370.551964)
		(mid 223.058356 -370.635658)
		(end 222.974662 -370.837714)
		(stroke
			(width 0.047498)
			(type default)
		)
		(layer "F.Cu")
	)
	(gr_arc
		(start 223.376744 -164.188902)
		(mid 223.471612 -164.252266)
		(end 223.5835 -164.2745)
		(stroke
			(width 0.047498)
			(type default)
		)
		(layer "F.Cu")
	)
	(gr_arc
		(start 223.57842 -61.552836)
		(mid 223.435728 -61.581219)
		(end 223.314768 -61.662056)
		(stroke
			(width 0.047498)
			(type default)
		)
		(layer "F.Cu")
	)
	(gr_arc
		(start 223.615504 -164.605208)
		(mid 223.494491 -164.634958)
		(end 223.391984 -164.705792)
		(stroke
			(width 0.047498)
			(type default)
		)
		(layer "F.Cu")
	)
	(gr_arc
		(start 223.636078 -164.6047)
		(mid 223.625787 -164.6048)
		(end 223.615504 -164.605208)
		(stroke
			(width 0.047498)
			(type default)
		)
		(layer "F.Cu")
	)
	(gr_arc
		(start 223.748346 -267.4747)
		(mid 223.396433 -267.544794)
		(end 223.098106 -267.744194)
		(stroke
			(width 0.047498)
			(type default)
		)
		(layer "F.Cu")
	)
	(gr_arc
		(start 223.773746 -473.221558)
		(mid 223.933403 -473.2039)
		(end 224.085404 -473.151962)
		(stroke
			(width 0.047498)
			(type default)
		)
		(layer "F.Cu")
	)
	(gr_arc
		(start 223.835722 -370.221764)
		(mid 224.046734 -370.179762)
		(end 224.225612 -370.06022)
		(stroke
			(width 0.047498)
			(type default)
		)
		(layer "F.Cu")
	)
	(gr_arc
		(start 223.844866 -372.621556)
		(mid 224.047353 -372.581312)
		(end 224.219008 -372.466616)
		(stroke
			(width 0.047498)
			(type default)
		)
		(layer "F.Cu")
	)
	(gr_arc
		(start 223.939354 -63.607442)
		(mid 224.067736 -63.581863)
		(end 224.17659 -63.509144)
		(stroke
			(width 0.047498)
			(type default)
		)
		(layer "F.Cu")
	)
	(gr_arc
		(start 223.954594 -269.621762)
		(mid 224.055775 -269.601619)
		(end 224.141538 -269.544292)
		(stroke
			(width 0.047498)
			(type default)
		)
		(layer "F.Cu")
	)
	(gr_arc
		(start 223.968564 -475.621604)
		(mid 224.056814 -475.604032)
		(end 224.131632 -475.55404)
		(stroke
			(width 0.047498)
			(type default)
		)
		(layer "F.Cu")
	)
	(gr_arc
		(start 223.999044 -61.22162)
		(mid 224.059386 -61.209577)
		(end 224.11055 -61.175392)
		(stroke
			(width 0.047498)
			(type default)
		)
		(layer "F.Cu")
	)
	(gr_arc
		(start 224.029016 -164.2745)
		(mid 224.145167 -164.251388)
		(end 224.243646 -164.1856)
		(stroke
			(width 0.047498)
			(type default)
		)
		(layer "F.Cu")
	)
	(gr_arc
		(start 224.032318 -267.475208)
		(mid 224.021654 -267.474786)
		(end 224.010982 -267.4747)
		(stroke
			(width 0.047498)
			(type default)
		)
		(layer "F.Cu")
	)
	(gr_arc
		(start 224.082864 -267.482066)
		(mid 224.057718 -267.477702)
		(end 224.032318 -267.475208)
		(stroke
			(width 0.047498)
			(type default)
		)
		(layer "F.Cu")
	)
	(gr_arc
		(start 224.085404 -473.151962)
		(mid 224.14513 -473.120593)
		(end 224.201736 -473.08389)
		(stroke
			(width 0.047498)
			(type default)
		)
		(layer "F.Cu")
	)
	(gr_arc
		(start 224.087182 -166.6367)
		(mid 224.219975 -166.610318)
		(end 224.332546 -166.5351)
		(stroke
			(width 0.047498)
			(type default)
		)
		(layer "F.Cu")
	)
	(gr_line
		(start 224.11055 -61.175392)
		(end 224.22104 -61.064648)
		(stroke
			(width 0.047498)
			(type default)
		)
		(layer "F.Cu")
	)
	(gr_arc
		(start 224.124774 -61.612272)
		(mid 224.057634 -61.567504)
		(end 223.97847 -61.55182)
		(stroke
			(width 0.047498)
			(type default)
		)
		(layer "F.Cu")
	)
	(gr_line
		(start 224.124774 -61.612272)
		(end 224.2566 -61.744606)
		(stroke
			(width 0.047498)
			(type default)
		)
		(layer "F.Cu")
	)
	(gr_arc
		(start 224.131124 -473.625926)
		(mid 223.956246 -473.570486)
		(end 223.773746 -473.551758)
		(stroke
			(width 0.047498)
			(type default)
		)
		(layer "F.Cu")
	)
	(gr_line
		(start 224.131632 -475.55404)
		(end 224.207832 -475.47784)
		(stroke
			(width 0.047498)
			(type default)
		)
		(layer "F.Cu")
	)
	(gr_arc
		(start 224.132648 -370.620544)
		(mid 224.056666 -370.569775)
		(end 223.96704 -370.551964)
		(stroke
			(width 0.047498)
			(type default)
		)
		(layer "F.Cu")
	)
	(gr_line
		(start 224.132648 -370.620544)
		(end 224.203006 -370.690902)
		(stroke
			(width 0.047498)
			(type default)
		)
		(layer "F.Cu")
	)
	(gr_arc
		(start 224.137728 -476.025464)
		(mid 224.056153 -475.970957)
		(end 223.959928 -475.951804)
		(stroke
			(width 0.047498)
			(type default)
		)
		(layer "F.Cu")
	)
	(gr_line
		(start 224.137728 -476.025464)
		(end 224.188528 -476.076264)
		(stroke
			(width 0.047498)
			(type default)
		)
		(layer "F.Cu")
	)
	(gr_line
		(start 224.141538 -269.544292)
		(end 224.217738 -269.468092)
		(stroke
			(width 0.047498)
			(type default)
		)
		(layer "F.Cu")
	)
	(gr_arc
		(start 224.144078 -473.631768)
		(mid 224.137612 -473.628822)
		(end 224.131124 -473.625926)
		(stroke
			(width 0.047498)
			(type default)
		)
		(layer "F.Cu")
	)
	(gr_line
		(start 224.144078 -473.631768)
		(end 224.220278 -473.707968)
		(stroke
			(width 0.047498)
			(type default)
		)
		(layer "F.Cu")
	)
	(gr_arc
		(start 224.155254 -64.043052)
		(mid 224.038485 -63.965029)
		(end 223.900746 -63.937642)
		(stroke
			(width 0.047498)
			(type default)
		)
		(layer "F.Cu")
	)
	(gr_line
		(start 224.155254 -64.043052)
		(end 224.203006 -64.090804)
		(stroke
			(width 0.047498)
			(type default)
		)
		(layer "F.Cu")
	)
	(gr_arc
		(start 224.163636 -166.984934)
		(mid 224.122947 -166.971441)
		(end 224.080324 -166.9669)
		(stroke
			(width 0.047498)
			(type default)
		)
		(layer "F.Cu")
	)
	(gr_arc
		(start 224.164652 -373.05234)
		(mid 224.053243 -372.977899)
		(end 223.921828 -372.951756)
		(stroke
			(width 0.047498)
			(type default)
		)
		(layer "F.Cu")
	)
	(gr_arc
		(start 224.164652 -373.05234)
		(mid 224.313463 -373.151798)
		(end 224.48901 -373.186706)
		(stroke
			(width 0.047498)
			(type default)
		)
		(layer "F.Cu")
	)
	(gr_arc
		(start 224.181416 -270.06931)
		(mid 224.051492 -269.982435)
		(end 223.898206 -269.951962)
		(stroke
			(width 0.047498)
			(type default)
		)
		(layer "F.Cu")
	)
	(gr_arc
		(start 224.181416 -270.06931)
		(mid 224.311344 -270.156166)
		(end 224.464626 -270.186658)
		(stroke
			(width 0.047498)
			(type default)
		)
		(layer "F.Cu")
	)
	(gr_arc
		(start 224.188528 -476.076264)
		(mid 224.310885 -476.158044)
		(end 224.455228 -476.186754)
		(stroke
			(width 0.047498)
			(type default)
		)
		(layer "F.Cu")
	)
	(gr_arc
		(start 224.203006 -370.690902)
		(mid 224.309049 -370.761775)
		(end 224.434146 -370.78666)
		(stroke
			(width 0.047498)
			(type default)
		)
		(layer "F.Cu")
	)
	(gr_arc
		(start 224.203006 -64.090804)
		(mid 224.309049 -64.161677)
		(end 224.434146 -64.186562)
		(stroke
			(width 0.047498)
			(type default)
		)
		(layer "F.Cu")
	)
	(gr_arc
		(start 224.217992 -267.5382)
		(mid 224.15601 -267.496692)
		(end 224.082864 -267.482066)
		(stroke
			(width 0.047498)
			(type default)
		)
		(layer "F.Cu")
	)
	(gr_line
		(start 224.217992 -267.5382)
		(end 224.319846 -267.6398)
		(stroke
			(width 0.047498)
			(type default)
		)
		(layer "F.Cu")
	)
	(gr_arc
		(start 224.220278 -473.707968)
		(mid 224.292806 -473.765981)
		(end 224.383346 -473.786708)
		(stroke
			(width 0.047498)
			(type default)
		)
		(layer "F.Cu")
	)
	(gr_line
		(start 224.22104 -61.064648)
		(end 224.221294 -61.06414)
		(stroke
			(width 0.047498)
			(type default)
		)
		(layer "F.Cu")
	)
	(gr_arc
		(start 224.222564 -167.025828)
		(mid 224.194928 -167.002749)
		(end 224.163636 -166.984934)
		(stroke
			(width 0.047498)
			(type default)
		)
		(layer "F.Cu")
	)
	(gr_arc
		(start 224.222564 -167.025828)
		(mid 224.2368 -167.03955)
		(end 224.25152 -167.052752)
		(stroke
			(width 0.047498)
			(type default)
		)
		(layer "F.Cu")
	)
	(gr_arc
		(start 224.230946 -164.6809)
		(mid 224.146574 -164.624524)
		(end 224.04705 -164.6047)
		(stroke
			(width 0.047498)
			(type default)
		)
		(layer "F.Cu")
	)
	(gr_arc
		(start 224.230946 -164.6809)
		(mid 224.34794 -164.759104)
		(end 224.485962 -164.786564)
		(stroke
			(width 0.047498)
			(type default)
		)
		(layer "F.Cu")
	)
	(gr_arc
		(start 224.237804 -63.458598)
		(mid 224.205997 -63.482418)
		(end 224.17659 -63.509144)
		(stroke
			(width 0.047498)
			(type default)
		)
		(layer "F.Cu")
	)
	(gr_line
		(start 224.243646 -164.1856)
		(end 224.319846 -164.1094)
		(stroke
			(width 0.047498)
			(type default)
		)
		(layer "F.Cu")
	)
	(gr_arc
		(start 224.25152 -167.052752)
		(mid 224.399741 -167.151846)
		(end 224.574608 -167.18661)
		(stroke
			(width 0.047498)
			(type default)
		)
		(layer "F.Cu")
	)
	(gr_arc
		(start 224.2566 -61.744606)
		(mid 224.302971 -61.775628)
		(end 224.357692 -61.786516)
		(stroke
			(width 0.047498)
			(type default)
		)
		(layer "F.Cu")
	)
	(gr_arc
		(start 224.294192 -267.1445)
		(mid 224.352893 -267.132803)
		(end 224.40265 -267.099542)
		(stroke
			(width 0.047498)
			(type default)
		)
		(layer "F.Cu")
	)
	(gr_line
		(start 224.319846 -267.6398)
		(end 224.370646 -267.6906)
		(stroke
			(width 0.047498)
			(type default)
		)
		(layer "F.Cu")
	)
	(gr_line
		(start 224.357692 -61.786516)
		(end 224.360994 -61.789818)
		(stroke
			(width 0.047498)
			(type default)
		)
		(layer "F.Cu")
	)
	(gr_line
		(start 224.360994 -61.789818)
		(end 225.399854 -61.789818)
		(stroke
			(width 0.047498)
			(type default)
		)
		(layer "F.Cu")
	)
	(gr_arc
		(start 224.370646 -267.6906)
		(mid 224.477057 -267.761647)
		(end 224.602548 -267.786612)
		(stroke
			(width 0.047498)
			(type default)
		)
		(layer "F.Cu")
	)
	(gr_line
		(start 224.383346 -473.786708)
		(end 225.396552 -473.786708)
		(stroke
			(width 0.047498)
			(type default)
		)
		(layer "F.Cu")
	)
	(gr_arc
		(start 224.402904 -369.986814)
		(mid 224.306966 -370.005897)
		(end 224.225612 -370.06022)
		(stroke
			(width 0.047498)
			(type default)
		)
		(layer "F.Cu")
	)
	(gr_line
		(start 224.402904 -369.986814)
		(end 224.406206 -369.990116)
		(stroke
			(width 0.047498)
			(type default)
		)
		(layer "F.Cu")
	)
	(gr_line
		(start 224.406206 -369.990116)
		(end 225.399854 -369.990116)
		(stroke
			(width 0.047498)
			(type default)
		)
		(layer "F.Cu")
	)
	(gr_arc
		(start 224.408746 -472.986862)
		(mid 224.294443 -473.012329)
		(end 224.201736 -473.08389)
		(stroke
			(width 0.047498)
			(type default)
		)
		(layer "F.Cu")
	)
	(gr_line
		(start 224.408746 -472.986862)
		(end 225.396552 -472.986862)
		(stroke
			(width 0.047498)
			(type default)
		)
		(layer "F.Cu")
	)
	(gr_arc
		(start 224.408746 -60.98667)
		(mid 224.307311 -61.006753)
		(end 224.221294 -61.06414)
		(stroke
			(width 0.047498)
			(type default)
		)
		(layer "F.Cu")
	)
	(gr_line
		(start 224.408746 -60.98667)
		(end 224.412048 -60.989972)
		(stroke
			(width 0.047498)
			(type default)
		)
		(layer "F.Cu")
	)
	(gr_arc
		(start 224.411286 -63.386716)
		(mid 224.317389 -63.405393)
		(end 224.237804 -63.458598)
		(stroke
			(width 0.047498)
			(type default)
		)
		(layer "F.Cu")
	)
	(gr_line
		(start 224.411286 -63.386716)
		(end 224.414588 -63.390018)
		(stroke
			(width 0.047498)
			(type default)
		)
		(layer "F.Cu")
	)
	(gr_arc
		(start 224.41154 -372.38686)
		(mid 224.30734 -372.407587)
		(end 224.219008 -372.466616)
		(stroke
			(width 0.047498)
			(type default)
		)
		(layer "F.Cu")
	)
	(gr_line
		(start 224.41154 -372.38686)
		(end 224.414842 -372.390162)
		(stroke
			(width 0.047498)
			(type default)
		)
		(layer "F.Cu")
	)
	(gr_line
		(start 224.412048 -60.989972)
		(end 225.399854 -60.989972)
		(stroke
			(width 0.047498)
			(type default)
		)
		(layer "F.Cu")
	)
	(gr_arc
		(start 224.41408 -269.386812)
		(mid 224.307839 -269.407945)
		(end 224.217738 -269.468092)
		(stroke
			(width 0.047498)
			(type default)
		)
		(layer "F.Cu")
	)
	(gr_line
		(start 224.41408 -269.386812)
		(end 224.417382 -269.390114)
		(stroke
			(width 0.047498)
			(type default)
		)
		(layer "F.Cu")
	)
	(gr_line
		(start 224.414588 -63.390018)
		(end 225.399854 -63.390018)
		(stroke
			(width 0.047498)
			(type default)
		)
		(layer "F.Cu")
	)
	(gr_line
		(start 224.414842 -372.390162)
		(end 225.399854 -372.390162)
		(stroke
			(width 0.047498)
			(type default)
		)
		(layer "F.Cu")
	)
	(gr_line
		(start 224.417382 -269.390114)
		(end 225.399854 -269.390114)
		(stroke
			(width 0.047498)
			(type default)
		)
		(layer "F.Cu")
	)
	(gr_arc
		(start 224.427288 -475.386908)
		(mid 224.308508 -475.410535)
		(end 224.207832 -475.47784)
		(stroke
			(width 0.047498)
			(type default)
		)
		(layer "F.Cu")
	)
	(gr_line
		(start 224.427288 -475.386908)
		(end 225.396552 -475.386908)
		(stroke
			(width 0.047498)
			(type default)
		)
		(layer "F.Cu")
	)
	(gr_line
		(start 224.434146 -370.78666)
		(end 224.437448 -370.789962)
		(stroke
			(width 0.047498)
			(type default)
		)
		(layer "F.Cu")
	)
	(gr_line
		(start 224.434146 -64.186562)
		(end 224.437448 -64.189864)
		(stroke
			(width 0.047498)
			(type default)
		)
		(layer "F.Cu")
	)
	(gr_line
		(start 224.437448 -370.789962)
		(end 225.399854 -370.789962)
		(stroke
			(width 0.047498)
			(type default)
		)
		(layer "F.Cu")
	)
	(gr_line
		(start 224.437448 -64.189864)
		(end 225.399854 -64.189864)
		(stroke
			(width 0.047498)
			(type default)
		)
		(layer "F.Cu")
	)
	(gr_arc
		(start 224.447354 -267.061188)
		(mid 224.424263 -267.079504)
		(end 224.40265 -267.099542)
		(stroke
			(width 0.047498)
			(type default)
		)
		(layer "F.Cu")
	)
	(gr_line
		(start 224.455228 -476.186754)
		(end 225.396552 -476.186754)
		(stroke
			(width 0.047498)
			(type default)
		)
		(layer "F.Cu")
	)
	(gr_line
		(start 224.464626 -270.186658)
		(end 224.467928 -270.18996)
		(stroke
			(width 0.047498)
			(type default)
		)
		(layer "F.Cu")
	)
	(gr_line
		(start 224.467928 -270.18996)
		(end 225.399854 -270.18996)
		(stroke
			(width 0.047498)
			(type default)
		)
		(layer "F.Cu")
	)
	(gr_line
		(start 224.485962 -164.786564)
		(end 224.489264 -164.789866)
		(stroke
			(width 0.047498)
			(type default)
		)
		(layer "F.Cu")
	)
	(gr_line
		(start 224.48901 -373.186706)
		(end 224.492312 -373.190008)
		(stroke
			(width 0.047498)
			(type default)
		)
		(layer "F.Cu")
	)
	(gr_line
		(start 224.489264 -164.789866)
		(end 225.399854 -164.789866)
		(stroke
			(width 0.047498)
			(type default)
		)
		(layer "F.Cu")
	)
	(gr_line
		(start 224.492312 -373.190008)
		(end 225.399854 -373.190008)
		(stroke
			(width 0.047498)
			(type default)
		)
		(layer "F.Cu")
	)
	(gr_line
		(start 224.574608 -167.18661)
		(end 224.57791 -167.189912)
		(stroke
			(width 0.047498)
			(type default)
		)
		(layer "F.Cu")
	)
	(gr_line
		(start 224.57791 -167.189912)
		(end 225.399854 -167.189912)
		(stroke
			(width 0.047498)
			(type default)
		)
		(layer "F.Cu")
	)
	(gr_line
		(start 224.602548 -267.786612)
		(end 224.60585 -267.789914)
		(stroke
			(width 0.047498)
			(type default)
		)
		(layer "F.Cu")
	)
	(gr_line
		(start 224.60585 -267.789914)
		(end 225.399854 -267.789914)
		(stroke
			(width 0.047498)
			(type default)
		)
		(layer "F.Cu")
	)
	(gr_arc
		(start 224.61601 -163.986718)
		(mid 224.455725 -164.018601)
		(end 224.319846 -164.1094)
		(stroke
			(width 0.047498)
			(type default)
		)
		(layer "F.Cu")
	)
	(gr_line
		(start 224.61601 -163.986718)
		(end 224.619312 -163.99002)
		(stroke
			(width 0.047498)
			(type default)
		)
		(layer "F.Cu")
	)
	(gr_line
		(start 224.619312 -163.99002)
		(end 225.399854 -163.99002)
		(stroke
			(width 0.047498)
			(type default)
		)
		(layer "F.Cu")
	)
	(gr_arc
		(start 224.626932 -266.986766)
		(mid 224.52973 -267.006101)
		(end 224.447354 -267.061188)
		(stroke
			(width 0.047498)
			(type default)
		)
		(layer "F.Cu")
	)
	(gr_line
		(start 224.626932 -266.986766)
		(end 224.630234 -266.990068)
		(stroke
			(width 0.047498)
			(type default)
		)
		(layer "F.Cu")
	)
	(gr_line
		(start 224.630234 -266.990068)
		(end 225.399854 -266.990068)
		(stroke
			(width 0.047498)
			(type default)
		)
		(layer "F.Cu")
	)
	(gr_arc
		(start 224.690686 -166.386764)
		(mid 224.496866 -166.425317)
		(end 224.332546 -166.5351)
		(stroke
			(width 0.047498)
			(type default)
		)
		(layer "F.Cu")
	)
	(gr_line
		(start 224.690686 -166.386764)
		(end 224.693988 -166.390066)
		(stroke
			(width 0.047498)
			(type default)
		)
		(layer "F.Cu")
	)
	(gr_line
		(start 224.693988 -166.390066)
		(end 225.399854 -166.390066)
		(stroke
			(width 0.047498)
			(type default)
		)
		(layer "F.Cu")
	)
	(gr_line
		(start 225.396552 -476.186754)
		(end 225.399854 -476.190056)
		(stroke
			(width 0.047498)
			(type default)
		)
		(layer "F.Cu")
	)
	(gr_line
		(start 225.396552 -475.386908)
		(end 225.399854 -475.39021)
		(stroke
			(width 0.047498)
			(type default)
		)
		(layer "F.Cu")
	)
	(gr_line
		(start 225.396552 -473.786708)
		(end 225.399854 -473.79001)
		(stroke
			(width 0.047498)
			(type default)
		)
		(layer "F.Cu")
	)
	(gr_line
		(start 225.396552 -472.986862)
		(end 225.399854 -472.990164)
		(stroke
			(width 0.047498)
			(type default)
		)
		(layer "F.Cu")
	)
	(gr_poly
		(pts
			(xy 51.561746 -18.1737) (xy 51.561746 -14.8717) (xy 46.481746 -9.7917) (xy 27.939746 -9.7917) (xy 27.177746 -10.5537)
			(xy 27.177746 -17.4117) (xy 28.193746 -18.4277) (xy 51.307746 -18.4277)
		)
		(stroke
			(width 0)
			(type solid)
		)
		(fill yes)
		(layer "B.Cu")
		(net "P5VB_LL")
	)
	(gr_poly
		(pts
			(xy 53.847746 -11.5697) (xy 53.847746 -5.2197) (xy 53.339746 -4.7117) (xy 47.624746 -4.7117) (xy 46.735746 -5.6007)
			(xy 46.735746 -9.4107) (xy 49.656746 -12.3317) (xy 53.085746 -12.3317)
		)
		(stroke
			(width 0)
			(type solid)
		)
		(fill yes)
		(layer "B.Cu")
		(net "P12V")
	)
	(gr_poly
		(pts
			(xy 226.948746 -32.3977) (xy 226.948746 -22.8727) (xy 224.281746 -20.2057) (xy 212.597746 -20.2057)
			(xy 212.089746 -20.7137) (xy 212.089746 -32.0167) (xy 212.851746 -32.7787) (xy 226.567746 -32.7787)
		)
		(stroke
			(width 0)
			(type solid)
		)
		(fill yes)
		(layer "B.Cu")
		(net "P5VA")
	)
	(gr_poly
		(pts
			(xy 234.314746 -12.3317) (xy 234.314746 -4.4577) (xy 233.679746 -3.8227) (xy 228.726746 -3.8227)
			(xy 228.091746 -4.4577) (xy 228.091746 -9.4107) (xy 231.393746 -12.7127) (xy 233.933746 -12.7127)
		)
		(stroke
			(width 0)
			(type solid)
		)
		(fill yes)
		(layer "B.Cu")
		(net "P12V")
	)
	(gr_poly
		(pts
			(xy 45.973746 -29.7307) (xy 45.973746 -27.6987) (xy 43.306746 -25.0317) (xy 43.306746 -19.5707) (xy 42.671746 -18.9357)
			(xy 27.558746 -18.9357) (xy 27.177746 -19.3167) (xy 27.177746 -28.9687) (xy 28.320746 -30.1117) (xy 45.592746 -30.1117)
		)
		(stroke
			(width 0)
			(type solid)
		)
		(fill yes)
		(layer "B.Cu")
		(net "P5VB")
	)
	(gr_poly
		(pts
			(xy 59.943746 -18.3007) (xy 59.943746 -8.3947) (xy 59.435746 -7.8867) (xy 54.609746 -7.8867) (xy 54.482746 -8.0137)
			(xy 54.482746 -12.9667) (xy 55.625746 -14.1097) (xy 55.625746 -18.1737) (xy 56.006746 -18.5547) (xy 59.689746 -18.5547)
		)
		(stroke
			(width 0)
			(type solid)
		)
		(fill yes)
		(layer "B.Cu")
		(net "P5VB_12VIN")
	)
	(gr_poly
		(pts
			(xy 233.806746 -21.6027) (xy 233.806746 -15.6337) (xy 227.456746 -9.2837) (xy 213.232746 -9.2837)
			(xy 212.343746 -10.1727) (xy 212.343746 -19.3167) (xy 212.597746 -19.5707) (xy 225.170746 -19.5707)
			(xy 227.456746 -21.8567) (xy 233.552746 -21.8567)
		)
		(stroke
			(width 0)
			(type solid)
		)
		(fill yes)
		(layer "B.Cu")
		(net "P5VA_LL")
	)
	(gr_poly
		(pts
			(xy 28.574746 -500.0117) (xy 28.574746 -497.5987) (xy 28.193746 -497.2177) (xy 24.002746 -497.2177)
			(xy 23.240746 -496.4557) (xy 11.937746 -496.4557) (xy 11.683746 -496.7097) (xy 11.683746 -499.1227)
			(xy 12.826746 -500.2657) (xy 24.637746 -500.2657) (xy 25.272746 -500.9007) (xy 27.685746 -500.9007)
		)
		(stroke
			(width 0)
			(type solid)
		)
		(fill yes)
		(layer "B.Cu")
		(net "P5VC_12VIN")
	)
	(gr_poly
		(pts
			(xy 22.732746 -494.2967) (xy 22.732746 -486.9307) (xy 21.589746 -485.7877) (xy 19.176746 -485.7877)
			(xy 18.281396 -484.892604) (xy 15.23365 -484.892604) (xy 14.096746 -483.7557) (xy 11.938 -483.7557)
			(xy 11.557 -484.1367) (xy 11.557 -491.871) (xy 11.684 -491.998) (xy 14.084046 -491.998) (xy 17.652746 -495.5667)
			(xy 21.462746 -495.5667)
		)
		(stroke
			(width 0)
			(type solid)
		)
		(fill yes)
		(layer "B.Cu")
		(net "P5VC_LL")
	)
	(gr_poly
		(pts
			(xy 242.442746 -21.6027) (xy 242.442746 -8.6487) (xy 241.553746 -7.7597) (xy 235.457746 -7.7597)
			(xy 234.949746 -8.2677) (xy 234.949746 -16.6497) (xy 236.727746 -18.4277) (xy 236.727746 -20.7137)
			(xy 237.223808 -21.209762)
			(arc
				(start 237.231174 -21.213572)
				(mid 237.385434 -21.324234)
				(end 237.496096 -21.478494)
			)
			(xy 237.499906 -21.48586) (xy 237.870746 -21.8567) (xy 242.188746 -21.8567)
		)
		(stroke
			(width 0)
			(type solid)
		)
		(fill yes)
		(layer "B.Cu")
		(net "P5VA_12VIN")
	)
	(gr_poly
		(pts
			(xy 34.924746 -495.3127) (xy 34.924746 -485.1527) (xy 33.146746 -483.3747) (xy 29.971746 -483.3747)
			(xy 27.177746 -480.5807) (xy 27.177746 -474.2307) (xy 26.415746 -473.4687) (xy 21.208746 -473.4687)
			(xy 20.319746 -474.3577) (xy 20.319746 -476.6437) (xy 20.065746 -476.8977) (xy 14.477746 -476.8977)
			(xy 13.842746 -477.5327) (xy 13.842746 -482.2317) (xy 15.620746 -484.0097) (xy 18.541746 -484.0097)
			(xy 19.424396 -484.892604) (xy 22.104604 -484.892604) (xy 23.622 -486.41) (xy 23.622 -494.423954)
			(xy 25.907746 -496.7097) (xy 33.527746 -496.7097)
		)
		(stroke
			(width 0)
			(type solid)
		)
		(fill yes)
		(layer "B.Cu")
		(net "P5VC")
	)
	(gr_poly
		(pts
			(arc
				(start 32.090106 -504.4567)
				(mid 32.639 -504.163994)
				(end 33.187894 -504.4567)
			)
			(xy 34.543746 -504.4567) (xy 35.432746 -503.5677) (xy 35.432746 -497.4717) (xy 35.178746 -497.2177)
			(xy 29.717746 -497.2177) (xy 29.463746 -497.4717) (xy 29.463746 -503.8217) (xy 30.098746 -504.4567)
		)
		(stroke
			(width 0)
			(type solid)
		)
		(fill yes)
		(layer "B.Cu")
		(net "P12V")
	)
	(gr_line
		(start 2.811526 -422.498774)
		(end 4.707128 -422.498774)
		(stroke
			(width 0.047498)
			(type default)
		)
		(layer "B.Cu")
	)
	(gr_line
		(start 2.811526 -421.498776)
		(end 4.837176 -421.498776)
		(stroke
			(width 0.047498)
			(type default)
		)
		(layer "B.Cu")
	)
	(gr_line
		(start 2.811526 -418.498782)
		(end 4.675378 -418.498782)
		(stroke
			(width 0.047498)
			(type default)
		)
		(layer "B.Cu")
	)
	(gr_line
		(start 2.811526 -417.498784)
		(end 4.715764 -417.498784)
		(stroke
			(width 0.047498)
			(type default)
		)
		(layer "B.Cu")
	)
	(gr_line
		(start 2.811526 -414.49879)
		(end 4.919218 -414.49879)
		(stroke
			(width 0.047498)
			(type default)
		)
		(layer "B.Cu")
	)
	(gr_line
		(start 2.811526 -413.498792)
		(end 4.825492 -413.498792)
		(stroke
			(width 0.047498)
			(type default)
		)
		(layer "B.Cu")
	)
	(gr_line
		(start 2.811526 -410.498798)
		(end 4.702302 -410.498798)
		(stroke
			(width 0.047498)
			(type default)
		)
		(layer "B.Cu")
	)
	(gr_line
		(start 2.811526 -409.4988)
		(end 4.715764 -409.4988)
		(stroke
			(width 0.047498)
			(type default)
		)
		(layer "B.Cu")
	)
	(gr_line
		(start 2.811526 -406.498806)
		(end 4.568952 -406.498806)
		(stroke
			(width 0.047498)
			(type default)
		)
		(layer "B.Cu")
	)
	(gr_line
		(start 2.811526 -405.498808)
		(end 4.789678 -405.498808)
		(stroke
			(width 0.047498)
			(type default)
		)
		(layer "B.Cu")
	)
	(gr_line
		(start 2.811526 -398.498822)
		(end 4.598162 -398.498822)
		(stroke
			(width 0.047498)
			(type default)
		)
		(layer "B.Cu")
	)
	(gr_line
		(start 2.811526 -397.498824)
		(end 4.701794 -397.498824)
		(stroke
			(width 0.047498)
			(type default)
		)
		(layer "B.Cu")
	)
	(gr_line
		(start 2.811526 -384.49885)
		(end 4.872482 -384.49885)
		(stroke
			(width 0.047498)
			(type default)
		)
		(layer "B.Cu")
	)
	(gr_line
		(start 2.811526 -383.498852)
		(end 4.93776 -383.498852)
		(stroke
			(width 0.047498)
			(type default)
		)
		(layer "B.Cu")
	)
	(gr_line
		(start 2.811526 -380.498858)
		(end 4.922774 -380.498858)
		(stroke
			(width 0.047498)
			(type default)
		)
		(layer "B.Cu")
	)
	(gr_line
		(start 2.811526 -379.49886)
		(end 2.81305 -379.500384)
		(stroke
			(width 0.047498)
			(type default)
		)
		(layer "B.Cu")
	)
	(gr_line
		(start 2.811526 -376.498866)
		(end 4.890516 -376.498866)
		(stroke
			(width 0.047498)
			(type default)
		)
		(layer "B.Cu")
	)
	(gr_line
		(start 2.811526 -375.498868)
		(end 4.873244 -375.498868)
		(stroke
			(width 0.047498)
			(type default)
		)
		(layer "B.Cu")
	)
	(gr_line
		(start 2.811526 -372.498874)
		(end 4.699508 -372.498874)
		(stroke
			(width 0.047498)
			(type default)
		)
		(layer "B.Cu")
	)
	(gr_line
		(start 2.811526 -371.498876)
		(end 4.697476 -371.498876)
		(stroke
			(width 0.047498)
			(type default)
		)
		(layer "B.Cu")
	)
	(gr_line
		(start 2.811526 -368.498882)
		(end 4.879086 -368.498882)
		(stroke
			(width 0.047498)
			(type default)
		)
		(layer "B.Cu")
	)
	(gr_line
		(start 2.811526 -367.498884)
		(end 4.858512 -367.498884)
		(stroke
			(width 0.047498)
			(type default)
		)
		(layer "B.Cu")
	)
	(gr_line
		(start 2.811526 -364.49889)
		(end 4.81076 -364.49889)
		(stroke
			(width 0.047498)
			(type default)
		)
		(layer "B.Cu")
	)
	(gr_line
		(start 2.811526 -363.498892)
		(end 4.944618 -363.498892)
		(stroke
			(width 0.047498)
			(type default)
		)
		(layer "B.Cu")
	)
	(gr_line
		(start 2.811526 -360.498898)
		(end 4.789932 -360.498898)
		(stroke
			(width 0.047498)
			(type default)
		)
		(layer "B.Cu")
	)
	(gr_line
		(start 2.811526 -359.4989)
		(end 4.907788 -359.4989)
		(stroke
			(width 0.047498)
			(type default)
		)
		(layer "B.Cu")
	)
	(gr_line
		(start 2.811526 -354.498402)
		(end 4.971796 -354.498402)
		(stroke
			(width 0.047498)
			(type default)
		)
		(layer "B.Cu")
	)
	(gr_line
		(start 2.811526 -353.498404)
		(end 2.81305 -353.499928)
		(stroke
			(width 0.047498)
			(type default)
		)
		(layer "B.Cu")
	)
	(gr_line
		(start 2.811526 -350.49841)
		(end 2.81305 -350.499934)
		(stroke
			(width 0.047498)
			(type default)
		)
		(layer "B.Cu")
	)
	(gr_line
		(start 2.811526 -349.498412)
		(end 4.703826 -349.498412)
		(stroke
			(width 0.047498)
			(type default)
		)
		(layer "B.Cu")
	)
	(gr_line
		(start 2.811526 -346.498418)
		(end 4.800346 -346.498418)
		(stroke
			(width 0.047498)
			(type default)
		)
		(layer "B.Cu")
	)
	(gr_line
		(start 2.811526 -345.49842)
		(end 4.83108 -345.49842)
		(stroke
			(width 0.047498)
			(type default)
		)
		(layer "B.Cu")
	)
	(gr_line
		(start 2.811526 -172.498766)
		(end 4.660138 -172.498766)
		(stroke
			(width 0.047498)
			(type default)
		)
		(layer "B.Cu")
	)
	(gr_line
		(start 2.811526 -171.498768)
		(end 4.821428 -171.498768)
		(stroke
			(width 0.047498)
			(type default)
		)
		(layer "B.Cu")
	)
	(gr_line
		(start 2.811526 -168.498774)
		(end 2.81305 -168.500298)
		(stroke
			(width 0.047498)
			(type default)
		)
		(layer "B.Cu")
	)
	(gr_line
		(start 2.811526 -167.498776)
		(end 4.867148 -167.498776)
		(stroke
			(width 0.047498)
			(type default)
		)
		(layer "B.Cu")
	)
	(gr_line
		(start 2.811526 -164.498782)
		(end 4.981702 -164.498782)
		(stroke
			(width 0.047498)
			(type default)
		)
		(layer "B.Cu")
	)
	(gr_line
		(start 2.811526 -163.498784)
		(end 4.691888 -163.498784)
		(stroke
			(width 0.047498)
			(type default)
		)
		(layer "B.Cu")
	)
	(gr_line
		(start 2.811526 -160.49879)
		(end 4.986528 -160.49879)
		(stroke
			(width 0.047498)
			(type default)
		)
		(layer "B.Cu")
	)
	(gr_line
		(start 2.811526 -159.498792)
		(end 4.999482 -159.498792)
		(stroke
			(width 0.047498)
			(type default)
		)
		(layer "B.Cu")
	)
	(gr_line
		(start 2.811526 -156.498798)
		(end 4.641596 -156.498798)
		(stroke
			(width 0.047498)
			(type default)
		)
		(layer "B.Cu")
	)
	(gr_line
		(start 2.811526 -155.4988)
		(end 4.64693 -155.4988)
		(stroke
			(width 0.047498)
			(type default)
		)
		(layer "B.Cu")
	)
	(gr_line
		(start 2.811526 -148.498814)
		(end 4.688586 -148.498814)
		(stroke
			(width 0.047498)
			(type default)
		)
		(layer "B.Cu")
	)
	(gr_line
		(start 2.811526 -147.498816)
		(end 4.660646 -147.498816)
		(stroke
			(width 0.047498)
			(type default)
		)
		(layer "B.Cu")
	)
	(gr_line
		(start 2.811526 -134.498842)
		(end 4.900676 -134.498842)
		(stroke
			(width 0.047498)
			(type default)
		)
		(layer "B.Cu")
	)
	(gr_line
		(start 2.811526 -133.498844)
		(end 4.966462 -133.498844)
		(stroke
			(width 0.047498)
			(type default)
		)
		(layer "B.Cu")
	)
	(gr_line
		(start 2.811526 -130.49885)
		(end 4.824476 -130.49885)
		(stroke
			(width 0.047498)
			(type default)
		)
		(layer "B.Cu")
	)
	(gr_line
		(start 2.811526 -129.498852)
		(end 2.81305 -129.500376)
		(stroke
			(width 0.047498)
			(type default)
		)
		(layer "B.Cu")
	)
	(gr_line
		(start 2.811526 -126.498858)
		(end 4.966716 -126.498858)
		(stroke
			(width 0.047498)
			(type default)
		)
		(layer "B.Cu")
	)
	(gr_line
		(start 2.811526 -125.49886)
		(end 4.98856 -125.49886)
		(stroke
			(width 0.047498)
			(type default)
		)
		(layer "B.Cu")
	)
	(gr_line
		(start 2.811526 -122.498866)
		(end 4.926076 -122.498866)
		(stroke
			(width 0.047498)
			(type default)
		)
		(layer "B.Cu")
	)
	(gr_line
		(start 2.811526 -121.498868)
		(end 4.875276 -121.498868)
		(stroke
			(width 0.047498)
			(type default)
		)
		(layer "B.Cu")
	)
	(gr_line
		(start 2.811526 -118.498874)
		(end 4.849876 -118.498874)
		(stroke
			(width 0.047498)
			(type default)
		)
		(layer "B.Cu")
	)
	(gr_line
		(start 2.811526 -117.498876)
		(end 4.926076 -117.498876)
		(stroke
			(width 0.047498)
			(type default)
		)
		(layer "B.Cu")
	)
	(gr_line
		(start 2.811526 -114.498882)
		(end 5.010658 -114.498882)
		(stroke
			(width 0.047498)
			(type default)
		)
		(layer "B.Cu")
	)
	(gr_line
		(start 2.811526 -113.498884)
		(end 2.81305 -113.500408)
		(stroke
			(width 0.047498)
			(type default)
		)
		(layer "B.Cu")
	)
	(gr_line
		(start 2.811526 -110.49889)
		(end 4.93014 -110.49889)
		(stroke
			(width 0.047498)
			(type default)
		)
		(layer "B.Cu")
	)
	(gr_line
		(start 2.811526 -109.498892)
		(end 5.025898 -109.498892)
		(stroke
			(width 0.047498)
			(type default)
		)
		(layer "B.Cu")
	)
	(gr_line
		(start 2.811526 -104.498394)
		(end 2.81305 -104.499918)
		(stroke
			(width 0.047498)
			(type default)
		)
		(layer "B.Cu")
	)
	(gr_line
		(start 2.811526 -103.498396)
		(end 5.036566 -103.498396)
		(stroke
			(width 0.047498)
			(type default)
		)
		(layer "B.Cu")
	)
	(gr_line
		(start 2.811526 -100.498402)
		(end 4.994656 -100.498402)
		(stroke
			(width 0.047498)
			(type default)
		)
		(layer "B.Cu")
	)
	(gr_line
		(start 2.811526 -99.498404)
		(end 4.951476 -99.498404)
		(stroke
			(width 0.047498)
			(type default)
		)
		(layer "B.Cu")
	)
	(gr_line
		(start 2.811526 -96.49841)
		(end 4.864354 -96.49841)
		(stroke
			(width 0.047498)
			(type default)
		)
		(layer "B.Cu")
	)
	(gr_line
		(start 2.811526 -95.498412)
		(end 4.996434 -95.503746)
		(stroke
			(width 0.047498)
			(type default)
		)
		(layer "B.Cu")
	)
	(gr_line
		(start 2.81305 -379.500384)
		(end 5.024882 -379.500384)
		(stroke
			(width 0.047498)
			(type default)
		)
		(layer "B.Cu")
	)
	(gr_line
		(start 2.81305 -353.499928)
		(end 5.092954 -353.499928)
		(stroke
			(width 0.047498)
			(type default)
		)
		(layer "B.Cu")
	)
	(gr_line
		(start 2.81305 -350.499934)
		(end 5.068062 -350.499934)
		(stroke
			(width 0.047498)
			(type default)
		)
		(layer "B.Cu")
	)
	(gr_line
		(start 2.81305 -168.500298)
		(end 5.044948 -168.500298)
		(stroke
			(width 0.047498)
			(type default)
		)
		(layer "B.Cu")
	)
	(gr_line
		(start 2.81305 -129.500376)
		(end 5.069586 -129.500376)
		(stroke
			(width 0.047498)
			(type default)
		)
		(layer "B.Cu")
	)
	(gr_line
		(start 2.81305 -113.500408)
		(end 5.036058 -113.500408)
		(stroke
			(width 0.047498)
			(type default)
		)
		(layer "B.Cu")
	)
	(gr_line
		(start 2.81305 -104.499918)
		(end 5.066538 -104.499918)
		(stroke
			(width 0.047498)
			(type default)
		)
		(layer "B.Cu")
	)
	(gr_line
		(start 4.568952 -406.498806)
		(end 4.570476 -406.50033)
		(stroke
			(width 0.047498)
			(type default)
		)
		(layer "B.Cu")
	)
	(gr_arc
		(start 4.570476 -406.50033)
		(mid 4.936127 -406.427552)
		(end 5.246116 -406.220422)
		(stroke
			(width 0.047498)
			(type default)
		)
		(layer "B.Cu")
	)
	(gr_line
		(start 4.598162 -398.498822)
		(end 4.599686 -398.500346)
		(stroke
			(width 0.047498)
			(type default)
		)
		(layer "B.Cu")
	)
	(gr_arc
		(start 4.599686 -398.500346)
		(mid 4.896051 -398.441393)
		(end 5.14731 -398.273524)
		(stroke
			(width 0.047498)
			(type default)
		)
		(layer "B.Cu")
	)
	(gr_line
		(start 4.641596 -156.498798)
		(end 4.64312 -156.500322)
		(stroke
			(width 0.047498)
			(type default)
		)
		(layer "B.Cu")
	)
	(gr_arc
		(start 4.64312 -156.500322)
		(mid 4.946088 -156.440039)
		(end 5.202936 -156.26842)
		(stroke
			(width 0.047498)
			(type default)
		)
		(layer "B.Cu")
	)
	(gr_line
		(start 4.64693 -155.4988)
		(end 4.648454 -155.500324)
		(stroke
			(width 0.047498)
			(type default)
		)
		(layer "B.Cu")
	)
	(gr_line
		(start 4.660138 -172.498766)
		(end 4.661662 -172.50029)
		(stroke
			(width 0.047498)
			(type default)
		)
		(layer "B.Cu")
	)
	(gr_line
		(start 4.660646 -147.498816)
		(end 4.66217 -147.50034)
		(stroke
			(width 0.047498)
			(type default)
		)
		(layer "B.Cu")
	)
	(gr_arc
		(start 4.661662 -172.50029)
		(mid 4.966287 -172.439684)
		(end 5.224526 -172.267118)
		(stroke
			(width 0.047498)
			(type default)
		)
		(layer "B.Cu")
	)
	(gr_line
		(start 4.675378 -418.498782)
		(end 4.676902 -418.500306)
		(stroke
			(width 0.047498)
			(type default)
		)
		(layer "B.Cu")
	)
	(gr_arc
		(start 4.676902 -418.500306)
		(mid 4.996782 -418.436654)
		(end 5.26796 -418.25545)
		(stroke
			(width 0.047498)
			(type default)
		)
		(layer "B.Cu")
	)
	(gr_line
		(start 4.688586 -148.498814)
		(end 4.69011 -148.500338)
		(stroke
			(width 0.047498)
			(type default)
		)
		(layer "B.Cu")
	)
	(gr_arc
		(start 4.69011 -148.500338)
		(mid 4.96626 -148.445408)
		(end 5.200396 -148.28901)
		(stroke
			(width 0.047498)
			(type default)
		)
		(layer "B.Cu")
	)
	(gr_line
		(start 4.691888 -163.498784)
		(end 4.693412 -163.500308)
		(stroke
			(width 0.047498)
			(type default)
		)
		(layer "B.Cu")
	)
	(gr_line
		(start 4.697476 -371.498876)
		(end 4.699 -371.5004)
		(stroke
			(width 0.047498)
			(type default)
		)
		(layer "B.Cu")
	)
	(gr_line
		(start 4.699508 -372.498874)
		(end 4.701032 -372.500398)
		(stroke
			(width 0.047498)
			(type default)
		)
		(layer "B.Cu")
	)
	(gr_arc
		(start 4.701032 -372.500398)
		(mid 4.99273 -372.442367)
		(end 5.24002 -372.277132)
		(stroke
			(width 0.047498)
			(type default)
		)
		(layer "B.Cu")
	)
	(gr_line
		(start 4.701794 -397.498824)
		(end 4.703318 -397.500348)
		(stroke
			(width 0.047498)
			(type default)
		)
		(layer "B.Cu")
	)
	(gr_line
		(start 4.702302 -410.498798)
		(end 4.703826 -410.500322)
		(stroke
			(width 0.047498)
			(type default)
		)
		(layer "B.Cu")
	)
	(gr_arc
		(start 4.703826 -410.500322)
		(mid 4.992227 -410.442963)
		(end 5.236718 -410.279596)
		(stroke
			(width 0.047498)
			(type default)
		)
		(layer "B.Cu")
	)
	(gr_line
		(start 4.703826 -349.498412)
		(end 4.70535 -349.499936)
		(stroke
			(width 0.047498)
			(type default)
		)
		(layer "B.Cu")
	)
	(gr_line
		(start 4.707128 -422.498774)
		(end 4.708652 -422.500298)
		(stroke
			(width 0.047498)
			(type default)
		)
		(layer "B.Cu")
	)
	(gr_arc
		(start 4.708652 -422.500298)
		(mid 4.990725 -422.444177)
		(end 5.22986 -422.284398)
		(stroke
			(width 0.047498)
			(type default)
		)
		(layer "B.Cu")
	)
	(gr_line
		(start 4.715764 -417.498784)
		(end 4.717288 -417.500308)
		(stroke
			(width 0.047498)
			(type default)
		)
		(layer "B.Cu")
	)
	(gr_line
		(start 4.715764 -409.4988)
		(end 4.717288 -409.500324)
		(stroke
			(width 0.047498)
			(type default)
		)
		(layer "B.Cu")
	)
	(gr_line
		(start 4.789678 -405.498808)
		(end 4.791202 -405.500332)
		(stroke
			(width 0.047498)
			(type default)
		)
		(layer "B.Cu")
	)
	(gr_line
		(start 4.789932 -360.498898)
		(end 4.791456 -360.500422)
		(stroke
			(width 0.047498)
			(type default)
		)
		(layer "B.Cu")
	)
	(gr_arc
		(start 4.791456 -360.500422)
		(mid 5.000807 -360.458737)
		(end 5.178298 -360.340148)
		(stroke
			(width 0.047498)
			(type default)
		)
		(layer "B.Cu")
	)
	(gr_line
		(start 4.800346 -346.498418)
		(end 4.80187 -346.499942)
		(stroke
			(width 0.047498)
			(type default)
		)
		(layer "B.Cu")
	)
	(gr_arc
		(start 4.80187 -346.499942)
		(mid 5.075705 -346.445508)
		(end 5.307838 -346.290392)
		(stroke
			(width 0.047498)
			(type default)
		)
		(layer "B.Cu")
	)
	(gr_line
		(start 4.81076 -364.49889)
		(end 4.812284 -364.500414)
		(stroke
			(width 0.047498)
			(type default)
		)
		(layer "B.Cu")
	)
	(gr_arc
		(start 4.812284 -364.500414)
		(mid 5.013686 -364.460353)
		(end 5.184394 -364.346236)
		(stroke
			(width 0.047498)
			(type default)
		)
		(layer "B.Cu")
	)
	(gr_line
		(start 4.821428 -171.498768)
		(end 4.822952 -171.500292)
		(stroke
			(width 0.047498)
			(type default)
		)
		(layer "B.Cu")
	)
	(gr_line
		(start 4.824476 -130.49885)
		(end 4.826 -130.500374)
		(stroke
			(width 0.047498)
			(type default)
		)
		(layer "B.Cu")
	)
	(gr_line
		(start 4.825492 -413.498792)
		(end 4.827016 -413.500316)
		(stroke
			(width 0.047498)
			(type default)
		)
		(layer "B.Cu")
	)
	(gr_arc
		(start 4.826 -130.500374)
		(mid 5.008821 -130.463979)
		(end 5.16382 -130.36042)
		(stroke
			(width 0.047498)
			(type default)
		)
		(layer "B.Cu")
	)
	(gr_line
		(start 4.83108 -345.49842)
		(end 4.832604 -345.499944)
		(stroke
			(width 0.047498)
			(type default)
		)
		(layer "B.Cu")
	)
	(gr_line
		(start 4.837176 -421.498776)
		(end 4.8387 -421.5003)
		(stroke
			(width 0.047498)
			(type default)
		)
		(layer "B.Cu")
	)
	(gr_line
		(start 4.849876 -118.498874)
		(end 4.8514 -118.500398)
		(stroke
			(width 0.047498)
			(type default)
		)
		(layer "B.Cu")
	)
	(gr_arc
		(start 4.8514 -118.500398)
		(mid 4.97814 -118.475164)
		(end 5.085588 -118.40337)
		(stroke
			(width 0.047498)
			(type default)
		)
		(layer "B.Cu")
	)
	(gr_line
		(start 4.858512 -367.498884)
		(end 4.860036 -367.500408)
		(stroke
			(width 0.047498)
			(type default)
		)
		(layer "B.Cu")
	)
	(gr_line
		(start 4.864354 -96.49841)
		(end 4.865878 -96.499934)
		(stroke
			(width 0.047498)
			(type default)
		)
		(layer "B.Cu")
	)
	(gr_arc
		(start 4.865878 -96.499934)
		(mid 5.10947 -96.451489)
		(end 5.315966 -96.313498)
		(stroke
			(width 0.047498)
			(type default)
		)
		(layer "B.Cu")
	)
	(gr_line
		(start 4.867148 -167.498776)
		(end 4.868672 -167.5003)
		(stroke
			(width 0.047498)
			(type default)
		)
		(layer "B.Cu")
	)
	(gr_line
		(start 4.872482 -384.49885)
		(end 4.874006 -384.500374)
		(stroke
			(width 0.047498)
			(type default)
		)
		(layer "B.Cu")
	)
	(gr_line
		(start 4.873244 -375.498868)
		(end 4.874768 -375.500392)
		(stroke
			(width 0.047498)
			(type default)
		)
		(layer "B.Cu")
	)
	(gr_arc
		(start 4.874006 -384.500374)
		(mid 5.120882 -384.451236)
		(end 5.33019 -384.311398)
		(stroke
			(width 0.047498)
			(type default)
		)
		(layer "B.Cu")
	)
	(gr_line
		(start 4.875276 -121.498868)
		(end 4.8768 -121.500392)
		(stroke
			(width 0.047498)
			(type default)
		)
		(layer "B.Cu")
	)
	(gr_line
		(start 4.879086 -368.498882)
		(end 4.88061 -368.500406)
		(stroke
			(width 0.047498)
			(type default)
		)
		(layer "B.Cu")
	)
	(gr_arc
		(start 4.88061 -368.500406)
		(mid 5.125851 -368.451625)
		(end 5.333746 -368.3127)
		(stroke
			(width 0.047498)
			(type default)
		)
		(layer "B.Cu")
	)
	(gr_line
		(start 4.890516 -376.498866)
		(end 4.89204 -376.50039)
		(stroke
			(width 0.047498)
			(type default)
		)
		(layer "B.Cu")
	)
	(gr_arc
		(start 4.89204 -376.50039)
		(mid 5.127653 -376.453515)
		(end 5.327396 -376.32005)
		(stroke
			(width 0.047498)
			(type default)
		)
		(layer "B.Cu")
	)
	(gr_line
		(start 4.900676 -134.498842)
		(end 4.9022 -134.500366)
		(stroke
			(width 0.047498)
			(type default)
		)
		(layer "B.Cu")
	)
	(gr_arc
		(start 4.9022 -134.500366)
		(mid 5.036231 -134.473683)
		(end 5.14985 -134.39775)
		(stroke
			(width 0.047498)
			(type default)
		)
		(layer "B.Cu")
	)
	(gr_line
		(start 4.907788 -359.4989)
		(end 4.909312 -359.500424)
		(stroke
			(width 0.047498)
			(type default)
		)
		(layer "B.Cu")
	)
	(gr_line
		(start 4.919218 -414.49879)
		(end 4.920742 -414.500314)
		(stroke
			(width 0.047498)
			(type default)
		)
		(layer "B.Cu")
	)
	(gr_arc
		(start 4.920742 -414.500314)
		(mid 5.116898 -414.461306)
		(end 5.2832 -414.3502)
		(stroke
			(width 0.047498)
			(type default)
		)
		(layer "B.Cu")
	)
	(gr_line
		(start 4.922774 -380.498858)
		(end 4.924298 -380.500382)
		(stroke
			(width 0.047498)
			(type default)
		)
		(layer "B.Cu")
	)
	(gr_arc
		(start 4.924298 -380.500382)
		(mid 5.183151 -380.448899)
		(end 5.40258 -380.302262)
		(stroke
			(width 0.047498)
			(type default)
		)
		(layer "B.Cu")
	)
	(gr_line
		(start 4.926076 -122.498866)
		(end 4.9276 -122.50039)
		(stroke
			(width 0.047498)
			(type default)
		)
		(layer "B.Cu")
	)
	(gr_line
		(start 4.926076 -117.498876)
		(end 4.9276 -117.5004)
		(stroke
			(width 0.047498)
			(type default)
		)
		(layer "B.Cu")
	)
	(gr_arc
		(start 4.9276 -122.50039)
		(mid 4.982566 -122.489536)
		(end 5.0292 -122.45848)
		(stroke
			(width 0.047498)
			(type default)
		)
		(layer "B.Cu")
	)
	(gr_line
		(start 4.93014 -110.49889)
		(end 4.931664 -110.500414)
		(stroke
			(width 0.047498)
			(type default)
		)
		(layer "B.Cu")
	)
	(gr_arc
		(start 4.931664 -110.500414)
		(mid 5.123443 -110.462267)
		(end 5.285994 -110.353602)
		(stroke
			(width 0.047498)
			(type default)
		)
		(layer "B.Cu")
	)
	(gr_line
		(start 4.93776 -383.498852)
		(end 4.939284 -383.500376)
		(stroke
			(width 0.047498)
			(type default)
		)
		(layer "B.Cu")
	)
	(gr_line
		(start 4.944618 -363.498892)
		(end 4.946142 -363.500416)
		(stroke
			(width 0.047498)
			(type default)
		)
		(layer "B.Cu")
	)
	(gr_line
		(start 4.951476 -99.498404)
		(end 4.953 -99.499928)
		(stroke
			(width 0.047498)
			(type default)
		)
		(layer "B.Cu")
	)
	(gr_line
		(start 4.966462 -133.498844)
		(end 4.967986 -133.500368)
		(stroke
			(width 0.047498)
			(type default)
		)
		(layer "B.Cu")
	)
	(gr_line
		(start 4.966716 -126.498858)
		(end 4.96824 -126.500382)
		(stroke
			(width 0.047498)
			(type default)
		)
		(layer "B.Cu")
	)
	(gr_arc
		(start 4.96824 -126.500382)
		(mid 5.125908 -126.469035)
		(end 5.259578 -126.379732)
		(stroke
			(width 0.047498)
			(type default)
		)
		(layer "B.Cu")
	)
	(gr_line
		(start 4.971796 -354.498402)
		(end 4.97332 -354.499926)
		(stroke
			(width 0.047498)
			(type default)
		)
		(layer "B.Cu")
	)
	(gr_arc
		(start 4.97332 -354.499926)
		(mid 5.161084 -354.462517)
		(end 5.320284 -354.356162)
		(stroke
			(width 0.047498)
			(type default)
		)
		(layer "B.Cu")
	)
	(gr_line
		(start 4.981702 -164.498782)
		(end 4.983226 -164.500306)
		(stroke
			(width 0.047498)
			(type default)
		)
		(layer "B.Cu")
	)
	(gr_arc
		(start 4.983226 -164.500306)
		(mid 5.123566 -164.472353)
		(end 5.24256 -164.392864)
		(stroke
			(width 0.047498)
			(type default)
		)
		(layer "B.Cu")
	)
	(gr_line
		(start 4.986528 -160.49879)
		(end 4.988052 -160.500314)
		(stroke
			(width 0.047498)
			(type default)
		)
		(layer "B.Cu")
	)
	(gr_arc
		(start 4.988052 -160.500314)
		(mid 5.119742 -160.47408)
		(end 5.231384 -160.399476)
		(stroke
			(width 0.047498)
			(type default)
		)
		(layer "B.Cu")
	)
	(gr_line
		(start 4.98856 -125.49886)
		(end 4.990084 -125.500384)
		(stroke
			(width 0.047498)
			(type default)
		)
		(layer "B.Cu")
	)
	(gr_line
		(start 4.994656 -100.498402)
		(end 4.99618 -100.499926)
		(stroke
			(width 0.047498)
			(type default)
		)
		(layer "B.Cu")
	)
	(gr_arc
		(start 4.99618 -100.499926)
		(mid 5.115641 -100.476164)
		(end 5.216906 -100.408486)
		(stroke
			(width 0.047498)
			(type default)
		)
		(layer "B.Cu")
	)
	(gr_line
		(start 4.999482 -159.498792)
		(end 5.001006 -159.500316)
		(stroke
			(width 0.047498)
			(type default)
		)
		(layer "B.Cu")
	)
	(gr_line
		(start 5.010658 -114.498882)
		(end 5.012182 -114.500406)
		(stroke
			(width 0.047498)
			(type default)
		)
		(layer "B.Cu")
	)
	(gr_arc
		(start 5.012182 -114.500406)
		(mid 5.12931 -114.477108)
		(end 5.22859 -114.410744)
		(stroke
			(width 0.047498)
			(type default)
		)
		(layer "B.Cu")
	)
	(gr_line
		(start 5.025898 -109.498892)
		(end 5.027422 -109.500416)
		(stroke
			(width 0.047498)
			(type default)
		)
		(layer "B.Cu")
	)
	(gr_line
		(start 5.0292 -122.45848)
		(end 5.203444 -122.283982)
		(stroke
			(width 0.047498)
			(type default)
		)
		(layer "B.Cu")
	)
	(gr_line
		(start 5.036566 -103.498396)
		(end 5.03809 -103.49992)
		(stroke
			(width 0.047498)
			(type default)
		)
		(layer "B.Cu")
	)
	(gr_arc
		(start 5.044948 -168.500298)
		(mid 5.247987 -168.459877)
		(end 5.420106 -168.34485)
		(stroke
			(width 0.047498)
			(type default)
		)
		(layer "B.Cu")
	)
	(gr_arc
		(start 5.051806 -99.540822)
		(mid 5.006464 -99.510568)
		(end 4.953 -99.499928)
		(stroke
			(width 0.047498)
			(type default)
		)
		(layer "B.Cu")
	)
	(gr_line
		(start 5.051806 -99.540822)
		(end 5.274564 -99.76358)
		(stroke
			(width 0.047498)
			(type default)
		)
		(layer "B.Cu")
	)
	(gr_arc
		(start 5.056632 -117.553994)
		(mid 4.997447 -117.514355)
		(end 4.9276 -117.5004)
		(stroke
			(width 0.047498)
			(type default)
		)
		(layer "B.Cu")
	)
	(gr_line
		(start 5.056632 -117.553994)
		(end 5.241036 -117.738144)
		(stroke
			(width 0.047498)
			(type default)
		)
		(layer "B.Cu")
	)
	(gr_arc
		(start 5.066538 -104.499918)
		(mid 5.253075 -104.462829)
		(end 5.411216 -104.35717)
		(stroke
			(width 0.047498)
			(type default)
		)
		(layer "B.Cu")
	)
	(gr_arc
		(start 5.068062 -350.499934)
		(mid 5.231652 -350.467394)
		(end 5.370322 -350.374712)
		(stroke
			(width 0.047498)
			(type default)
		)
		(layer "B.Cu")
	)
	(gr_arc
		(start 5.077714 -121.58345)
		(mid 4.985519 -121.52194)
		(end 4.8768 -121.500392)
		(stroke
			(width 0.047498)
			(type default)
		)
		(layer "B.Cu")
	)
	(gr_line
		(start 5.077714 -121.58345)
		(end 5.207762 -121.713752)
		(stroke
			(width 0.047498)
			(type default)
		)
		(layer "B.Cu")
	)
	(gr_line
		(start 5.085588 -118.40337)
		(end 5.209794 -118.279164)
		(stroke
			(width 0.047498)
			(type default)
		)
		(layer "B.Cu")
	)
	(gr_arc
		(start 5.1308 -171.6278)
		(mid 4.989558 -171.533425)
		(end 4.822952 -171.500292)
		(stroke
			(width 0.047498)
			(type default)
		)
		(layer "B.Cu")
	)
	(gr_line
		(start 5.1308 -171.6278)
		(end 5.2451 -171.742354)
		(stroke
			(width 0.047498)
			(type default)
		)
		(layer "B.Cu")
	)
	(gr_line
		(start 5.14731 -398.273524)
		(end 5.147564 -398.273524)
		(stroke
			(width 0.047498)
			(type default)
		)
		(layer "B.Cu")
	)
	(gr_line
		(start 5.14985 -134.39775)
		(end 5.244592 -134.302754)
		(stroke
			(width 0.047498)
			(type default)
		)
		(layer "B.Cu")
	)
	(gr_line
		(start 5.16382 -130.36042)
		(end 5.310124 -130.214116)
		(stroke
			(width 0.047498)
			(type default)
		)
		(layer "B.Cu")
	)
	(gr_arc
		(start 5.199888 -147.723098)
		(mid 4.953181 -147.558254)
		(end 4.66217 -147.50034)
		(stroke
			(width 0.047498)
			(type default)
		)
		(layer "B.Cu")
	)
	(gr_arc
		(start 5.199888 -147.723098)
		(mid 5.318865 -147.802622)
		(end 5.459222 -147.83054)
		(stroke
			(width 0.047498)
			(type default)
		)
		(layer "B.Cu")
	)
	(gr_arc
		(start 5.207762 -121.713752)
		(mid 5.337251 -121.800201)
		(end 5.489956 -121.830592)
		(stroke
			(width 0.047498)
			(type default)
		)
		(layer "B.Cu")
	)
	(gr_arc
		(start 5.216398 -155.735528)
		(mid 4.955823 -155.561417)
		(end 4.648454 -155.500324)
		(stroke
			(width 0.047498)
			(type default)
		)
		(layer "B.Cu")
	)
	(gr_arc
		(start 5.216398 -155.735528)
		(mid 5.321632 -155.805841)
		(end 5.44576 -155.830524)
		(stroke
			(width 0.047498)
			(type default)
		)
		(layer "B.Cu")
	)
	(gr_arc
		(start 5.216906 -413.66186)
		(mid 5.038023 -413.542334)
		(end 4.827016 -413.500316)
		(stroke
			(width 0.047498)
			(type default)
		)
		(layer "B.Cu")
	)
	(gr_arc
		(start 5.216906 -413.66186)
		(mid 5.397871 -413.785589)
		(end 5.611368 -413.835342)
		(stroke
			(width 0.047498)
			(type default)
		)
		(layer "B.Cu")
	)
	(gr_line
		(start 5.216906 -100.408486)
		(end 5.384546 -100.2411)
		(stroke
			(width 0.047498)
			(type default)
		)
		(layer "B.Cu")
	)
	(gr_arc
		(start 5.221986 -397.715232)
		(mid 4.984019 -397.556228)
		(end 4.703318 -397.500348)
		(stroke
			(width 0.047498)
			(type default)
		)
		(layer "B.Cu")
	)
	(gr_line
		(start 5.221986 -397.715232)
		(end 5.249164 -397.74241)
		(stroke
			(width 0.047498)
			(type default)
		)
		(layer "B.Cu")
	)
	(gr_arc
		(start 5.228082 -113.57991)
		(mid 5.139969 -113.52108)
		(end 5.036058 -113.500408)
		(stroke
			(width 0.047498)
			(type default)
		)
		(layer "B.Cu")
	)
	(gr_line
		(start 5.228082 -113.57991)
		(end 5.355082 -113.70691)
		(stroke
			(width 0.047498)
			(type default)
		)
		(layer "B.Cu")
	)
	(gr_line
		(start 5.22859 -114.410744)
		(end 5.36829 -114.271044)
		(stroke
			(width 0.047498)
			(type default)
		)
		(layer "B.Cu")
	)
	(gr_arc
		(start 5.234178 -109.586014)
		(mid 5.1393 -109.522693)
		(end 5.027422 -109.500416)
		(stroke
			(width 0.047498)
			(type default)
		)
		(layer "B.Cu")
	)
	(gr_line
		(start 5.234178 -109.586014)
		(end 5.373878 -109.725714)
		(stroke
			(width 0.047498)
			(type default)
		)
		(layer "B.Cu")
	)
	(gr_arc
		(start 5.238496 -409.716224)
		(mid 4.999364 -409.556441)
		(end 4.717288 -409.500324)
		(stroke
			(width 0.047498)
			(type default)
		)
		(layer "B.Cu")
	)
	(gr_line
		(start 5.238496 -409.716224)
		(end 5.23875 -409.716224)
		(stroke
			(width 0.047498)
			(type default)
		)
		(layer "B.Cu")
	)
	(gr_arc
		(start 5.23875 -409.716224)
		(mid 5.36519 -409.800745)
		(end 5.51434 -409.830524)
		(stroke
			(width 0.047498)
			(type default)
		)
		(layer "B.Cu")
	)
	(gr_arc
		(start 5.239004 -417.716462)
		(mid 4.999639 -417.556523)
		(end 4.717288 -417.500308)
		(stroke
			(width 0.047498)
			(type default)
		)
		(layer "B.Cu")
	)
	(gr_arc
		(start 5.239004 -417.716462)
		(mid 5.365333 -417.800851)
		(end 5.51434 -417.830508)
		(stroke
			(width 0.047498)
			(type default)
		)
		(layer "B.Cu")
	)
	(gr_arc
		(start 5.241036 -117.738144)
		(mid 5.343481 -117.806551)
		(end 5.464302 -117.8306)
		(stroke
			(width 0.047498)
			(type default)
		)
		(layer "B.Cu")
	)
	(gr_arc
		(start 5.24256 -164.392864)
		(mid 5.306435 -164.34786)
		(end 5.364734 -164.295836)
		(stroke
			(width 0.047498)
			(type default)
		)
		(layer "B.Cu")
	)
	(gr_arc
		(start 5.2451 -171.742354)
		(mid 5.348038 -171.810963)
		(end 5.469382 -171.835064)
		(stroke
			(width 0.047498)
			(type default)
		)
		(layer "B.Cu")
	)
	(gr_arc
		(start 5.245354 -163.728908)
		(mid 4.992121 -163.559703)
		(end 4.693412 -163.500308)
		(stroke
			(width 0.047498)
			(type default)
		)
		(layer "B.Cu")
	)
	(gr_arc
		(start 5.245354 -163.728908)
		(mid 5.357937 -163.804103)
		(end 5.490718 -163.830508)
		(stroke
			(width 0.047498)
			(type default)
		)
		(layer "B.Cu")
	)
	(gr_line
		(start 5.246116 -406.220422)
		(end 5.24637 -406.220422)
		(stroke
			(width 0.047498)
			(type default)
		)
		(layer "B.Cu")
	)
	(gr_arc
		(start 5.249164 -397.74241)
		(mid 5.343674 -397.805559)
		(end 5.455158 -397.827754)
		(stroke
			(width 0.047498)
			(type default)
		)
		(layer "B.Cu")
	)
	(gr_arc
		(start 5.255006 -383.631186)
		(mid 5.110162 -383.534359)
		(end 4.939284 -383.500376)
		(stroke
			(width 0.047498)
			(type default)
		)
		(layer "B.Cu")
	)
	(gr_arc
		(start 5.255006 -383.631186)
		(mid 5.449388 -383.761068)
		(end 5.678678 -383.8067)
		(stroke
			(width 0.047498)
			(type default)
		)
		(layer "B.Cu")
	)
	(gr_arc
		(start 5.260594 -125.612398)
		(mid 5.136483 -125.52947)
		(end 4.990084 -125.500384)
		(stroke
			(width 0.047498)
			(type default)
		)
		(layer "B.Cu")
	)
	(gr_line
		(start 5.260594 -125.612398)
		(end 5.298694 -125.650498)
		(stroke
			(width 0.047498)
			(type default)
		)
		(layer "B.Cu")
	)
	(gr_arc
		(start 5.263134 -371.73408)
		(mid 5.004307 -371.561137)
		(end 4.699 -371.5004)
		(stroke
			(width 0.047498)
			(type default)
		)
		(layer "B.Cu")
	)
	(gr_arc
		(start 5.263134 -371.73408)
		(mid 5.369987 -371.805517)
		(end 5.496052 -371.8306)
		(stroke
			(width 0.047498)
			(type default)
		)
		(layer "B.Cu")
	)
	(gr_arc
		(start 5.267198 -159.610552)
		(mid 5.145068 -159.528947)
		(end 5.001006 -159.500316)
		(stroke
			(width 0.047498)
			(type default)
		)
		(layer "B.Cu")
	)
	(gr_arc
		(start 5.267198 -159.610552)
		(mid 5.510883 -159.77335)
		(end 5.798312 -159.830516)
		(stroke
			(width 0.047498)
			(type default)
		)
		(layer "B.Cu")
	)
	(gr_arc
		(start 5.274564 -99.76358)
		(mid 5.348331 -99.81287)
		(end 5.435346 -99.830128)
		(stroke
			(width 0.047498)
			(type default)
		)
		(layer "B.Cu")
	)
	(gr_arc
		(start 5.275834 -133.627876)
		(mid 5.134592 -133.533501)
		(end 4.967986 -133.500368)
		(stroke
			(width 0.047498)
			(type default)
		)
		(layer "B.Cu")
	)
	(gr_arc
		(start 5.275834 -133.627876)
		(mid 5.500523 -133.777952)
		(end 5.765546 -133.830568)
		(stroke
			(width 0.047498)
			(type default)
		)
		(layer "B.Cu")
	)
	(gr_line
		(start 5.2832 -414.3502)
		(end 5.355844 -414.277556)
		(stroke
			(width 0.047498)
			(type default)
		)
		(layer "B.Cu")
	)
	(gr_line
		(start 5.285994 -110.353602)
		(end 5.349494 -110.290102)
		(stroke
			(width 0.047498)
			(type default)
		)
		(layer "B.Cu")
	)
	(gr_arc
		(start 5.295646 -103.6066)
		(mid 5.177478 -103.527643)
		(end 5.03809 -103.49992)
		(stroke
			(width 0.047498)
			(type default)
		)
		(layer "B.Cu")
	)
	(gr_line
		(start 5.295646 -103.6066)
		(end 5.448046 -103.759)
		(stroke
			(width 0.047498)
			(type default)
		)
		(layer "B.Cu")
	)
	(gr_arc
		(start 5.298694 -125.650498)
		(mid 5.498215 -125.783772)
		(end 5.733542 -125.830584)
		(stroke
			(width 0.047498)
			(type default)
		)
		(layer "B.Cu")
	)
	(gr_arc
		(start 5.299202 -367.682272)
		(mid 5.097711 -367.54764)
		(end 4.860036 -367.500408)
		(stroke
			(width 0.047498)
			(type default)
		)
		(layer "B.Cu")
	)
	(gr_arc
		(start 5.299202 -367.682272)
		(mid 5.463516 -367.792077)
		(end 5.657342 -367.830608)
		(stroke
			(width 0.047498)
			(type default)
		)
		(layer "B.Cu")
	)
	(gr_arc
		(start 5.319268 -129.603754)
		(mid 5.204713 -129.527211)
		(end 5.069586 -129.500376)
		(stroke
			(width 0.047498)
			(type default)
		)
		(layer "B.Cu")
	)
	(gr_line
		(start 5.319268 -129.603754)
		(end 5.390388 -129.674874)
		(stroke
			(width 0.047498)
			(type default)
		)
		(layer "B.Cu")
	)
	(gr_arc
		(start 5.319776 -405.71928)
		(mid 5.077264 -405.557239)
		(end 4.791202 -405.500332)
		(stroke
			(width 0.047498)
			(type default)
		)
		(layer "B.Cu")
	)
	(gr_arc
		(start 5.319776 -405.71928)
		(mid 5.384446 -405.762521)
		(end 5.460746 -405.7777)
		(stroke
			(width 0.047498)
			(type default)
		)
		(layer "B.Cu")
	)
	(gr_arc
		(start 5.325364 -375.687082)
		(mid 5.118629 -375.548946)
		(end 4.874768 -375.500392)
		(stroke
			(width 0.047498)
			(type default)
		)
		(layer "B.Cu")
	)
	(gr_line
		(start 5.325364 -375.687082)
		(end 5.362194 -375.723912)
		(stroke
			(width 0.047498)
			(type default)
		)
		(layer "B.Cu")
	)
	(gr_line
		(start 5.327396 -376.32005)
		(end 5.460746 -376.1867)
		(stroke
			(width 0.047498)
			(type default)
		)
		(layer "B.Cu")
	)
	(gr_line
		(start 5.33019 -384.311398)
		(end 5.39877 -384.242818)
		(stroke
			(width 0.047498)
			(type default)
		)
		(layer "B.Cu")
	)
	(gr_arc
		(start 5.331714 -95.63354)
		(mid 5.1762 -95.53734)
		(end 4.996434 -95.503746)
		(stroke
			(width 0.047498)
			(type default)
		)
		(layer "B.Cu")
	)
	(gr_arc
		(start 5.331714 -95.63354)
		(mid 5.56858 -95.779271)
		(end 5.842 -95.830136)
		(stroke
			(width 0.047498)
			(type default)
		)
		(layer "B.Cu")
	)
	(gr_arc
		(start 5.332984 -359.675938)
		(mid 5.138602 -359.546056)
		(end 4.909312 -359.500424)
		(stroke
			(width 0.047498)
			(type default)
		)
		(layer "B.Cu")
	)
	(gr_arc
		(start 5.332984 -359.675938)
		(mid 5.530742 -359.808092)
		(end 5.764022 -359.8545)
		(stroke
			(width 0.047498)
			(type default)
		)
		(layer "B.Cu")
	)
	(gr_arc
		(start 5.334 -379.6284)
		(mid 5.192175 -379.533636)
		(end 5.024882 -379.500384)
		(stroke
			(width 0.047498)
			(type default)
		)
		(layer "B.Cu")
	)
	(gr_line
		(start 5.334 -379.6284)
		(end 5.346446 -379.640592)
		(stroke
			(width 0.047498)
			(type default)
		)
		(layer "B.Cu")
	)
	(gr_arc
		(start 5.346446 -379.640592)
		(mid 5.515625 -379.753779)
		(end 5.715254 -379.7935)
		(stroke
			(width 0.047498)
			(type default)
		)
		(layer "B.Cu")
	)
	(gr_arc
		(start 5.355082 -113.70691)
		(mid 5.396356 -113.743534)
		(end 5.441696 -113.774982)
		(stroke
			(width 0.047498)
			(type default)
		)
		(layer "B.Cu")
	)
	(gr_arc
		(start 5.359146 -349.7707)
		(mid 5.059168 -349.570318)
		(end 4.70535 -349.499936)
		(stroke
			(width 0.047498)
			(type default)
		)
		(layer "B.Cu")
	)
	(gr_arc
		(start 5.359146 -349.7707)
		(mid 5.424831 -349.820554)
		(end 5.501386 -349.851218)
		(stroke
			(width 0.047498)
			(type default)
		)
		(layer "B.Cu")
	)
	(gr_arc
		(start 5.359146 -167.7035)
		(mid 5.134128 -167.55309)
		(end 4.868672 -167.5003)
		(stroke
			(width 0.047498)
			(type default)
		)
		(layer "B.Cu")
	)
	(gr_arc
		(start 5.359146 -167.7035)
		(mid 5.499805 -167.797485)
		(end 5.665724 -167.8305)
		(stroke
			(width 0.047498)
			(type default)
		)
		(layer "B.Cu")
	)
	(gr_arc
		(start 5.362194 -375.723912)
		(mid 5.423354 -375.770175)
		(end 5.494782 -375.79808)
		(stroke
			(width 0.047498)
			(type default)
		)
		(layer "B.Cu")
	)
	(gr_line
		(start 5.370322 -350.374712)
		(end 5.404358 -350.340676)
		(stroke
			(width 0.047498)
			(type default)
		)
		(layer "B.Cu")
	)
	(gr_arc
		(start 5.373878 -109.725714)
		(mid 5.490065 -109.803347)
		(end 5.627116 -109.830616)
		(stroke
			(width 0.047498)
			(type default)
		)
		(layer "B.Cu")
	)
	(gr_arc
		(start 5.381498 -345.727274)
		(mid 5.129663 -345.559003)
		(end 4.832604 -345.499944)
		(stroke
			(width 0.047498)
			(type default)
		)
		(layer "B.Cu")
	)
	(gr_arc
		(start 5.381498 -345.727274)
		(mid 5.49548 -345.80339)
		(end 5.62991 -345.830144)
		(stroke
			(width 0.047498)
			(type default)
		)
		(layer "B.Cu")
	)
	(gr_line
		(start 5.390388 -129.674874)
		(end 5.449062 -129.733802)
		(stroke
			(width 0.047498)
			(type default)
		)
		(layer "B.Cu")
	)
	(gr_arc
		(start 5.399278 -363.688122)
		(mid 5.191377 -363.549207)
		(end 4.946142 -363.500416)
		(stroke
			(width 0.047498)
			(type default)
		)
		(layer "B.Cu")
	)
	(gr_arc
		(start 5.399278 -363.688122)
		(mid 5.597034 -363.820282)
		(end 5.830316 -363.866684)
		(stroke
			(width 0.047498)
			(type default)
		)
		(layer "B.Cu")
	)
	(gr_line
		(start 5.411216 -104.35717)
		(end 5.462016 -104.30637)
		(stroke
			(width 0.047498)
			(type default)
		)
		(layer "B.Cu")
	)
	(gr_arc
		(start 5.415788 -398.162272)
		(mid 5.270623 -398.191241)
		(end 5.147564 -398.273524)
		(stroke
			(width 0.047498)
			(type default)
		)
		(layer "B.Cu")
	)
	(gr_line
		(start 5.420106 -168.34485)
		(end 5.512054 -168.252648)
		(stroke
			(width 0.047498)
			(type default)
		)
		(layer "B.Cu")
	)
	(gr_arc
		(start 5.421884 -96.23171)
		(mid 5.366309 -96.269215)
		(end 5.315966 -96.313498)
		(stroke
			(width 0.047498)
			(type default)
		)
		(layer "B.Cu")
	)
	(gr_arc
		(start 5.423662 -421.742616)
		(mid 5.155279 -421.563288)
		(end 4.8387 -421.5003)
		(stroke
			(width 0.047498)
			(type default)
		)
		(layer "B.Cu")
	)
	(gr_arc
		(start 5.423662 -421.742616)
		(mid 5.520963 -421.807655)
		(end 5.635752 -421.8305)
		(stroke
			(width 0.047498)
			(type default)
		)
		(layer "B.Cu")
	)
	(gr_arc
		(start 5.441696 -113.774982)
		(mid 5.557446 -113.825316)
		(end 5.682488 -113.842546)
		(stroke
			(width 0.047498)
			(type default)
		)
		(layer "B.Cu")
	)
	(gr_arc
		(start 5.448046 -103.759)
		(mid 5.549307 -103.826702)
		(end 5.668772 -103.85044)
		(stroke
			(width 0.047498)
			(type default)
		)
		(layer "B.Cu")
	)
	(gr_arc
		(start 5.449062 -129.733802)
		(mid 5.532616 -129.789643)
		(end 5.63118 -129.80924)
		(stroke
			(width 0.047498)
			(type default)
		)
		(layer "B.Cu")
	)
	(gr_arc
		(start 5.455158 -397.827754)
		(mid 5.477723 -397.829809)
		(end 5.50037 -397.830548)
		(stroke
			(width 0.047498)
			(type default)
		)
		(layer "B.Cu")
	)
	(gr_arc
		(start 5.463032 -156.160724)
		(mid 5.322284 -156.18872)
		(end 5.202936 -156.26842)
		(stroke
			(width 0.047498)
			(type default)
		)
		(layer "B.Cu")
	)
	(gr_arc
		(start 5.470144 -171.835318)
		(mid 5.469763 -171.835191)
		(end 5.469382 -171.835064)
		(stroke
			(width 0.047498)
			(type default)
		)
		(layer "B.Cu")
	)
	(gr_arc
		(start 5.490464 -130.13944)
		(mid 5.392874 -130.158852)
		(end 5.310124 -130.214116)
		(stroke
			(width 0.047498)
			(type default)
		)
		(layer "B.Cu")
	)
	(gr_arc
		(start 5.494782 -375.79808)
		(mid 5.526818 -375.803765)
		(end 5.559298 -375.8057)
		(stroke
			(width 0.047498)
			(type default)
		)
		(layer "B.Cu")
	)
	(gr_arc
		(start 5.495544 -118.1608)
		(mid 5.340896 -118.191561)
		(end 5.209794 -118.279164)
		(stroke
			(width 0.047498)
			(type default)
		)
		(layer "B.Cu")
	)
	(gr_arc
		(start 5.496814 -418.160708)
		(mid 5.372979 -418.18534)
		(end 5.26796 -418.25545)
		(stroke
			(width 0.047498)
			(type default)
		)
		(layer "B.Cu")
	)
	(gr_arc
		(start 5.500878 -122.160792)
		(mid 5.339912 -122.19281)
		(end 5.203444 -122.283982)
		(stroke
			(width 0.047498)
			(type default)
		)
		(layer "B.Cu")
	)
	(gr_arc
		(start 5.501386 -349.851218)
		(mid 5.506076 -349.852398)
		(end 5.510784 -349.853504)
		(stroke
			(width 0.047498)
			(type default)
		)
		(layer "B.Cu")
	)
	(gr_arc
		(start 5.510022 -148.16074)
		(mid 5.342459 -148.194095)
		(end 5.200396 -148.28901)
		(stroke
			(width 0.047498)
			(type default)
		)
		(layer "B.Cu")
	)
	(gr_arc
		(start 5.510784 -349.853504)
		(mid 5.543604 -349.858986)
		(end 5.576824 -349.86087)
		(stroke
			(width 0.047498)
			(type default)
		)
		(layer "B.Cu")
	)
	(gr_arc
		(start 5.512308 -353.673664)
		(mid 5.319907 -353.545106)
		(end 5.092954 -353.499928)
		(stroke
			(width 0.047498)
			(type default)
		)
		(layer "B.Cu")
	)
	(gr_line
		(start 5.512308 -353.673664)
		(end 5.545582 -353.706938)
		(stroke
			(width 0.047498)
			(type default)
		)
		(layer "B.Cu")
	)
	(gr_arc
		(start 5.517642 -406.1079)
		(mid 5.370824 -406.137198)
		(end 5.24637 -406.220422)
		(stroke
			(width 0.047498)
			(type default)
		)
		(layer "B.Cu")
	)
	(gr_arc
		(start 5.520944 -372.1608)
		(mid 5.368921 -372.191039)
		(end 5.24002 -372.277132)
		(stroke
			(width 0.047498)
			(type default)
		)
		(layer "B.Cu")
	)
	(gr_arc
		(start 5.523738 -410.160724)
		(mid 5.36841 -410.191621)
		(end 5.236718 -410.279596)
		(stroke
			(width 0.047498)
			(type default)
		)
		(layer "B.Cu")
	)
	(gr_arc
		(start 5.528564 -422.1607)
		(mid 5.366918 -422.192853)
		(end 5.22986 -422.284398)
		(stroke
			(width 0.047498)
			(type default)
		)
		(layer "B.Cu")
	)
	(gr_line
		(start 5.528564 -422.1607)
		(end 5.715 -422.1607)
		(stroke
			(width 0.047498)
			(type default)
		)
		(layer "B.Cu")
	)
	(gr_arc
		(start 5.545074 -364.196884)
		(mid 5.349898 -364.235726)
		(end 5.184394 -364.346236)
		(stroke
			(width 0.047498)
			(type default)
		)
		(layer "B.Cu")
	)
	(gr_arc
		(start 5.545582 -353.706938)
		(mid 5.703744 -353.820779)
		(end 5.889752 -353.878896)
		(stroke
			(width 0.047498)
			(type default)
		)
		(layer "B.Cu")
	)
	(gr_arc
		(start 5.553456 -360.1847)
		(mid 5.350416 -360.225105)
		(end 5.178298 -360.340148)
		(stroke
			(width 0.047498)
			(type default)
		)
		(layer "B.Cu")
	)
	(gr_line
		(start 5.553456 -360.1847)
		(end 5.841746 -360.1847)
		(stroke
			(width 0.047498)
			(type default)
		)
		(layer "B.Cu")
	)
	(gr_arc
		(start 5.579618 -100.160328)
		(mid 5.474042 -100.181297)
		(end 5.384546 -100.2411)
		(stroke
			(width 0.047498)
			(type default)
		)
		(layer "B.Cu")
	)
	(gr_arc
		(start 5.583428 -376.1359)
		(mid 5.517039 -376.149106)
		(end 5.460746 -376.1867)
		(stroke
			(width 0.047498)
			(type default)
		)
		(layer "B.Cu")
	)
	(gr_arc
		(start 5.587746 -134.160768)
		(mid 5.402037 -134.197614)
		(end 5.244592 -134.302754)
		(stroke
			(width 0.047498)
			(type default)
		)
		(layer "B.Cu")
	)
	(gr_arc
		(start 5.605526 -114.172746)
		(mid 5.477126 -114.198298)
		(end 5.36829 -114.271044)
		(stroke
			(width 0.047498)
			(type default)
		)
		(layer "B.Cu")
	)
	(gr_line
		(start 5.611368 -413.835342)
		(end 5.632196 -413.836358)
		(stroke
			(width 0.047498)
			(type default)
		)
		(layer "B.Cu")
	)
	(gr_arc
		(start 5.621782 -346.160344)
		(mid 5.451874 -346.194141)
		(end 5.307838 -346.290392)
		(stroke
			(width 0.047498)
			(type default)
		)
		(layer "B.Cu")
	)
	(gr_arc
		(start 5.62864 -414.164526)
		(mid 5.480991 -414.193895)
		(end 5.355844 -414.277556)
		(stroke
			(width 0.047498)
			(type default)
		)
		(layer "B.Cu")
	)
	(gr_line
		(start 5.62864 -414.164526)
		(end 6.050534 -414.164526)
		(stroke
			(width 0.047498)
			(type default)
		)
		(layer "B.Cu")
	)
	(gr_arc
		(start 5.632196 -413.836358)
		(mid 5.635498 -413.836494)
		(end 5.6388 -413.836612)
		(stroke
			(width 0.047498)
			(type default)
		)
		(layer "B.Cu")
	)
	(gr_arc
		(start 5.632196 -368.165126)
		(mid 5.470823 -368.214336)
		(end 5.333746 -368.3127)
		(stroke
			(width 0.047498)
			(type default)
		)
		(layer "B.Cu")
	)
	(gr_line
		(start 5.6388 -413.836612)
		(end 6.088888 -413.836612)
		(stroke
			(width 0.047498)
			(type default)
		)
		(layer "B.Cu")
	)
	(gr_arc
		(start 5.654548 -384.1369)
		(mid 5.516133 -384.164432)
		(end 5.39877 -384.242818)
		(stroke
			(width 0.047498)
			(type default)
		)
		(layer "B.Cu")
	)
	(gr_arc
		(start 5.659374 -354.2157)
		(mid 5.475857 -354.252204)
		(end 5.320284 -354.356162)
		(stroke
			(width 0.047498)
			(type default)
		)
		(layer "B.Cu")
	)
	(gr_line
		(start 5.659374 -354.2157)
		(end 5.889752 -354.2157)
		(stroke
			(width 0.047498)
			(type default)
		)
		(layer "B.Cu")
	)
	(gr_arc
		(start 5.66166 -110.160816)
		(mid 5.492715 -110.194404)
		(end 5.349494 -110.290102)
		(stroke
			(width 0.047498)
			(type default)
		)
		(layer "B.Cu")
	)
	(gr_arc
		(start 5.68579 -96.160336)
		(mid 5.549081 -96.178451)
		(end 5.421884 -96.23171)
		(stroke
			(width 0.047498)
			(type default)
		)
		(layer "B.Cu")
	)
	(gr_arc
		(start 5.700522 -368.160808)
		(mid 5.666288 -368.161838)
		(end 5.632196 -368.165126)
		(stroke
			(width 0.047498)
			(type default)
		)
		(layer "B.Cu")
	)
	(gr_line
		(start 5.715 -421.8305)
		(end 5.715 -421.830754)
		(stroke
			(width 0.047498)
			(type default)
		)
		(layer "B.Cu")
	)
	(gr_arc
		(start 5.734558 -168.1607)
		(mid 5.614169 -168.184553)
		(end 5.512054 -168.252648)
		(stroke
			(width 0.047498)
			(type default)
		)
		(layer "B.Cu")
	)
	(gr_arc
		(start 5.765546 -350.19107)
		(mid 5.570067 -350.229941)
		(end 5.404358 -350.340676)
		(stroke
			(width 0.047498)
			(type default)
		)
		(layer "B.Cu")
	)
	(gr_arc
		(start 5.765546 -104.18064)
		(mid 5.601275 -104.213315)
		(end 5.462016 -104.30637)
		(stroke
			(width 0.047498)
			(type default)
		)
		(layer "B.Cu")
	)
	(gr_arc
		(start 5.788152 -126.160784)
		(mid 5.502088 -126.217686)
		(end 5.259578 -126.379732)
		(stroke
			(width 0.047498)
			(type default)
		)
		(layer "B.Cu")
	)
	(gr_line
		(start 5.790946 -376.1359)
		(end 6.121146 -376.1359)
		(stroke
			(width 0.047498)
			(type default)
		)
		(layer "B.Cu")
	)
	(gr_arc
		(start 5.808218 -164.160708)
		(mid 5.576425 -164.19528)
		(end 5.364734 -164.295836)
		(stroke
			(width 0.047498)
			(type default)
		)
		(layer "B.Cu")
	)
	(gr_arc
		(start 5.808218 -160.160716)
		(mid 5.49605 -160.222716)
		(end 5.231384 -160.399476)
		(stroke
			(width 0.047498)
			(type default)
		)
		(layer "B.Cu")
	)
	(gr_line
		(start 5.841746 -359.8545)
		(end 5.841746 -359.854754)
		(stroke
			(width 0.047498)
			(type default)
		)
		(layer "B.Cu")
	)
	(gr_line
		(start 6.121146 -375.8057)
		(end 6.121146 -375.805954)
		(stroke
			(width 0.047498)
			(type default)
		)
		(layer "B.Cu")
	)
	(gr_arc
		(start 6.197346 -133.830568)
		(mid 6.42168 -133.785931)
		(end 6.611874 -133.658864)
		(stroke
			(width 0.047498)
			(type default)
		)
		(layer "B.Cu")
	)
	(gr_arc
		(start 6.330188 -130.222244)
		(mid 6.238474 -130.160963)
		(end 6.13029 -130.13944)
		(stroke
			(width 0.047498)
			(type default)
		)
		(layer "B.Cu")
	)
	(gr_arc
		(start 6.433566 -130.30073)
		(mid 6.384546 -130.257973)
		(end 6.330188 -130.222244)
		(stroke
			(width 0.047498)
			(type default)
		)
		(layer "B.Cu")
	)
	(gr_line
		(start 6.46811 -418.254942)
		(end 6.46811 -418.255196)
		(stroke
			(width 0.047498)
			(type default)
		)
		(layer "B.Cu")
	)
	(gr_line
		(start 6.478778 -348.49943)
		(end 6.51764 -348.460568)
		(stroke
			(width 0.047498)
			(type default)
		)
		(layer "B.Cu")
	)
	(gr_arc
		(start 6.491732 -347.585538)
		(mid 6.764297 -347.767713)
		(end 7.085838 -347.831664)
		(stroke
			(width 0.047498)
			(type default)
		)
		(layer "B.Cu")
	)
	(gr_line
		(start 6.518148 -130.385312)
		(end 6.554978 -130.422142)
		(stroke
			(width 0.047498)
			(type default)
		)
		(layer "B.Cu")
	)
	(gr_arc
		(start 6.54431 -134.230872)
		(mid 6.466697 -134.179013)
		(end 6.375146 -134.160768)
		(stroke
			(width 0.047498)
			(type default)
		)
		(layer "B.Cu")
	)
	(gr_line
		(start 6.54431 -134.230872)
		(end 6.756146 -134.442708)
		(stroke
			(width 0.047498)
			(type default)
		)
		(layer "B.Cu")
	)
	(gr_line
		(start 6.607556 -121.587006)
		(end 6.679946 -121.514616)
		(stroke
			(width 0.047498)
			(type default)
		)
		(layer "B.Cu")
	)
	(gr_line
		(start 6.611874 -133.658864)
		(end 6.756146 -133.514592)
		(stroke
			(width 0.047498)
			(type default)
		)
		(layer "B.Cu")
	)
	(gr_line
		(start 6.666992 -117.57279)
		(end 6.727444 -117.512592)
		(stroke
			(width 0.047498)
			(type default)
		)
		(layer "B.Cu")
	)
	(gr_line
		(start 6.679946 -102.457504)
		(end 6.899148 -102.238302)
		(stroke
			(width 0.047498)
			(type default)
		)
		(layer "B.Cu")
	)
	(gr_arc
		(start 6.679946 -101.498654)
		(mid 6.771972 -101.720826)
		(end 6.994144 -101.812852)
		(stroke
			(width 0.047498)
			(type default)
		)
		(layer "B.Cu")
	)
	(gr_line
		(start 6.679946 -98.457766)
		(end 6.821678 -98.316034)
		(stroke
			(width 0.047498)
			(type default)
		)
		(layer "B.Cu")
	)
	(gr_line
		(start 6.679946 -97.498916)
		(end 6.839204 -97.658174)
		(stroke
			(width 0.047498)
			(type default)
		)
		(layer "B.Cu")
	)
	(gr_line
		(start 6.705346 -128.458214)
		(end 6.775196 -128.388364)
		(stroke
			(width 0.047498)
			(type default)
		)
		(layer "B.Cu")
	)
	(gr_arc
		(start 6.705346 -127.499364)
		(mid 6.797372 -127.721536)
		(end 7.019544 -127.813562)
		(stroke
			(width 0.047498)
			(type default)
		)
		(layer "B.Cu")
	)
	(gr_arc
		(start 6.705346 -107.660186)
		(mid 6.75742 -107.785902)
		(end 6.883146 -107.837986)
		(stroke
			(width 0.047498)
			(type default)
		)
		(layer "B.Cu")
	)
	(gr_line
		(start 6.705346 -107.523788)
		(end 6.705346 -107.660186)
		(stroke
			(width 0.047498)
			(type default)
		)
		(layer "B.Cu")
	)
	(gr_line
		(start 6.71068 -130.577844)
		(end 6.716014 -130.583178)
		(stroke
			(width 0.047498)
			(type default)
		)
		(layer "B.Cu")
	)
	(gr_arc
		(start 6.728968 -111.5949)
		(mid 7.042426 -111.757701)
		(end 7.391146 -111.813848)
		(stroke
			(width 0.047498)
			(type default)
		)
		(layer "B.Cu")
	)
	(gr_arc
		(start 6.730746 -118.1608)
		(mid 6.673546 -118.056357)
		(end 6.554724 -118.048278)
		(stroke
			(width 0.047498)
			(type default)
		)
		(layer "B.Cu")
	)
	(gr_line
		(start 6.730746 -118.1608)
		(end 6.730746 -118.4275)
		(stroke
			(width 0.047498)
			(type default)
		)
		(layer "B.Cu")
	)
	(gr_arc
		(start 6.73481 -122.159776)
		(mid 6.670651 -122.044643)
		(end 6.538976 -122.038618)
		(stroke
			(width 0.047498)
			(type default)
		)
		(layer "B.Cu")
	)
	(gr_line
		(start 6.73481 -122.159776)
		(end 6.73481 -122.376692)
		(stroke
			(width 0.047498)
			(type default)
		)
		(layer "B.Cu")
	)
	(gr_line
		(start 6.737096 -108.38688)
		(end 6.755892 -108.368338)
		(stroke
			(width 0.047498)
			(type default)
		)
		(layer "B.Cu")
	)
	(gr_arc
		(start 6.748272 -161.5313)
		(mid 7.079468 -161.752598)
		(end 7.47014 -161.830258)
		(stroke
			(width 0.047498)
			(type default)
		)
		(layer "B.Cu")
	)
	(gr_line
		(start 6.756908 -130.15722)
		(end 6.788404 -130.188462)
		(stroke
			(width 0.047498)
			(type default)
		)
		(layer "B.Cu")
	)
	(gr_arc
		(start 6.791198 -165.597078)
		(mid 7.098737 -165.802569)
		(end 7.461504 -165.8747)
		(stroke
			(width 0.047498)
			(type default)
		)
		(layer "B.Cu")
	)
	(gr_arc
		(start 6.832346 -115.5319)
		(mid 6.91485 -115.731082)
		(end 7.114032 -115.813586)
		(stroke
			(width 0.047498)
			(type default)
		)
		(layer "B.Cu")
	)
	(gr_arc
		(start 6.839204 -97.658174)
		(mid 7.010872 -97.772841)
		(end 7.213346 -97.813114)
		(stroke
			(width 0.047498)
			(type default)
		)
		(layer "B.Cu")
	)
	(gr_line
		(start 6.857746 -166.562278)
		(end 6.857746 -166.7637)
		(stroke
			(width 0.047498)
			(type default)
		)
		(layer "B.Cu")
	)
	(gr_line
		(start 6.883146 -107.837986)
		(end 6.906006 -107.837986)
		(stroke
			(width 0.047498)
			(type default)
		)
		(layer "B.Cu")
	)
	(gr_arc
		(start 6.889242 -399.34007)
		(mid 7.087492 -399.062118)
		(end 7.115048 -398.721834)
		(stroke
			(width 0.047498)
			(type default)
		)
		(layer "B.Cu")
	)
	(gr_line
		(start 6.897116 -376.806206)
		(end 6.897116 -376.80646)
		(stroke
			(width 0.047498)
			(type default)
		)
		(layer "B.Cu")
	)
	(gr_arc
		(start 6.984746 -166.2557)
		(mid 6.890727 -166.396351)
		(end 6.857746 -166.562278)
		(stroke
			(width 0.047498)
			(type default)
		)
		(layer "B.Cu")
	)
	(gr_arc
		(start 6.984746 -157.531562)
		(mid 7.315942 -157.75286)
		(end 7.706614 -157.83052)
		(stroke
			(width 0.047498)
			(type default)
		)
		(layer "B.Cu")
	)
	(gr_line
		(start 7.019544 -127.813562)
		(end 7.033006 -127.813562)
		(stroke
			(width 0.047498)
			(type default)
		)
		(layer "B.Cu")
	)
	(gr_arc
		(start 7.032498 -169.605452)
		(mid 7.130104 -169.841094)
		(end 7.365746 -169.9387)
		(stroke
			(width 0.047498)
			(type default)
		)
		(layer "B.Cu")
	)
	(gr_line
		(start 7.032498 -169.531538)
		(end 7.032498 -169.605452)
		(stroke
			(width 0.047498)
			(type default)
		)
		(layer "B.Cu")
	)
	(gr_line
		(start 7.04596 -132.539994)
		(end 7.049516 -132.545328)
		(stroke
			(width 0.047498)
			(type default)
		)
		(layer "B.Cu")
	)
	(gr_line
		(start 7.046468 -365.281972)
		(end 7.046722 -365.281972)
		(stroke
			(width 0.047498)
			(type default)
		)
		(layer "B.Cu")
	)
	(gr_arc
		(start 7.107428 -166.2049)
		(mid 7.041038 -166.218101)
		(end 6.984746 -166.2557)
		(stroke
			(width 0.047498)
			(type default)
		)
		(layer "B.Cu")
	)
	(gr_line
		(start 7.107428 -166.2049)
		(end 7.128764 -166.2049)
		(stroke
			(width 0.047498)
			(type default)
		)
		(layer "B.Cu")
	)
	(gr_arc
		(start 7.121398 -116.143786)
		(mid 6.899047 -116.235887)
		(end 6.806946 -116.458238)
		(stroke
			(width 0.047498)
			(type default)
		)
		(layer "B.Cu")
	)
	(gr_arc
		(start 7.129018 -102.143052)
		(mid 7.004605 -102.167814)
		(end 6.899148 -102.238302)
		(stroke
			(width 0.047498)
			(type default)
		)
		(layer "B.Cu")
	)
	(gr_line
		(start 7.227062 -376.805698)
		(end 7.227062 -376.80646)
		(stroke
			(width 0.047498)
			(type default)
		)
		(layer "B.Cu")
	)
	(gr_line
		(start 7.238746 -353.3267)
		(end 7.39394 -353.171506)
		(stroke
			(width 0.047498)
			(type default)
		)
		(layer "B.Cu")
	)
	(gr_arc
		(start 7.238746 -348.161864)
		(mid 6.848482 -348.239492)
		(end 6.51764 -348.460568)
		(stroke
			(width 0.047498)
			(type default)
		)
		(layer "B.Cu")
	)
	(gr_arc
		(start 7.238746 -108.168186)
		(mid 6.977425 -108.22026)
		(end 6.755892 -108.368338)
		(stroke
			(width 0.047498)
			(type default)
		)
		(layer "B.Cu")
	)
	(gr_arc
		(start 7.238746 -98.143314)
		(mid 7.013044 -98.188209)
		(end 6.821678 -98.316034)
		(stroke
			(width 0.047498)
			(type default)
		)
		(layer "B.Cu")
	)
	(gr_arc
		(start 7.2644 -421.903906)
		(mid 7.470981 -421.594735)
		(end 7.543546 -421.230044)
		(stroke
			(width 0.047498)
			(type default)
		)
		(layer "B.Cu")
	)
	(gr_line
		(start 7.289038 -367.867184)
		(end 7.536942 -367.61928)
		(stroke
			(width 0.047498)
			(type default)
		)
		(layer "B.Cu")
	)
	(gr_line
		(start 7.340346 -409.835096)
		(end 7.497572 -409.678124)
		(stroke
			(width 0.047498)
			(type default)
		)
		(layer "B.Cu")
	)
	(gr_line
		(start 7.365746 -358.5337)
		(end 7.43712 -358.462326)
		(stroke
			(width 0.047498)
			(type default)
		)
		(layer "B.Cu")
	)
	(gr_arc
		(start 7.365746 -128.143762)
		(mid 7.046144 -128.207326)
		(end 6.775196 -128.388364)
		(stroke
			(width 0.047498)
			(type default)
		)
		(layer "B.Cu")
	)
	(gr_line
		(start 7.386828 -415.282888)
		(end 7.393432 -415.289238)
		(stroke
			(width 0.047498)
			(type default)
		)
		(layer "B.Cu")
	)
	(gr_arc
		(start 7.3914 -424.053)
		(mid 7.596073 -423.810775)
		(end 7.505446 -423.5069)
		(stroke
			(width 0.047498)
			(type default)
		)
		(layer "B.Cu")
	)
	(gr_arc
		(start 7.39394 -353.171506)
		(mid 7.467071 -353.062082)
		(end 7.492746 -352.933)
		(stroke
			(width 0.047498)
			(type default)
		)
		(layer "B.Cu")
	)
	(gr_arc
		(start 7.398004 -112.144048)
		(mid 7.042477 -112.230475)
		(end 6.756146 -112.458246)
		(stroke
			(width 0.047498)
			(type default)
		)
		(layer "B.Cu")
	)
	(gr_arc
		(start 7.43712 -358.462326)
		(mid 7.609907 -358.203732)
		(end 7.670546 -357.8987)
		(stroke
			(width 0.047498)
			(type default)
		)
		(layer "B.Cu")
	)
	(gr_arc
		(start 7.47014 -162.160458)
		(mid 7.079487 -162.238164)
		(end 6.748272 -162.459416)
		(stroke
			(width 0.047498)
			(type default)
		)
		(layer "B.Cu")
	)
	(gr_arc
		(start 7.492746 -414.0327)
		(mid 7.624341 -413.835754)
		(end 7.670546 -413.60344)
		(stroke
			(width 0.047498)
			(type default)
		)
		(layer "B.Cu")
	)
	(gr_line
		(start 7.492746 -352.718878)
		(end 7.492746 -352.933)
		(stroke
			(width 0.047498)
			(type default)
		)
		(layer "B.Cu")
	)
	(gr_arc
		(start 7.493 -170.2689)
		(mid 7.243773 -170.318471)
		(end 7.032498 -170.459654)
		(stroke
			(width 0.047498)
			(type default)
		)
		(layer "B.Cu")
	)
	(gr_arc
		(start 7.497572 -409.678124)
		(mid 7.603077 -409.520086)
		(end 7.640066 -409.3337)
		(stroke
			(width 0.047498)
			(type default)
		)
		(layer "B.Cu")
	)
	(gr_arc
		(start 7.525004 -417.830508)
		(mid 7.704176 -417.562358)
		(end 7.767066 -417.246054)
		(stroke
			(width 0.047498)
			(type default)
		)
		(layer "B.Cu")
	)
	(gr_arc
		(start 7.536942 -367.61928)
		(mid 7.63582 -367.471276)
		(end 7.670546 -367.2967)
		(stroke
			(width 0.047498)
			(type default)
		)
		(layer "B.Cu")
	)
	(gr_line
		(start 7.593838 -355.119686)
		(end 7.599172 -355.12502)
		(stroke
			(width 0.047498)
			(type default)
		)
		(layer "B.Cu")
	)
	(gr_line
		(start 7.620508 -415.049462)
		(end 7.626604 -415.055812)
		(stroke
			(width 0.047498)
			(type default)
		)
		(layer "B.Cu")
	)
	(gr_arc
		(start 7.64921 -384.0226)
		(mid 7.815378 -383.773912)
		(end 7.873746 -383.480564)
		(stroke
			(width 0.047498)
			(type default)
		)
		(layer "B.Cu")
	)
	(gr_line
		(start 7.670546 -413.34944)
		(end 7.670546 -413.60344)
		(stroke
			(width 0.047498)
			(type default)
		)
		(layer "B.Cu")
	)
	(gr_arc
		(start 7.706614 -158.16072)
		(mid 7.315929 -158.23837)
		(end 6.984746 -158.459678)
		(stroke
			(width 0.047498)
			(type default)
		)
		(layer "B.Cu")
	)
	(gr_arc
		(start 7.716012 -371.479572)
		(mid 7.81675 -371.339628)
		(end 7.868158 -371.175026)
		(stroke
			(width 0.047498)
			(type default)
		)
		(layer "B.Cu")
	)
	(gr_arc
		(start 7.746746 -380.3777)
		(mid 7.934717 -380.096382)
		(end 8.000746 -379.764544)
		(stroke
			(width 0.047498)
			(type default)
		)
		(layer "B.Cu")
	)
	(gr_arc
		(start 7.746746 -364.3757)
		(mid 7.810831 -364.279791)
		(end 7.83336 -364.166658)
		(stroke
			(width 0.047498)
			(type default)
		)
		(layer "B.Cu")
	)
	(gr_line
		(start 7.747 -172.593)
		(end 7.752334 -172.598334)
		(stroke
			(width 0.047498)
			(type default)
		)
		(layer "B.Cu")
	)
	(gr_arc
		(start 7.75208 -399.300446)
		(mid 7.675462 -398.960689)
		(end 7.535926 -398.64157)
		(stroke
			(width 0.047498)
			(type default)
		)
		(layer "B.Cu")
	)
	(gr_arc
		(start 7.766812 -416.183826)
		(mid 7.76529 -416.123424)
		(end 7.760716 -416.063176)
		(stroke
			(width 0.047498)
			(type default)
		)
		(layer "B.Cu")
	)
	(gr_arc
		(start 7.822946 -352.386138)
		(mid 7.84638 -352.503946)
		(end 7.913116 -352.603816)
		(stroke
			(width 0.047498)
			(type default)
		)
		(layer "B.Cu")
	)
	(gr_line
		(start 7.83336 -363.496352)
		(end 7.83336 -364.166658)
		(stroke
			(width 0.047498)
			(type default)
		)
		(layer "B.Cu")
	)
	(gr_arc
		(start 7.868158 -371.175026)
		(mid 7.872311 -371.137025)
		(end 7.873746 -371.098826)
		(stroke
			(width 0.047498)
			(type default)
		)
		(layer "B.Cu")
	)
	(gr_arc
		(start 7.873746 -421.313102)
		(mid 7.939782 -421.644932)
		(end 8.127746 -421.926258)
		(stroke
			(width 0.047498)
			(type default)
		)
		(layer "B.Cu")
	)
	(gr_arc
		(start 7.873746 -376.4407)
		(mid 8.061717 -376.159382)
		(end 8.127746 -375.827544)
		(stroke
			(width 0.047498)
			(type default)
		)
		(layer "B.Cu")
	)
	(gr_line
		(start 7.913116 -352.603816)
		(end 8.212582 -352.903282)
		(stroke
			(width 0.047498)
			(type default)
		)
		(layer "B.Cu")
	)
	(gr_arc
		(start 7.9248 -423.596308)
		(mid 7.958022 -423.763191)
		(end 8.052562 -423.904664)
		(stroke
			(width 0.047498)
			(type default)
		)
		(layer "B.Cu")
	)
	(gr_arc
		(start 7.9248 -423.5958)
		(mid 7.899646 -423.469341)
		(end 7.828026 -423.36212)
		(stroke
			(width 0.047498)
			(type default)
		)
		(layer "B.Cu")
	)
	(gr_line
		(start 7.9248 -423.5958)
		(end 7.9248 -423.596308)
		(stroke
			(width 0.047498)
			(type default)
		)
		(layer "B.Cu")
	)
	(gr_arc
		(start 7.970266 -409.338272)
		(mid 8.01858 -409.581295)
		(end 8.156194 -409.787344)
		(stroke
			(width 0.047498)
			(type default)
		)
		(layer "B.Cu")
	)
	(gr_arc
		(start 8.000746 -413.0167)
		(mid 8.013507 -413.139226)
		(end 8.051292 -413.256476)
		(stroke
			(width 0.047498)
			(type default)
		)
		(layer "B.Cu")
	)
	(gr_arc
		(start 8.000746 -367.541048)
		(mid 8.040046 -367.738449)
		(end 8.151876 -367.905792)
		(stroke
			(width 0.047498)
			(type default)
		)
		(layer "B.Cu")
	)
	(gr_arc
		(start 8.000746 -357.92918)
		(mid 8.063633 -358.245056)
		(end 8.242554 -358.512872)
		(stroke
			(width 0.047498)
			(type default)
		)
		(layer "B.Cu")
	)
	(gr_arc
		(start 8.051292 -413.256476)
		(mid 8.10457 -413.35197)
		(end 8.174482 -413.436054)
		(stroke
			(width 0.047498)
			(type default)
		)
		(layer "B.Cu")
	)
	(gr_line
		(start 8.052562 -423.904664)
		(end 8.253476 -424.105324)
		(stroke
			(width 0.047498)
			(type default)
		)
		(layer "B.Cu")
	)
	(gr_arc
		(start 8.097266 -417.139628)
		(mid 8.172985 -417.520267)
		(end 8.388604 -417.842954)
		(stroke
			(width 0.047498)
			(type default)
		)
		(layer "B.Cu")
	)
	(gr_line
		(start 8.127746 -386.461)
		(end 8.189214 -386.399786)
		(stroke
			(width 0.047498)
			(type default)
		)
		(layer "B.Cu")
	)
	(gr_line
		(start 8.127746 -385.532884)
		(end 8.189214 -385.594098)
		(stroke
			(width 0.047498)
			(type default)
		)
		(layer "B.Cu")
	)
	(gr_arc
		(start 8.130794 -347.831664)
		(mid 8.261139 -347.801743)
		(end 8.363204 -347.715332)
		(stroke
			(width 0.047498)
			(type default)
		)
		(layer "B.Cu")
	)
	(gr_line
		(start 8.156194 -409.787344)
		(end 8.203946 -409.835096)
		(stroke
			(width 0.047498)
			(type default)
		)
		(layer "B.Cu")
	)
	(gr_arc
		(start 8.16356 -363.163612)
		(mid 8.23389 -363.517453)
		(end 8.434324 -363.817408)
		(stroke
			(width 0.047498)
			(type default)
		)
		(layer "B.Cu")
	)
	(gr_line
		(start 8.174482 -413.436054)
		(end 8.296402 -413.557974)
		(stroke
			(width 0.047498)
			(type default)
		)
		(layer "B.Cu")
	)
	(gr_arc
		(start 8.189214 -385.594098)
		(mid 8.452336 -385.770012)
		(end 8.762746 -385.831842)
		(stroke
			(width 0.047498)
			(type default)
		)
		(layer "B.Cu")
	)
	(gr_arc
		(start 8.203946 -383.317242)
		(mid 8.284043 -383.719737)
		(end 8.512048 -384.060954)
		(stroke
			(width 0.047498)
			(type default)
		)
		(layer "B.Cu")
	)
	(gr_arc
		(start 8.203946 -371.238018)
		(mid 8.217132 -371.304417)
		(end 8.254746 -371.3607)
		(stroke
			(width 0.047498)
			(type default)
		)
		(layer "B.Cu")
	)
	(gr_line
		(start 8.254746 -371.3607)
		(end 8.27405 -371.380004)
		(stroke
			(width 0.047498)
			(type default)
		)
		(layer "B.Cu")
	)
	(gr_arc
		(start 8.27405 -371.380004)
		(mid 8.430212 -371.484333)
		(end 8.61441 -371.520974)
		(stroke
			(width 0.047498)
			(type default)
		)
		(layer "B.Cu")
	)
	(gr_arc
		(start 8.330946 -379.6157)
		(mid 8.410299 -380.014612)
		(end 8.636254 -380.352808)
		(stroke
			(width 0.047498)
			(type default)
		)
		(layer "B.Cu")
	)
	(gr_arc
		(start 8.457946 -375.6787)
		(mid 8.526353 -376.023041)
		(end 8.721344 -376.31497)
		(stroke
			(width 0.047498)
			(type default)
		)
		(layer "B.Cu")
	)
	(gr_line
		(start 8.463534 -348.161864)
		(end 9.013444 -348.161864)
		(stroke
			(width 0.047498)
			(type default)
		)
		(layer "B.Cu")
	)
	(gr_arc
		(start 8.595614 -347.599254)
		(mid 8.465296 -347.629051)
		(end 8.363204 -347.715332)
		(stroke
			(width 0.047498)
			(type default)
		)
		(layer "B.Cu")
	)
	(gr_line
		(start 8.595614 -347.599254)
		(end 8.881364 -347.599254)
		(stroke
			(width 0.047498)
			(type default)
		)
		(layer "B.Cu")
	)
	(gr_line
		(start 8.636254 -380.352808)
		(end 8.661146 -380.3777)
		(stroke
			(width 0.047498)
			(type default)
		)
		(layer "B.Cu")
	)
	(gr_line
		(start 8.721344 -376.31497)
		(end 8.75411 -376.347482)
		(stroke
			(width 0.047498)
			(type default)
		)
		(layer "B.Cu")
	)
	(gr_arc
		(start 8.762746 -386.162042)
		(mid 8.452338 -386.22388)
		(end 8.189214 -386.399786)
		(stroke
			(width 0.047498)
			(type default)
		)
		(layer "B.Cu")
	)
	(gr_arc
		(start 8.854186 -94.6277)
		(mid 8.92513 -94.514471)
		(end 8.936228 -94.38132)
		(stroke
			(width 0.047498)
			(type default)
		)
		(layer "B.Cu")
	)
	(gr_arc
		(start 9.018524 -94.134686)
		(mid 8.947427 -94.248005)
		(end 8.936228 -94.38132)
		(stroke
			(width 0.047498)
			(type default)
		)
		(layer "B.Cu")
	)
	(gr_line
		(start 9.018524 -94.134686)
		(end 9.220454 -93.932756)
		(stroke
			(width 0.047498)
			(type default)
		)
		(layer "B.Cu")
	)
	(gr_arc
		(start 9.113774 -347.715332)
		(mid 9.011657 -347.629101)
		(end 8.881364 -347.599254)
		(stroke
			(width 0.047498)
			(type default)
		)
		(layer "B.Cu")
	)
	(gr_arc
		(start 9.113774 -347.715332)
		(mid 9.215855 -347.801705)
		(end 9.346184 -347.831664)
		(stroke
			(width 0.047498)
			(type default)
		)
		(layer "B.Cu")
	)
	(gr_line
		(start 9.270746 -132.448554)
		(end 9.270746 -132.4737)
		(stroke
			(width 0.047498)
			(type default)
		)
		(layer "B.Cu")
	)
	(gr_line
		(start 9.271 -176.53)
		(end 9.276334 -176.535334)
		(stroke
			(width 0.047498)
			(type default)
		)
		(layer "B.Cu")
	)
	(gr_line
		(start 9.32307 -94.626176)
		(end 9.711944 -94.237302)
		(stroke
			(width 0.047498)
			(type default)
		)
		(layer "B.Cu")
	)
	(gr_arc
		(start 9.432544 -132.057902)
		(mid 9.312792 -132.237138)
		(end 9.270746 -132.448554)
		(stroke
			(width 0.047498)
			(type default)
		)
		(layer "B.Cu")
	)
	(gr_arc
		(start 9.467088 -93.85046)
		(mid 9.333762 -93.861626)
		(end 9.220454 -93.932756)
		(stroke
			(width 0.047498)
			(type default)
		)
		(layer "B.Cu")
	)
	(gr_arc
		(start 9.467088 -93.85046)
		(mid 9.600258 -93.839393)
		(end 9.713468 -93.768418)
		(stroke
			(width 0.047498)
			(type default)
		)
		(layer "B.Cu")
	)
	(gr_arc
		(start 9.631934 -347.831664)
		(mid 9.762268 -347.801728)
		(end 9.864344 -347.715332)
		(stroke
			(width 0.047498)
			(type default)
		)
		(layer "B.Cu")
	)
	(gr_arc
		(start 9.686544 -132.057902)
		(mid 9.559544 -132.005297)
		(end 9.432544 -132.057902)
		(stroke
			(width 0.047498)
			(type default)
		)
		(layer "B.Cu")
	)
	(gr_arc
		(start 9.85139 -131.755388)
		(mid 9.584988 -131.577384)
		(end 9.270746 -131.51485)
		(stroke
			(width 0.047498)
			(type default)
		)
		(layer "B.Cu")
	)
	(gr_line
		(start 9.964674 -348.161864)
		(end 10.514584 -348.161864)
		(stroke
			(width 0.047498)
			(type default)
		)
		(layer "B.Cu")
	)
	(gr_line
		(start 10.02157 -132.391912)
		(end 10.029698 -132.399786)
		(stroke
			(width 0.047498)
			(type default)
		)
		(layer "B.Cu")
	)
	(gr_line
		(start 10.029698 -132.399786)
		(end 10.029698 -132.402834)
		(stroke
			(width 0.047498)
			(type default)
		)
		(layer "B.Cu")
	)
	(gr_arc
		(start 10.096754 -347.599254)
		(mid 9.966436 -347.629051)
		(end 9.864344 -347.715332)
		(stroke
			(width 0.047498)
			(type default)
		)
		(layer "B.Cu")
	)
	(gr_line
		(start 10.096754 -347.599254)
		(end 10.382504 -347.599254)
		(stroke
			(width 0.047498)
			(type default)
		)
		(layer "B.Cu")
	)
	(gr_line
		(start 10.273538 -132.177028)
		(end 10.314432 -132.2324)
		(stroke
			(width 0.047498)
			(type default)
		)
		(layer "B.Cu")
	)
	(gr_arc
		(start 10.614914 -347.715332)
		(mid 10.512797 -347.629101)
		(end 10.382504 -347.599254)
		(stroke
			(width 0.047498)
			(type default)
		)
		(layer "B.Cu")
	)
	(gr_arc
		(start 10.614914 -347.715332)
		(mid 10.71699 -347.801727)
		(end 10.847324 -347.831664)
		(stroke
			(width 0.047498)
			(type default)
		)
		(layer "B.Cu")
	)
	(gr_line
		(start 11.028172 -176.94402)
		(end 11.033506 -176.949354)
		(stroke
			(width 0.047498)
			(type default)
		)
		(layer "B.Cu")
	)
	(gr_arc
		(start 11.133074 -347.831664)
		(mid 11.263396 -347.801714)
		(end 11.365484 -347.715332)
		(stroke
			(width 0.047498)
			(type default)
		)
		(layer "B.Cu")
	)
	(gr_line
		(start 11.465814 -348.161864)
		(end 12.015724 -348.161864)
		(stroke
			(width 0.047498)
			(type default)
		)
		(layer "B.Cu")
	)
	(gr_arc
		(start 11.597894 -347.599254)
		(mid 11.467576 -347.629051)
		(end 11.365484 -347.715332)
		(stroke
			(width 0.047498)
			(type default)
		)
		(layer "B.Cu")
	)
	(gr_line
		(start 11.597894 -347.599254)
		(end 11.883644 -347.599254)
		(stroke
			(width 0.047498)
			(type default)
		)
		(layer "B.Cu")
	)
	(gr_line
		(start 11.760454 -378.421138)
		(end 11.760708 -378.415042)
		(stroke
			(width 0.047498)
			(type default)
		)
		(layer "B.Cu")
	)
	(gr_line
		(start 11.981688 -377.454414)
		(end 11.981942 -377.453652)
		(stroke
			(width 0.047498)
			(type default)
		)
		(layer "B.Cu")
	)
	(gr_arc
		(start 12.116054 -347.715332)
		(mid 12.013937 -347.629101)
		(end 11.883644 -347.599254)
		(stroke
			(width 0.047498)
			(type default)
		)
		(layer "B.Cu")
	)
	(gr_arc
		(start 12.116054 -347.715332)
		(mid 12.218133 -347.801712)
		(end 12.348464 -347.831664)
		(stroke
			(width 0.047498)
			(type default)
		)
		(layer "B.Cu")
	)
	(gr_line
		(start 12.21867 -385.06019)
		(end 12.229084 -385.049776)
		(stroke
			(width 0.047498)
			(type default)
		)
		(layer "B.Cu")
	)
	(gr_line
		(start 12.509246 -174.3202)
		(end 12.742672 -174.553626)
		(stroke
			(width 0.047498)
			(type default)
		)
		(layer "B.Cu")
	)
	(gr_arc
		(start 12.634214 -347.831664)
		(mid 12.764554 -347.801736)
		(end 12.866624 -347.715332)
		(stroke
			(width 0.047498)
			(type default)
		)
		(layer "B.Cu")
	)
	(gr_line
		(start 12.966954 -348.161864)
		(end 13.516864 -348.161864)
		(stroke
			(width 0.047498)
			(type default)
		)
		(layer "B.Cu")
	)
	(gr_arc
		(start 13.099034 -347.599254)
		(mid 12.968716 -347.629051)
		(end 12.866624 -347.715332)
		(stroke
			(width 0.047498)
			(type default)
		)
		(layer "B.Cu")
	)
	(gr_line
		(start 13.099034 -347.599254)
		(end 13.384784 -347.599254)
		(stroke
			(width 0.047498)
			(type default)
		)
		(layer "B.Cu")
	)
	(gr_line
		(start 13.311632 -376.885962)
		(end 13.311886 -376.885708)
		(stroke
			(width 0.047498)
			(type default)
		)
		(layer "B.Cu")
	)
	(gr_line
		(start 13.311886 -376.885708)
		(end 13.348462 -376.848878)
		(stroke
			(width 0.047498)
			(type default)
		)
		(layer "B.Cu")
	)
	(gr_line
		(start 13.492226 -173.71822)
		(end 13.725652 -173.951646)
		(stroke
			(width 0.047498)
			(type default)
		)
		(layer "B.Cu")
	)
	(gr_line
		(start 13.545058 -377.119134)
		(end 13.582904 -377.081542)
		(stroke
			(width 0.047498)
			(type default)
		)
		(layer "B.Cu")
	)
	(gr_line
		(start 13.588746 -377.0757)
		(end 13.778738 -376.885708)
		(stroke
			(width 0.047498)
			(type default)
		)
		(layer "B.Cu")
	)
	(gr_arc
		(start 13.617194 -347.715332)
		(mid 13.515077 -347.629101)
		(end 13.384784 -347.599254)
		(stroke
			(width 0.047498)
			(type default)
		)
		(layer "B.Cu")
	)
	(gr_arc
		(start 13.617194 -347.715332)
		(mid 13.719269 -347.801734)
		(end 13.849604 -347.831664)
		(stroke
			(width 0.047498)
			(type default)
		)
		(layer "B.Cu")
	)
	(gr_line
		(start 14.896846 -173.3296)
		(end 14.90218 -173.334934)
		(stroke
			(width 0.047498)
			(type default)
		)
		(layer "B.Cu")
	)
	(gr_line
		(start 15.663926 -171.67352)
		(end 15.897352 -171.906946)
		(stroke
			(width 0.047498)
			(type default)
		)
		(layer "B.Cu")
	)
	(gr_line
		(start 15.762986 -221.472506)
		(end 15.76324 -221.47276)
		(stroke
			(width 0.047498)
			(type default)
		)
		(layer "B.Cu")
	)
	(gr_line
		(start 15.76324 -221.47276)
		(end 15.996666 -221.239334)
		(stroke
			(width 0.047498)
			(type default)
		)
		(layer "B.Cu")
	)
	(gr_line
		(start 15.934944 -221.767908)
		(end 15.996412 -221.706186)
		(stroke
			(width 0.047498)
			(type default)
		)
		(layer "B.Cu")
	)
	(gr_line
		(start 15.996412 -221.706186)
		(end 15.996666 -221.70644)
		(stroke
			(width 0.047498)
			(type default)
		)
		(layer "B.Cu")
	)
	(gr_line
		(start 16.0655 -338.2645)
		(end 16.070834 -338.269834)
		(stroke
			(width 0.047498)
			(type default)
		)
		(layer "B.Cu")
	)
	(gr_line
		(start 16.326104 -133.900164)
		(end 16.326866 -133.900926)
		(stroke
			(width 0.047498)
			(type default)
		)
		(layer "B.Cu")
	)
	(gr_line
		(start 16.326866 -133.900926)
		(end 16.327374 -133.901434)
		(stroke
			(width 0.047498)
			(type default)
		)
		(layer "B.Cu")
	)
	(gr_line
		(start 16.56207 -133.669024)
		(end 16.56969 -133.677152)
		(stroke
			(width 0.047498)
			(type default)
		)
		(layer "B.Cu")
	)
	(gr_line
		(start 16.611854 -170.979338)
		(end 16.84528 -171.212764)
		(stroke
			(width 0.047498)
			(type default)
		)
		(layer "B.Cu")
	)
	(gr_arc
		(start 17.137634 -347.831664)
		(mid 17.267968 -347.801728)
		(end 17.370044 -347.715332)
		(stroke
			(width 0.047498)
			(type default)
		)
		(layer "B.Cu")
	)
	(gr_line
		(start 17.470374 -348.161864)
		(end 18.020284 -348.161864)
		(stroke
			(width 0.047498)
			(type default)
		)
		(layer "B.Cu")
	)
	(gr_arc
		(start 17.602454 -347.599254)
		(mid 17.472136 -347.629051)
		(end 17.370044 -347.715332)
		(stroke
			(width 0.047498)
			(type default)
		)
		(layer "B.Cu")
	)
	(gr_line
		(start 17.602454 -347.599254)
		(end 17.888204 -347.599254)
		(stroke
			(width 0.047498)
			(type default)
		)
		(layer "B.Cu")
	)
	(gr_arc
		(start 18.120614 -347.715332)
		(mid 18.018497 -347.629101)
		(end 17.888204 -347.599254)
		(stroke
			(width 0.047498)
			(type default)
		)
		(layer "B.Cu")
	)
	(gr_arc
		(start 18.120614 -347.715332)
		(mid 18.22269 -347.801727)
		(end 18.353024 -347.831664)
		(stroke
			(width 0.047498)
			(type default)
		)
		(layer "B.Cu")
	)
	(gr_line
		(start 18.819622 -134.502906)
		(end 18.821654 -134.504938)
		(stroke
			(width 0.047498)
			(type default)
		)
		(layer "B.Cu")
	)
	(gr_line
		(start 18.821654 -134.504938)
		(end 18.82521 -134.509256)
		(stroke
			(width 0.047498)
			(type default)
		)
		(layer "B.Cu")
	)
	(gr_line
		(start 19.058636 -134.275068)
		(end 19.075908 -134.294118)
		(stroke
			(width 0.047498)
			(type default)
		)
		(layer "B.Cu")
	)
	(gr_arc
		(start 19.677634 -169.08526)
		(mid 19.6465 -168.928555)
		(end 19.557746 -168.7957)
		(stroke
			(width 0.047498)
			(type default)
		)
		(layer "B.Cu")
	)
	(gr_line
		(start 19.677634 -169.08526)
		(end 19.677634 -169.634154)
		(stroke
			(width 0.047498)
			(type default)
		)
		(layer "B.Cu")
	)
	(gr_line
		(start 20.007072 -169.064432)
		(end 20.007072 -169.620946)
		(stroke
			(width 0.047498)
			(type default)
		)
		(layer "B.Cu")
	)
	(gr_arc
		(start 20.065746 -168.9227)
		(mid 20.022321 -168.987736)
		(end 20.007072 -169.064432)
		(stroke
			(width 0.047498)
			(type default)
		)
		(layer "B.Cu")
	)
	(gr_arc
		(start 20.372324 -168.7957)
		(mid 20.206416 -168.828728)
		(end 20.065746 -168.9227)
		(stroke
			(width 0.047498)
			(type default)
		)
		(layer "B.Cu")
	)
	(gr_line
		(start 20.372324 -168.7957)
		(end 20.446746 -168.7957)
		(stroke
			(width 0.047498)
			(type default)
		)
		(layer "B.Cu")
	)
	(gr_line
		(start 21.457666 -343.656666)
		(end 21.463 -343.662)
		(stroke
			(width 0.047498)
			(type default)
		)
		(layer "B.Cu")
	)
	(gr_arc
		(start 21.639276 -444.207392)
		(mid 21.836805 -444.339377)
		(end 22.069806 -444.3857)
		(stroke
			(width 0.047498)
			(type default)
		)
		(layer "B.Cu")
	)
	(gr_line
		(start 21.676614 -445.07023)
		(end 21.858224 -444.88862)
		(stroke
			(width 0.047498)
			(type default)
		)
		(layer "B.Cu")
	)
	(gr_arc
		(start 21.869146 -32.960818)
		(mid 21.928671 -33.104474)
		(end 22.072346 -33.164018)
		(stroke
			(width 0.047498)
			(type default)
		)
		(layer "B.Cu")
	)
	(gr_arc
		(start 21.945346 -238.3409)
		(mid 22.02214 -238.392222)
		(end 22.112732 -238.410242)
		(stroke
			(width 0.047498)
			(type default)
		)
		(layer "B.Cu")
	)
	(gr_arc
		(start 21.945346 -238.0107)
		(mid 21.876946 -238.1758)
		(end 21.945346 -238.3409)
		(stroke
			(width 0.047498)
			(type default)
		)
		(layer "B.Cu")
	)
	(gr_line
		(start 21.996146 -32.1945)
		(end 22.014434 -32.212788)
		(stroke
			(width 0.047498)
			(type default)
		)
		(layer "B.Cu")
	)
	(gr_arc
		(start 22.014434 -32.212788)
		(mid 22.150853 -32.316342)
		(end 22.31009 -32.379412)
		(stroke
			(width 0.047498)
			(type default)
		)
		(layer "B.Cu")
	)
	(gr_arc
		(start 22.07006 -341.08644)
		(mid 22.461167 -341.347721)
		(end 22.922484 -341.4395)
		(stroke
			(width 0.047498)
			(type default)
		)
		(layer "B.Cu")
	)
	(gr_arc
		(start 22.102064 -32.7279)
		(mid 21.937396 -32.796134)
		(end 21.869146 -32.960818)
		(stroke
			(width 0.047498)
			(type default)
		)
		(layer "B.Cu")
	)
	(gr_line
		(start 22.102064 -32.7279)
		(end 22.126702 -32.7279)
		(stroke
			(width 0.047498)
			(type default)
		)
		(layer "B.Cu")
	)
	(gr_arc
		(start 22.154134 -238.740442)
		(mid 21.98617 -238.773852)
		(end 21.843746 -238.868966)
		(stroke
			(width 0.047498)
			(type default)
		)
		(layer "B.Cu")
	)
	(gr_arc
		(start 22.163532 -444.726568)
		(mid 21.99872 -444.784696)
		(end 21.858224 -444.88862)
		(stroke
			(width 0.047498)
			(type default)
		)
		(layer "B.Cu")
	)
	(gr_arc
		(start 22.275546 -444.7159)
		(mid 22.219285 -444.718562)
		(end 22.163532 -444.726568)
		(stroke
			(width 0.047498)
			(type default)
		)
		(layer "B.Cu")
	)
	(gr_arc
		(start 22.31009 -32.379412)
		(mid 22.349361 -32.38778)
		(end 22.389084 -32.393636)
		(stroke
			(width 0.047498)
			(type default)
		)
		(layer "B.Cu")
	)
	(gr_arc
		(start 22.389084 -32.393636)
		(mid 22.424206 -32.396658)
		(end 22.459442 -32.3977)
		(stroke
			(width 0.047498)
			(type default)
		)
		(layer "B.Cu")
	)
	(gr_arc
		(start 22.735286 -341.7697)
		(mid 22.375251 -341.841315)
		(end 22.07006 -342.04529)
		(stroke
			(width 0.047498)
			(type default)
		)
		(layer "B.Cu")
	)
	(gr_line
		(start 23.198074 -214.037926)
		(end 23.594314 -213.641686)
		(stroke
			(width 0.047498)
			(type default)
		)
		(layer "B.Cu")
	)
	(gr_arc
		(start 23.587456 -336.698336)
		(mid 23.617253 -336.828654)
		(end 23.703534 -336.930746)
		(stroke
			(width 0.047498)
			(type default)
		)
		(layer "B.Cu")
	)
	(gr_line
		(start 23.587456 -336.412586)
		(end 23.587456 -336.698336)
		(stroke
			(width 0.047498)
			(type default)
		)
		(layer "B.Cu")
	)
	(gr_arc
		(start 23.587456 -335.197196)
		(mid 23.617253 -335.327514)
		(end 23.703534 -335.429606)
		(stroke
			(width 0.047498)
			(type default)
		)
		(layer "B.Cu")
	)
	(gr_line
		(start 23.587456 -334.911446)
		(end 23.587456 -335.197196)
		(stroke
			(width 0.047498)
			(type default)
		)
		(layer "B.Cu")
	)
	(gr_line
		(start 23.700486 -191.426592)
		(end 23.70582 -191.431926)
		(stroke
			(width 0.047498)
			(type default)
		)
		(layer "B.Cu")
	)
	(gr_arc
		(start 23.703788 -336.180176)
		(mid 23.617389 -336.28225)
		(end 23.587456 -336.412586)
		(stroke
			(width 0.047498)
			(type default)
		)
		(layer "B.Cu")
	)
	(gr_arc
		(start 23.703788 -336.180176)
		(mid 23.790083 -336.07808)
		(end 23.819866 -335.947766)
		(stroke
			(width 0.047498)
			(type default)
		)
		(layer "B.Cu")
	)
	(gr_arc
		(start 23.703788 -334.679036)
		(mid 23.617389 -334.78111)
		(end 23.587456 -334.911446)
		(stroke
			(width 0.047498)
			(type default)
		)
		(layer "B.Cu")
	)
	(gr_arc
		(start 23.703788 -334.679036)
		(mid 23.790068 -334.576937)
		(end 23.819866 -334.446626)
		(stroke
			(width 0.047498)
			(type default)
		)
		(layer "B.Cu")
	)
	(gr_arc
		(start 23.819866 -337.163156)
		(mid 23.789927 -337.032825)
		(end 23.703534 -336.930746)
		(stroke
			(width 0.047498)
			(type default)
		)
		(layer "B.Cu")
	)
	(gr_arc
		(start 23.819866 -335.662016)
		(mid 23.789912 -335.531697)
		(end 23.703534 -335.429606)
		(stroke
			(width 0.047498)
			(type default)
		)
		(layer "B.Cu")
	)
	(gr_line
		(start 24.150066 -336.280506)
		(end 24.150066 -336.830416)
		(stroke
			(width 0.047498)
			(type default)
		)
		(layer "B.Cu")
	)
	(gr_line
		(start 24.150066 -334.779366)
		(end 24.150066 -335.329276)
		(stroke
			(width 0.047498)
			(type default)
		)
		(layer "B.Cu")
	)
	(gr_arc
		(start 24.468836 -440.892946)
		(mid 24.498776 -441.023276)
		(end 24.585168 -441.125356)
		(stroke
			(width 0.047498)
			(type default)
		)
		(layer "B.Cu")
	)
	(gr_line
		(start 24.468836 -440.607196)
		(end 24.468836 -440.892946)
		(stroke
			(width 0.047498)
			(type default)
		)
		(layer "B.Cu")
	)
	(gr_arc
		(start 24.468836 -439.391806)
		(mid 24.498762 -439.522148)
		(end 24.585168 -439.624216)
		(stroke
			(width 0.047498)
			(type default)
		)
		(layer "B.Cu")
	)
	(gr_line
		(start 24.468836 -439.106056)
		(end 24.468836 -439.391806)
		(stroke
			(width 0.047498)
			(type default)
		)
		(layer "B.Cu")
	)
	(gr_arc
		(start 24.468836 -437.890666)
		(mid 24.498784 -438.02099)
		(end 24.585168 -438.123076)
		(stroke
			(width 0.047498)
			(type default)
		)
		(layer "B.Cu")
	)
	(gr_line
		(start 24.468836 -437.604916)
		(end 24.468836 -437.890666)
		(stroke
			(width 0.047498)
			(type default)
		)
		(layer "B.Cu")
	)
	(gr_arc
		(start 24.468836 -436.389526)
		(mid 24.498769 -436.519862)
		(end 24.585168 -436.621936)
		(stroke
			(width 0.047498)
			(type default)
		)
		(layer "B.Cu")
	)
	(gr_line
		(start 24.468836 -436.103776)
		(end 24.468836 -436.389526)
		(stroke
			(width 0.047498)
			(type default)
		)
		(layer "B.Cu")
	)
	(gr_arc
		(start 24.468836 -434.888386)
		(mid 24.498754 -435.018734)
		(end 24.585168 -435.120796)
		(stroke
			(width 0.047498)
			(type default)
		)
		(layer "B.Cu")
	)
	(gr_line
		(start 24.468836 -434.602636)
		(end 24.468836 -434.888386)
		(stroke
			(width 0.047498)
			(type default)
		)
		(layer "B.Cu")
	)
	(gr_arc
		(start 24.585168 -440.374786)
		(mid 24.4988 -440.476867)
		(end 24.468836 -440.607196)
		(stroke
			(width 0.047498)
			(type default)
		)
		(layer "B.Cu")
	)
	(gr_arc
		(start 24.585168 -440.374786)
		(mid 24.671399 -440.272669)
		(end 24.701246 -440.142376)
		(stroke
			(width 0.047498)
			(type default)
		)
		(layer "B.Cu")
	)
	(gr_arc
		(start 24.585168 -438.873646)
		(mid 24.498785 -438.975725)
		(end 24.468836 -439.106056)
		(stroke
			(width 0.047498)
			(type default)
		)
		(layer "B.Cu")
	)
	(gr_arc
		(start 24.585168 -438.873646)
		(mid 24.671399 -438.771529)
		(end 24.701246 -438.641236)
		(stroke
			(width 0.047498)
			(type default)
		)
		(layer "B.Cu")
	)
	(gr_arc
		(start 24.585168 -437.372506)
		(mid 24.49877 -437.474582)
		(end 24.468836 -437.604916)
		(stroke
			(width 0.047498)
			(type default)
		)
		(layer "B.Cu")
	)
	(gr_arc
		(start 24.585168 -437.372506)
		(mid 24.671399 -437.270389)
		(end 24.701246 -437.140096)
		(stroke
			(width 0.047498)
			(type default)
		)
		(layer "B.Cu")
	)
	(gr_arc
		(start 24.585168 -435.871366)
		(mid 24.498792 -435.973446)
		(end 24.468836 -436.103776)
		(stroke
			(width 0.047498)
			(type default)
		)
		(layer "B.Cu")
	)
	(gr_arc
		(start 24.585168 -435.871366)
		(mid 24.671399 -435.769249)
		(end 24.701246 -435.638956)
		(stroke
			(width 0.047498)
			(type default)
		)
		(layer "B.Cu")
	)
	(gr_arc
		(start 24.585168 -434.370226)
		(mid 24.498778 -434.472303)
		(end 24.468836 -434.602636)
		(stroke
			(width 0.047498)
			(type default)
		)
		(layer "B.Cu")
	)
	(gr_arc
		(start 24.585168 -434.370226)
		(mid 24.671399 -434.268109)
		(end 24.701246 -434.137816)
		(stroke
			(width 0.047498)
			(type default)
		)
		(layer "B.Cu")
	)
	(gr_line
		(start 24.638 -349.83166)
		(end 24.638 -349.9104)
		(stroke
			(width 0.047498)
			(type default)
		)
		(layer "B.Cu")
	)
	(gr_line
		(start 24.638 -343.2048)
		(end 24.638 -343.535)
		(stroke
			(width 0.047498)
			(type default)
		)
		(layer "B.Cu")
	)
	(gr_arc
		(start 24.696166 -348.827598)
		(mid 24.929938 -348.983799)
		(end 25.20569 -349.038672)
		(stroke
			(width 0.047498)
			(type default)
		)
		(layer "B.Cu")
	)
	(gr_arc
		(start 24.701246 -441.357766)
		(mid 24.671449 -441.227448)
		(end 24.585168 -441.125356)
		(stroke
			(width 0.047498)
			(type default)
		)
		(layer "B.Cu")
	)
	(gr_arc
		(start 24.701246 -439.856626)
		(mid 24.671449 -439.726308)
		(end 24.585168 -439.624216)
		(stroke
			(width 0.047498)
			(type default)
		)
		(layer "B.Cu")
	)
	(gr_arc
		(start 24.701246 -438.355486)
		(mid 24.671449 -438.225168)
		(end 24.585168 -438.123076)
		(stroke
			(width 0.047498)
			(type default)
		)
		(layer "B.Cu")
	)
	(gr_arc
		(start 24.701246 -436.854346)
		(mid 24.671449 -436.724028)
		(end 24.585168 -436.621936)
		(stroke
			(width 0.047498)
			(type default)
		)
		(layer "B.Cu")
	)
	(gr_arc
		(start 24.701246 -435.353206)
		(mid 24.671449 -435.222888)
		(end 24.585168 -435.120796)
		(stroke
			(width 0.047498)
			(type default)
		)
		(layer "B.Cu")
	)
	(gr_arc
		(start 24.8158 -349.4024)
		(mid 24.6842 -349.599346)
		(end 24.638 -349.83166)
		(stroke
			(width 0.047498)
			(type default)
		)
		(layer "B.Cu")
	)
	(gr_arc
		(start 24.896826 -349.368872)
		(mid 24.852974 -349.377564)
		(end 24.8158 -349.4024)
		(stroke
			(width 0.047498)
			(type default)
		)
		(layer "B.Cu")
	)
	(gr_line
		(start 24.967946 -343.535)
		(end 24.9682 -343.535)
		(stroke
			(width 0.047498)
			(type default)
		)
		(layer "B.Cu")
	)
	(gr_line
		(start 24.975566 -345.66352)
		(end 25.038304 -345.600782)
		(stroke
			(width 0.047498)
			(type default)
		)
		(layer "B.Cu")
	)
	(gr_line
		(start 25.031446 -440.475116)
		(end 25.031446 -441.025026)
		(stroke
			(width 0.047498)
			(type default)
		)
		(layer "B.Cu")
	)
	(gr_line
		(start 25.031446 -438.973976)
		(end 25.031446 -439.523886)
		(stroke
			(width 0.047498)
			(type default)
		)
		(layer "B.Cu")
	)
	(gr_line
		(start 25.031446 -437.472836)
		(end 25.031446 -438.022746)
		(stroke
			(width 0.047498)
			(type default)
		)
		(layer "B.Cu")
	)
	(gr_line
		(start 25.031446 -435.971696)
		(end 25.031446 -436.521606)
		(stroke
			(width 0.047498)
			(type default)
		)
		(layer "B.Cu")
	)
	(gr_line
		(start 25.031446 -434.470556)
		(end 25.031446 -435.020466)
		(stroke
			(width 0.047498)
			(type default)
		)
		(layer "B.Cu")
	)
	(gr_arc
		(start 25.459436 -232.967276)
		(mid 25.489372 -233.097611)
		(end 25.575768 -233.199686)
		(stroke
			(width 0.047498)
			(type default)
		)
		(layer "B.Cu")
	)
	(gr_line
		(start 25.459436 -232.681526)
		(end 25.459436 -232.967276)
		(stroke
			(width 0.047498)
			(type default)
		)
		(layer "B.Cu")
	)
	(gr_arc
		(start 25.459436 -231.466136)
		(mid 25.489372 -231.596471)
		(end 25.575768 -231.698546)
		(stroke
			(width 0.047498)
			(type default)
		)
		(layer "B.Cu")
	)
	(gr_line
		(start 25.459436 -231.180386)
		(end 25.459436 -231.466136)
		(stroke
			(width 0.047498)
			(type default)
		)
		(layer "B.Cu")
	)
	(gr_arc
		(start 25.459436 -229.964996)
		(mid 25.489372 -230.095331)
		(end 25.575768 -230.197406)
		(stroke
			(width 0.047498)
			(type default)
		)
		(layer "B.Cu")
	)
	(gr_line
		(start 25.459436 -229.679246)
		(end 25.459436 -229.964996)
		(stroke
			(width 0.047498)
			(type default)
		)
		(layer "B.Cu")
	)
	(gr_arc
		(start 25.459436 -205.134718)
		(mid 25.489372 -205.265053)
		(end 25.575768 -205.367128)
		(stroke
			(width 0.047498)
			(type default)
		)
		(layer "B.Cu")
	)
	(gr_line
		(start 25.459436 -204.848968)
		(end 25.459436 -205.134718)
		(stroke
			(width 0.047498)
			(type default)
		)
		(layer "B.Cu")
	)
	(gr_arc
		(start 25.575768 -232.449116)
		(mid 25.489369 -232.55119)
		(end 25.459436 -232.681526)
		(stroke
			(width 0.047498)
			(type default)
		)
		(layer "B.Cu")
	)
	(gr_arc
		(start 25.575768 -232.449116)
		(mid 25.662046 -232.347017)
		(end 25.691846 -232.216706)
		(stroke
			(width 0.047498)
			(type default)
		)
		(layer "B.Cu")
	)
	(gr_arc
		(start 25.575768 -230.947976)
		(mid 25.489369 -231.05005)
		(end 25.459436 -231.180386)
		(stroke
			(width 0.047498)
			(type default)
		)
		(layer "B.Cu")
	)
	(gr_arc
		(start 25.575768 -230.947976)
		(mid 25.662068 -230.845882)
		(end 25.691846 -230.715566)
		(stroke
			(width 0.047498)
			(type default)
		)
		(layer "B.Cu")
	)
	(gr_arc
		(start 25.575768 -229.446836)
		(mid 25.489369 -229.54891)
		(end 25.459436 -229.679246)
		(stroke
			(width 0.047498)
			(type default)
		)
		(layer "B.Cu")
	)
	(gr_arc
		(start 25.575768 -229.446836)
		(mid 25.662054 -229.344739)
		(end 25.691846 -229.214426)
		(stroke
			(width 0.047498)
			(type default)
		)
		(layer "B.Cu")
	)
	(gr_arc
		(start 25.575768 -204.616558)
		(mid 25.489369 -204.718632)
		(end 25.459436 -204.848968)
		(stroke
			(width 0.047498)
			(type default)
		)
		(layer "B.Cu")
	)
	(gr_arc
		(start 25.575768 -204.616558)
		(mid 25.662062 -204.514462)
		(end 25.691846 -204.384148)
		(stroke
			(width 0.047498)
			(type default)
		)
		(layer "B.Cu")
	)
	(gr_arc
		(start 25.608534 -341.80145)
		(mid 25.680993 -341.795188)
		(end 25.7429 -341.757)
		(stroke
			(width 0.047498)
			(type default)
		)
		(layer "B.Cu")
	)
	(gr_arc
		(start 25.691846 -233.432096)
		(mid 25.661987 -233.301819)
		(end 25.575768 -233.199686)
		(stroke
			(width 0.047498)
			(type default)
		)
		(layer "B.Cu")
	)
	(gr_arc
		(start 25.691846 -231.930956)
		(mid 25.662009 -231.800662)
		(end 25.575768 -231.698546)
		(stroke
			(width 0.047498)
			(type default)
		)
		(layer "B.Cu")
	)
	(gr_arc
		(start 25.691846 -230.429816)
		(mid 25.661995 -230.299533)
		(end 25.575768 -230.197406)
		(stroke
			(width 0.047498)
			(type default)
		)
		(layer "B.Cu")
	)
	(gr_arc
		(start 25.691846 -205.599538)
		(mid 25.662003 -205.469249)
		(end 25.575768 -205.367128)
		(stroke
			(width 0.047498)
			(type default)
		)
		(layer "B.Cu")
	)
	(gr_line
		(start 25.7429 -341.757)
		(end 25.9969 -341.503)
		(stroke
			(width 0.047498)
			(type default)
		)
		(layer "B.Cu")
	)
	(gr_line
		(start 25.830784 -342.265)
		(end 25.9969 -342.431116)
		(stroke
			(width 0.047498)
			(type default)
		)
		(layer "B.Cu")
	)
	(gr_line
		(start 25.913588 -188.191902)
		(end 26.147014 -188.425328)
		(stroke
			(width 0.047498)
			(type default)
		)
		(layer "B.Cu")
	)
	(gr_line
		(start 26.022046 -232.549446)
		(end 26.022046 -233.099356)
		(stroke
			(width 0.047498)
			(type default)
		)
		(layer "B.Cu")
	)
	(gr_line
		(start 26.022046 -231.048306)
		(end 26.022046 -231.598216)
		(stroke
			(width 0.047498)
			(type default)
		)
		(layer "B.Cu")
	)
	(gr_line
		(start 26.022046 -229.547166)
		(end 26.022046 -230.097076)
		(stroke
			(width 0.047498)
			(type default)
		)
		(layer "B.Cu")
	)
	(gr_line
		(start 26.022046 -204.716888)
		(end 26.022046 -205.266798)
		(stroke
			(width 0.047498)
			(type default)
		)
		(layer "B.Cu")
	)
	(gr_arc
		(start 26.183336 -400.761962)
		(mid 26.213282 -400.892287)
		(end 26.299668 -400.994372)
		(stroke
			(width 0.047498)
			(type default)
		)
		(layer "B.Cu")
	)
	(gr_line
		(start 26.183336 -400.476212)
		(end 26.183336 -400.761962)
		(stroke
			(width 0.047498)
			(type default)
		)
		(layer "B.Cu")
	)
	(gr_arc
		(start 26.183336 -399.260822)
		(mid 26.213267 -399.391159)
		(end 26.299668 -399.493232)
		(stroke
			(width 0.047498)
			(type default)
		)
		(layer "B.Cu")
	)
	(gr_line
		(start 26.183336 -398.975072)
		(end 26.183336 -399.260822)
		(stroke
			(width 0.047498)
			(type default)
		)
		(layer "B.Cu")
	)
	(gr_arc
		(start 26.299668 -400.243802)
		(mid 26.213269 -400.345877)
		(end 26.183336 -400.476212)
		(stroke
			(width 0.047498)
			(type default)
		)
		(layer "B.Cu")
	)
	(gr_arc
		(start 26.299668 -400.243802)
		(mid 26.385899 -400.141685)
		(end 26.415746 -400.011392)
		(stroke
			(width 0.047498)
			(type default)
		)
		(layer "B.Cu")
	)
	(gr_arc
		(start 26.299668 -398.742662)
		(mid 26.213291 -398.844742)
		(end 26.183336 -398.975072)
		(stroke
			(width 0.047498)
			(type default)
		)
		(layer "B.Cu")
	)
	(gr_arc
		(start 26.299668 -398.742662)
		(mid 26.385899 -398.640545)
		(end 26.415746 -398.510252)
		(stroke
			(width 0.047498)
			(type default)
		)
		(layer "B.Cu")
	)
	(gr_line
		(start 26.319988 -350.251776)
		(end 26.320242 -350.251776)
		(stroke
			(width 0.047498)
			(type default)
		)
		(layer "B.Cu")
	)
	(gr_arc
		(start 26.415746 -401.226782)
		(mid 26.385949 -401.096464)
		(end 26.299668 -400.994372)
		(stroke
			(width 0.047498)
			(type default)
		)
		(layer "B.Cu")
	)
	(gr_arc
		(start 26.415746 -399.725642)
		(mid 26.385949 -399.595324)
		(end 26.299668 -399.493232)
		(stroke
			(width 0.047498)
			(type default)
		)
		(layer "B.Cu")
	)
	(gr_line
		(start 26.631646 -232.54081)
		(end 26.631646 -233.09072)
		(stroke
			(width 0.047498)
			(type default)
		)
		(layer "B.Cu")
	)
	(gr_line
		(start 26.631646 -190.95466)
		(end 26.631646 -191.1477)
		(stroke
			(width 0.047498)
			(type default)
		)
		(layer "B.Cu")
	)
	(gr_line
		(start 26.650188 -349.921576)
		(end 26.650188 -350.277176)
		(stroke
			(width 0.047498)
			(type default)
		)
		(layer "B.Cu")
	)
	(gr_line
		(start 26.65349 -365.921036)
		(end 26.697432 -365.921036)
		(stroke
			(width 0.047498)
			(type default)
		)
		(layer "B.Cu")
	)
	(gr_line
		(start 26.669746 -367.015014)
		(end 27.082496 -367.015014)
		(stroke
			(width 0.047498)
			(type default)
		)
		(layer "B.Cu")
	)
	(gr_line
		(start 26.745946 -400.344132)
		(end 26.745946 -400.894042)
		(stroke
			(width 0.047498)
			(type default)
		)
		(layer "B.Cu")
	)
	(gr_line
		(start 26.745946 -398.842992)
		(end 26.745946 -399.392902)
		(stroke
			(width 0.047498)
			(type default)
		)
		(layer "B.Cu")
	)
	(gr_line
		(start 26.822146 -442.0997)
		(end 26.923746 -442.0997)
		(stroke
			(width 0.047498)
			(type default)
		)
		(layer "B.Cu")
	)
	(gr_arc
		(start 26.946352 -366.02416)
		(mid 26.832147 -365.947856)
		(end 26.697432 -365.921036)
		(stroke
			(width 0.047498)
			(type default)
		)
		(layer "B.Cu")
	)
	(gr_line
		(start 26.961592 -190.62446)
		(end 26.961592 -190.8175)
		(stroke
			(width 0.047498)
			(type default)
		)
		(layer "B.Cu")
	)
	(gr_arc
		(start 26.961846 -232.20807)
		(mid 26.991643 -232.338388)
		(end 27.077924 -232.44048)
		(stroke
			(width 0.047498)
			(type default)
		)
		(layer "B.Cu")
	)
	(gr_line
		(start 27.037538 -362.5977)
		(end 27.063446 -362.5977)
		(stroke
			(width 0.047498)
			(type default)
		)
		(layer "B.Cu")
	)
	(gr_line
		(start 27.050492 -362.927646)
		(end 27.050746 -362.9279)
		(stroke
			(width 0.047498)
			(type default)
		)
		(layer "B.Cu")
	)
	(gr_arc
		(start 27.052778 -366.4077)
		(mid 27.06887 -366.488129)
		(end 27.1145 -366.55629)
		(stroke
			(width 0.047498)
			(type default)
		)
		(layer "B.Cu")
	)
	(gr_arc
		(start 27.052778 -366.2807)
		(mid 27.025078 -366.141846)
		(end 26.946352 -366.02416)
		(stroke
			(width 0.047498)
			(type default)
		)
		(layer "B.Cu")
	)
	(gr_line
		(start 27.052778 -366.2807)
		(end 27.052778 -366.4077)
		(stroke
			(width 0.047498)
			(type default)
		)
		(layer "B.Cu")
	)
	(gr_arc
		(start 27.077924 -233.19105)
		(mid 26.991693 -233.293167)
		(end 26.961846 -233.42346)
		(stroke
			(width 0.047498)
			(type default)
		)
		(layer "B.Cu")
	)
	(gr_arc
		(start 27.077924 -233.19105)
		(mid 27.164308 -233.088972)
		(end 27.194256 -232.95864)
		(stroke
			(width 0.047498)
			(type default)
		)
		(layer "B.Cu")
	)
	(gr_line
		(start 27.1145 -366.55629)
		(end 27.191462 -366.633506)
		(stroke
			(width 0.047498)
			(type default)
		)
		(layer "B.Cu")
	)
	(gr_arc
		(start 27.126946 -338.9757)
		(mid 27.407223 -338.920022)
		(end 27.644852 -338.761324)
		(stroke
			(width 0.047498)
			(type default)
		)
		(layer "B.Cu")
	)
	(gr_arc
		(start 27.191462 -366.633506)
		(mid 27.30044 -366.671848)
		(end 27.415236 -366.684814)
		(stroke
			(width 0.047498)
			(type default)
		)
		(layer "B.Cu")
	)
	(gr_arc
		(start 27.194256 -232.67289)
		(mid 27.164328 -232.54255)
		(end 27.077924 -232.44048)
		(stroke
			(width 0.047498)
			(type default)
		)
		(layer "B.Cu")
	)
	(gr_line
		(start 27.194256 -232.67289)
		(end 27.194256 -232.95864)
		(stroke
			(width 0.047498)
			(type default)
		)
		(layer "B.Cu")
	)
	(gr_arc
		(start 27.279346 -236.0549)
		(mid 27.420245 -236.026967)
		(end 27.539696 -235.947204)
		(stroke
			(width 0.047498)
			(type default)
		)
		(layer "B.Cu")
	)
	(gr_arc
		(start 27.376628 -442.178694)
		(mid 27.657675 -442.136844)
		(end 27.787346 -441.884054)
		(stroke
			(width 0.047498)
			(type default)
		)
		(layer "B.Cu")
	)
	(gr_line
		(start 27.415236 -366.684814)
		(end 27.685746 -366.684814)
		(stroke
			(width 0.047498)
			(type default)
		)
		(layer "B.Cu")
	)
	(gr_arc
		(start 27.469846 -236.46384)
		(mid 27.382429 -236.405523)
		(end 27.279346 -236.3851)
		(stroke
			(width 0.047498)
			(type default)
		)
		(layer "B.Cu")
	)
	(gr_line
		(start 27.469846 -236.46384)
		(end 27.64663 -236.640878)
		(stroke
			(width 0.047498)
			(type default)
		)
		(layer "B.Cu")
	)
	(gr_line
		(start 27.539696 -235.947204)
		(end 27.711146 -235.7755)
		(stroke
			(width 0.047498)
			(type default)
		)
		(layer "B.Cu")
	)
	(gr_arc
		(start 27.642312 -339.519514)
		(mid 27.405875 -339.361439)
		(end 27.126946 -339.3059)
		(stroke
			(width 0.047498)
			(type default)
		)
		(layer "B.Cu")
	)
	(gr_line
		(start 27.642312 -339.519514)
		(end 27.743912 -339.62086)
		(stroke
			(width 0.047498)
			(type default)
		)
		(layer "B.Cu")
	)
	(gr_line
		(start 27.644852 -338.761324)
		(end 27.743912 -338.66201)
		(stroke
			(width 0.047498)
			(type default)
		)
		(layer "B.Cu")
	)
	(gr_line
		(start 27.685746 -367.01476)
		(end 27.685746 -367.015014)
		(stroke
			(width 0.047498)
			(type default)
		)
		(layer "B.Cu")
	)
	(gr_line
		(start 27.725116 -442.77407)
		(end 27.812746 -442.8617)
		(stroke
			(width 0.047498)
			(type default)
		)
		(layer "B.Cu")
	)
	(gr_line
		(start 27.787346 -441.8457)
		(end 27.787346 -441.884054)
		(stroke
			(width 0.047498)
			(type default)
		)
		(layer "B.Cu")
	)
	(gr_arc
		(start 27.901646 -366.595406)
		(mid 27.929834 -366.55322)
		(end 27.939746 -366.503458)
		(stroke
			(width 0.047498)
			(type default)
		)
		(layer "B.Cu")
	)
	(gr_arc
		(start 27.94127 -345.3257)
		(mid 28.174545 -345.27928)
		(end 28.372308 -345.147138)
		(stroke
			(width 0.047498)
			(type default)
		)
		(layer "B.Cu")
	)
	(gr_line
		(start 28.136088 -366.828324)
		(end 28.156916 -366.807496)
		(stroke
			(width 0.047498)
			(type default)
		)
		(layer "B.Cu")
	)
	(gr_arc
		(start 28.156916 -366.807496)
		(mid 28.240583 -366.682346)
		(end 28.269946 -366.5347)
		(stroke
			(width 0.047498)
			(type default)
		)
		(layer "B.Cu")
	)
	(gr_line
		(start 28.372308 -345.147138)
		(end 28.521914 -344.997532)
		(stroke
			(width 0.047498)
			(type default)
		)
		(layer "B.Cu")
	)
	(gr_arc
		(start 28.55976 -344.981784)
		(mid 28.539265 -344.985879)
		(end 28.521914 -344.997532)
		(stroke
			(width 0.047498)
			(type default)
		)
		(layer "B.Cu")
	)
	(gr_arc
		(start 28.701746 -345.8337)
		(mid 28.5048 -345.702105)
		(end 28.272486 -345.6559)
		(stroke
			(width 0.047498)
			(type default)
		)
		(layer "B.Cu")
	)
	(gr_arc
		(start 29.015436 -32.3215)
		(mid 29.279616 -32.23088)
		(end 29.432504 -31.997142)
		(stroke
			(width 0.047498)
			(type default)
		)
		(layer "B.Cu")
	)
	(gr_arc
		(start 29.113988 -32.664654)
		(mid 29.082115 -32.65497)
		(end 29.048964 -32.6517)
		(stroke
			(width 0.047498)
			(type default)
		)
		(layer "B.Cu")
	)
	(gr_line
		(start 29.113988 -32.664654)
		(end 29.147516 -32.678624)
		(stroke
			(width 0.047498)
			(type default)
		)
		(layer "B.Cu")
	)
	(gr_arc
		(start 29.209746 -362.5977)
		(mid 29.454282 -362.549015)
		(end 29.661612 -362.410502)
		(stroke
			(width 0.047498)
			(type default)
		)
		(layer "B.Cu")
	)
	(gr_arc
		(start 29.261816 -32.754824)
		(mid 29.208407 -32.711116)
		(end 29.147516 -32.678624)
		(stroke
			(width 0.047498)
			(type default)
		)
		(layer "B.Cu")
	)
	(gr_line
		(start 29.261816 -32.754824)
		(end 29.356304 -32.849312)
		(stroke
			(width 0.047498)
			(type default)
		)
		(layer "B.Cu")
	)
	(gr_arc
		(start 29.432504 -33.0327)
		(mid 29.412646 -32.933428)
		(end 29.356304 -32.849312)
		(stroke
			(width 0.047498)
			(type default)
		)
		(layer "B.Cu")
	)
	(gr_line
		(start 29.661612 -362.410502)
		(end 29.81706 -362.255054)
		(stroke
			(width 0.047498)
			(type default)
		)
		(layer "B.Cu")
	)
	(gr_arc
		(start 29.81706 -363.213904)
		(mid 29.500315 -363.002262)
		(end 29.126688 -362.9279)
		(stroke
			(width 0.047498)
			(type default)
		)
		(layer "B.Cu")
	)
	(gr_line
		(start 31.088838 -64.017144)
		(end 31.088838 -64.182752)
		(stroke
			(width 0.047498)
			(type default)
		)
		(layer "B.Cu")
	)
	(gr_arc
		(start 31.139892 -63.893954)
		(mid 31.102102 -63.950466)
		(end 31.088838 -64.017144)
		(stroke
			(width 0.047498)
			(type default)
		)
		(layer "B.Cu")
	)
	(gr_line
		(start 31.190946 -63.2841)
		(end 31.293816 -63.38697)
		(stroke
			(width 0.047498)
			(type default)
		)
		(layer "B.Cu")
	)
	(gr_arc
		(start 31.263082 -63.8429)
		(mid 31.196418 -63.856193)
		(end 31.139892 -63.893954)
		(stroke
			(width 0.047498)
			(type default)
		)
		(layer "B.Cu")
	)
	(gr_line
		(start 31.263082 -63.8429)
		(end 31.264606 -63.8429)
		(stroke
			(width 0.047498)
			(type default)
		)
		(layer "B.Cu")
	)
	(gr_arc
		(start 31.293816 -63.38697)
		(mid 31.433077 -63.480021)
		(end 31.597346 -63.5127)
		(stroke
			(width 0.047498)
			(type default)
		)
		(layer "B.Cu")
	)
	(gr_arc
		(start 31.341822 -475.198186)
		(mid 31.441586 -475.439036)
		(end 31.682436 -475.5388)
		(stroke
			(width 0.047498)
			(type default)
		)
		(layer "B.Cu")
	)
	(gr_arc
		(start 31.447232 -372.345204)
		(mid 31.535841 -372.559095)
		(end 31.749746 -372.647718)
		(stroke
			(width 0.047498)
			(type default)
		)
		(layer "B.Cu")
	)
	(gr_line
		(start 31.447232 -372.1227)
		(end 31.447232 -372.345204)
		(stroke
			(width 0.047498)
			(type default)
		)
		(layer "B.Cu")
	)
	(gr_line
		(start 31.79572 -65.371472)
		(end 32.003492 -65.1637)
		(stroke
			(width 0.047498)
			(type default)
		)
		(layer "B.Cu")
	)
	(gr_arc
		(start 31.854648 -475.869)
		(mid 31.604472 -475.918805)
		(end 31.392368 -476.060516)
		(stroke
			(width 0.047498)
			(type default)
		)
		(layer "B.Cu")
	)
	(gr_line
		(start 32.022034 -65.144904)
		(end 32.032956 -65.133982)
		(stroke
			(width 0.047498)
			(type default)
		)
		(layer "B.Cu")
	)
	(gr_arc
		(start 32.074866 -372.977918)
		(mid 31.801456 -373.032339)
		(end 31.56966 -373.187214)
		(stroke
			(width 0.047498)
			(type default)
		)
		(layer "B.Cu")
	)
	(gr_line
		(start 32.262572 -65.371218)
		(end 32.262826 -65.371472)
		(stroke
			(width 0.047498)
			(type default)
		)
		(layer "B.Cu")
	)
	(gr_arc
		(start 32.91459 -181.065424)
		(mid 32.903402 -180.932106)
		(end 32.832294 -180.81879)
		(stroke
			(width 0.047498)
			(type default)
		)
		(layer "B.Cu")
	)
	(gr_arc
		(start 32.91459 -181.065424)
		(mid 32.925699 -181.198579)
		(end 32.996632 -181.311804)
		(stroke
			(width 0.047498)
			(type default)
		)
		(layer "B.Cu")
	)
	(gr_line
		(start 32.996632 -181.311804)
		(end 33.198816 -181.513988)
		(stroke
			(width 0.047498)
			(type default)
		)
		(layer "B.Cu")
	)
	(gr_arc
		(start 33.198816 -181.513988)
		(mid 33.312041 -181.584947)
		(end 33.445196 -181.59603)
		(stroke
			(width 0.047498)
			(type default)
		)
		(layer "B.Cu")
	)
	(gr_line
		(start 33.301178 -180.820568)
		(end 33.690052 -181.209442)
		(stroke
			(width 0.047498)
			(type default)
		)
		(layer "B.Cu")
	)
	(gr_arc
		(start 33.69183 -181.678326)
		(mid 33.578517 -181.607201)
		(end 33.445196 -181.59603)
		(stroke
			(width 0.047498)
			(type default)
		)
		(layer "B.Cu")
	)
	(gr_line
		(start 33.888934 -472.866466)
		(end 33.925256 -472.902788)
		(stroke
			(width 0.047498)
			(type default)
		)
		(layer "B.Cu")
	)
	(gr_line
		(start 34.183574 -189.018418)
		(end 34.183828 -189.018418)
		(stroke
			(width 0.047498)
			(type default)
		)
		(layer "B.Cu")
	)
	(gr_line
		(start 34.23031 -461.460596)
		(end 34.230564 -461.46085)
		(stroke
			(width 0.047498)
			(type default)
		)
		(layer "B.Cu")
	)
	(gr_line
		(start 34.417254 -188.784738)
		(end 34.417254 -188.784992)
		(stroke
			(width 0.047498)
			(type default)
		)
		(layer "B.Cu")
	)
	(gr_line
		(start 34.5821 -368.462306)
		(end 34.5821 -368.655346)
		(stroke
			(width 0.047498)
			(type default)
		)
		(layer "B.Cu")
	)
	(gr_line
		(start 34.5821 -367.462054)
		(end 34.5821 -367.655094)
		(stroke
			(width 0.047498)
			(type default)
		)
		(layer "B.Cu")
	)
	(gr_arc
		(start 34.6202 -473.075)
		(mid 34.783499 -473.042518)
		(end 34.921952 -472.950032)
		(stroke
			(width 0.047498)
			(type default)
		)
		(layer "B.Cu")
	)
	(gr_arc
		(start 34.860738 -473.5576)
		(mid 34.692119 -473.444863)
		(end 34.4932 -473.4052)
		(stroke
			(width 0.047498)
			(type default)
		)
		(layer "B.Cu")
	)
	(gr_line
		(start 34.860738 -473.5576)
		(end 35.051746 -473.748354)
		(stroke
			(width 0.047498)
			(type default)
		)
		(layer "B.Cu")
	)
	(gr_line
		(start 34.912046 -368.792506)
		(end 34.912046 -368.985546)
		(stroke
			(width 0.047498)
			(type default)
		)
		(layer "B.Cu")
	)
	(gr_line
		(start 34.912046 -367.131854)
		(end 34.912046 -367.324894)
		(stroke
			(width 0.047498)
			(type default)
		)
		(layer "B.Cu")
	)
	(gr_line
		(start 34.921952 -472.950032)
		(end 35.051746 -472.820238)
		(stroke
			(width 0.047498)
			(type default)
		)
		(layer "B.Cu")
	)
	(gr_line
		(start 35.262312 -188.767466)
		(end 35.267646 -188.7728)
		(stroke
			(width 0.047498)
			(type default)
		)
		(layer "B.Cu")
	)
	(gr_arc
		(start 35.9283 -370.1415)
		(mid 36.085972 -370.110161)
		(end 36.219638 -370.02085)
		(stroke
			(width 0.047498)
			(type default)
		)
		(layer "B.Cu")
	)
	(gr_line
		(start 36.219638 -370.02085)
		(end 36.321746 -369.918742)
		(stroke
			(width 0.047498)
			(type default)
		)
		(layer "B.Cu")
	)
	(gr_arc
		(start 36.2966 -370.84)
		(mid 36.188727 -370.579573)
		(end 35.9283 -370.4717)
		(stroke
			(width 0.047498)
			(type default)
		)
		(layer "B.Cu")
	)
	(gr_line
		(start 37.4904 -473.3798)
		(end 37.490654 -473.3798)
		(stroke
			(width 0.047498)
			(type default)
		)
		(layer "B.Cu")
	)
	(gr_arc
		(start 37.71265 -61.3537)
		(mid 37.812159 -61.333859)
		(end 37.896546 -61.2775)
		(stroke
			(width 0.047498)
			(type default)
		)
		(layer "B.Cu")
	)
	(gr_line
		(start 37.8206 -473.0496)
		(end 37.8206 -473.3798)
		(stroke
			(width 0.047498)
			(type default)
		)
		(layer "B.Cu")
	)
	(gr_line
		(start 37.896546 -61.2775)
		(end 37.970206 -61.20384)
		(stroke
			(width 0.047498)
			(type default)
		)
		(layer "B.Cu")
	)
	(gr_arc
		(start 37.970206 -61.20384)
		(mid 38.066085 -61.060391)
		(end 38.099746 -60.891166)
		(stroke
			(width 0.047498)
			(type default)
		)
		(layer "B.Cu")
	)
	(gr_line
		(start 37.985954 -195.325492)
		(end 38.010338 -195.349876)
		(stroke
			(width 0.047498)
			(type default)
		)
		(layer "B.Cu")
	)
	(gr_line
		(start 37.985954 -195.325238)
		(end 37.985954 -195.325492)
		(stroke
			(width 0.047498)
			(type default)
		)
		(layer "B.Cu")
	)
	(gr_line
		(start 38.081204 -459.387448)
		(end 38.31463 -459.154022)
		(stroke
			(width 0.047498)
			(type default)
		)
		(layer "B.Cu")
	)
	(gr_arc
		(start 38.099746 -61.850016)
		(mid 37.915735 -61.727064)
		(end 37.69868 -61.6839)
		(stroke
			(width 0.047498)
			(type default)
		)
		(layer "B.Cu")
	)
	(gr_line
		(start 38.21938 -195.092066)
		(end 38.248082 -195.120768)
		(stroke
			(width 0.047498)
			(type default)
		)
		(layer "B.Cu")
	)
	(gr_arc
		(start 38.692836 -452.955152)
		(mid 38.722778 -453.08548)
		(end 38.809168 -453.187562)
		(stroke
			(width 0.047498)
			(type default)
		)
		(layer "B.Cu")
	)
	(gr_line
		(start 38.692836 -452.669402)
		(end 38.692836 -452.955152)
		(stroke
			(width 0.047498)
			(type default)
		)
		(layer "B.Cu")
	)
	(gr_arc
		(start 38.692836 -451.454012)
		(mid 38.722764 -451.584352)
		(end 38.809168 -451.686422)
		(stroke
			(width 0.047498)
			(type default)
		)
		(layer "B.Cu")
	)
	(gr_line
		(start 38.692836 -451.168262)
		(end 38.692836 -451.454012)
		(stroke
			(width 0.047498)
			(type default)
		)
		(layer "B.Cu")
	)
	(gr_arc
		(start 38.692836 -449.952872)
		(mid 38.722786 -450.083194)
		(end 38.809168 -450.185282)
		(stroke
			(width 0.047498)
			(type default)
		)
		(layer "B.Cu")
	)
	(gr_line
		(start 38.692836 -449.667122)
		(end 38.692836 -449.952872)
		(stroke
			(width 0.047498)
			(type default)
		)
		(layer "B.Cu")
	)
	(gr_arc
		(start 38.692836 -448.451732)
		(mid 38.722771 -448.582066)
		(end 38.809168 -448.684142)
		(stroke
			(width 0.047498)
			(type default)
		)
		(layer "B.Cu")
	)
	(gr_line
		(start 38.692836 -448.165982)
		(end 38.692836 -448.451732)
		(stroke
			(width 0.047498)
			(type default)
		)
		(layer "B.Cu")
	)
	(gr_arc
		(start 38.692836 -446.950592)
		(mid 38.722756 -447.080938)
		(end 38.809168 -447.183002)
		(stroke
			(width 0.047498)
			(type default)
		)
		(layer "B.Cu")
	)
	(gr_line
		(start 38.692836 -446.664842)
		(end 38.692836 -446.950592)
		(stroke
			(width 0.047498)
			(type default)
		)
		(layer "B.Cu")
	)
	(gr_arc
		(start 38.809168 -452.436992)
		(mid 38.722802 -452.539074)
		(end 38.692836 -452.669402)
		(stroke
			(width 0.047498)
			(type default)
		)
		(layer "B.Cu")
	)
	(gr_arc
		(start 38.809168 -452.436992)
		(mid 38.895399 -452.334875)
		(end 38.925246 -452.204582)
		(stroke
			(width 0.047498)
			(type default)
		)
		(layer "B.Cu")
	)
	(gr_arc
		(start 38.809168 -450.935852)
		(mid 38.722787 -451.037931)
		(end 38.692836 -451.168262)
		(stroke
			(width 0.047498)
			(type default)
		)
		(layer "B.Cu")
	)
	(gr_arc
		(start 38.809168 -450.935852)
		(mid 38.895399 -450.833735)
		(end 38.925246 -450.703442)
		(stroke
			(width 0.047498)
			(type default)
		)
		(layer "B.Cu")
	)
	(gr_arc
		(start 38.809168 -449.434712)
		(mid 38.722773 -449.536788)
		(end 38.692836 -449.667122)
		(stroke
			(width 0.047498)
			(type default)
		)
		(layer "B.Cu")
	)
	(gr_arc
		(start 38.809168 -449.434712)
		(mid 38.895399 -449.332595)
		(end 38.925246 -449.202302)
		(stroke
			(width 0.047498)
			(type default)
		)
		(layer "B.Cu")
	)
	(gr_arc
		(start 38.809168 -447.933572)
		(mid 38.722795 -448.035652)
		(end 38.692836 -448.165982)
		(stroke
			(width 0.047498)
			(type default)
		)
		(layer "B.Cu")
	)
	(gr_arc
		(start 38.809168 -447.933572)
		(mid 38.895399 -447.831455)
		(end 38.925246 -447.701162)
		(stroke
			(width 0.047498)
			(type default)
		)
		(layer "B.Cu")
	)
	(gr_arc
		(start 38.809168 -446.432432)
		(mid 38.72278 -446.53451)
		(end 38.692836 -446.664842)
		(stroke
			(width 0.047498)
			(type default)
		)
		(layer "B.Cu")
	)
	(gr_arc
		(start 38.809168 -446.432432)
		(mid 38.895399 -446.330315)
		(end 38.925246 -446.200022)
		(stroke
			(width 0.047498)
			(type default)
		)
		(layer "B.Cu")
	)
	(gr_line
		(start 38.925246 -457.6064)
		(end 38.9255 -457.6064)
		(stroke
			(width 0.047498)
			(type default)
		)
		(layer "B.Cu")
	)
	(gr_arc
		(start 38.925246 -453.419972)
		(mid 38.895449 -453.289654)
		(end 38.809168 -453.187562)
		(stroke
			(width 0.047498)
			(type default)
		)
		(layer "B.Cu")
	)
	(gr_arc
		(start 38.925246 -451.918832)
		(mid 38.895449 -451.788514)
		(end 38.809168 -451.686422)
		(stroke
			(width 0.047498)
			(type default)
		)
		(layer "B.Cu")
	)
	(gr_arc
		(start 38.925246 -450.417692)
		(mid 38.895449 -450.287374)
		(end 38.809168 -450.185282)
		(stroke
			(width 0.047498)
			(type default)
		)
		(layer "B.Cu")
	)
	(gr_arc
		(start 38.925246 -448.916552)
		(mid 38.895449 -448.786234)
		(end 38.809168 -448.684142)
		(stroke
			(width 0.047498)
			(type default)
		)
		(layer "B.Cu")
	)
	(gr_arc
		(start 38.925246 -447.415412)
		(mid 38.895449 -447.285094)
		(end 38.809168 -447.183002)
		(stroke
			(width 0.047498)
			(type default)
		)
		(layer "B.Cu")
	)
	(gr_line
		(start 39.255446 -457.2762)
		(end 39.255446 -457.6064)
		(stroke
			(width 0.047498)
			(type default)
		)
		(layer "B.Cu")
	)
	(gr_line
		(start 39.255446 -452.537322)
		(end 39.255446 -453.087232)
		(stroke
			(width 0.047498)
			(type default)
		)
		(layer "B.Cu")
	)
	(gr_line
		(start 39.255446 -451.036182)
		(end 39.255446 -451.586092)
		(stroke
			(width 0.047498)
			(type default)
		)
		(layer "B.Cu")
	)
	(gr_line
		(start 39.255446 -449.535042)
		(end 39.255446 -450.084952)
		(stroke
			(width 0.047498)
			(type default)
		)
		(layer "B.Cu")
	)
	(gr_line
		(start 39.255446 -448.033902)
		(end 39.255446 -448.583812)
		(stroke
			(width 0.047498)
			(type default)
		)
		(layer "B.Cu")
	)
	(gr_line
		(start 39.255446 -446.532762)
		(end 39.255446 -447.082672)
		(stroke
			(width 0.047498)
			(type default)
		)
		(layer "B.Cu")
	)
	(gr_line
		(start 41.61663 -112.286542)
		(end 41.622218 -112.291114)
		(stroke
			(width 0.047498)
			(type default)
		)
		(layer "B.Cu")
	)
	(gr_line
		(start 41.82491 -112.030256)
		(end 41.82491 -112.03051)
		(stroke
			(width 0.047498)
			(type default)
		)
		(layer "B.Cu")
	)
	(gr_arc
		(start 43.931078 -361.73664)
		(mid 43.960875 -361.866958)
		(end 44.047156 -361.96905)
		(stroke
			(width 0.047498)
			(type default)
		)
		(layer "B.Cu")
	)
	(gr_line
		(start 43.931078 -361.45089)
		(end 43.931078 -361.73664)
		(stroke
			(width 0.047498)
			(type default)
		)
		(layer "B.Cu")
	)
	(gr_arc
		(start 44.047156 -361.21848)
		(mid 43.960925 -361.320597)
		(end 43.931078 -361.45089)
		(stroke
			(width 0.047498)
			(type default)
		)
		(layer "B.Cu")
	)
	(gr_arc
		(start 44.047156 -361.21848)
		(mid 44.133571 -361.11641)
		(end 44.163488 -360.98607)
		(stroke
			(width 0.047498)
			(type default)
		)
		(layer "B.Cu")
	)
	(gr_arc
		(start 44.163488 -362.20146)
		(mid 44.133552 -362.071126)
		(end 44.047156 -361.96905)
		(stroke
			(width 0.047498)
			(type default)
		)
		(layer "B.Cu")
	)
	(gr_line
		(start 44.493688 -361.31881)
		(end 44.493688 -361.86872)
		(stroke
			(width 0.047498)
			(type default)
		)
		(layer "B.Cu")
	)
	(gr_line
		(start 46.113446 -115.875054)
		(end 46.188122 -115.904518)
		(stroke
			(width 0.047498)
			(type default)
		)
		(layer "B.Cu")
	)
	(gr_line
		(start 46.188122 -115.904518)
		(end 46.207426 -115.904518)
		(stroke
			(width 0.047498)
			(type default)
		)
		(layer "B.Cu")
	)
	(gr_line
		(start 46.224952 -115.56111)
		(end 46.278038 -115.577874)
		(stroke
			(width 0.047498)
			(type default)
		)
		(layer "B.Cu")
	)
	(gr_line
		(start 203.959968 -163.556442)
		(end 203.960222 -163.556442)
		(stroke
			(width 0.047498)
			(type default)
		)
		(layer "B.Cu")
	)
	(gr_line
		(start 204.082904 -163.249864)
		(end 204.083158 -163.249864)
		(stroke
			(width 0.047498)
			(type default)
		)
		(layer "B.Cu")
	)
	(gr_line
		(start 207.564736 -369.817904)
		(end 207.569308 -369.823492)
		(stroke
			(width 0.047498)
			(type default)
		)
		(layer "B.Cu")
	)
	(gr_line
		(start 207.569308 -369.823492)
		(end 207.67167 -369.94973)
		(stroke
			(width 0.047498)
			(type default)
		)
		(layer "B.Cu")
	)
	(gr_line
		(start 207.73644 -370.02974)
		(end 207.779366 -370.082572)
		(stroke
			(width 0.047498)
			(type default)
		)
		(layer "B.Cu")
	)
	(gr_line
		(start 207.825848 -369.61572)
		(end 207.912462 -369.7224)
		(stroke
			(width 0.047498)
			(type default)
		)
		(layer "B.Cu")
	)
	(gr_line
		(start 208.013046 -369.8494)
		(end 208.02473 -369.861084)
		(stroke
			(width 0.047498)
			(type default)
		)
		(layer "B.Cu")
	)
	(gr_line
		(start 208.01457 -369.848384)
		(end 208.013046 -369.8494)
		(stroke
			(width 0.047498)
			(type default)
		)
		(layer "B.Cu")
	)
	(gr_line
		(start 211.97697 -370.036598)
		(end 212.01761 -370.085874)
		(stroke
			(width 0.047498)
			(type default)
		)
		(layer "B.Cu")
	)
	(gr_line
		(start 212.25129 -369.852702)
		(end 212.252306 -369.851686)
		(stroke
			(width 0.047498)
			(type default)
		)
		(layer "B.Cu")
	)
	(gr_line
		(start 212.25129 -369.852702)
		(end 212.262212 -369.863624)
		(stroke
			(width 0.047498)
			(type default)
		)
		(layer "B.Cu")
	)
	(gr_arc
		(start 214.890604 -269.745968)
		(mid 214.924363 -269.744612)
		(end 214.957914 -269.740634)
		(stroke
			(width 0.047498)
			(type default)
		)
		(layer "B.Cu")
	)
	(gr_arc
		(start 214.957914 -269.740634)
		(mid 215.046653 -269.716704)
		(end 215.128348 -269.674594)
		(stroke
			(width 0.047498)
			(type default)
		)
		(layer "B.Cu")
	)
	(gr_arc
		(start 215.054434 -63.63716)
		(mid 215.220357 -63.604156)
		(end 215.361012 -63.51016)
		(stroke
			(width 0.047498)
			(type default)
		)
		(layer "B.Cu")
	)
	(gr_arc
		(start 215.097868 -166.7002)
		(mid 215.264901 -166.631013)
		(end 215.334088 -166.46398)
		(stroke
			(width 0.047498)
			(type default)
		)
		(layer "B.Cu")
	)
	(gr_arc
		(start 215.128348 -269.674594)
		(mid 215.164197 -269.648552)
		(end 215.197182 -269.618968)
		(stroke
			(width 0.047498)
			(type default)
		)
		(layer "B.Cu")
	)
	(gr_line
		(start 215.223344 -270.076168)
		(end 215.391746 -270.076168)
		(stroke
			(width 0.047498)
			(type default)
		)
		(layer "B.Cu")
	)
	(gr_arc
		(start 215.297766 -167.0304)
		(mid 215.620378 -166.966228)
		(end 215.893904 -166.783512)
		(stroke
			(width 0.047498)
			(type default)
		)
		(layer "B.Cu")
	)
	(gr_line
		(start 215.387174 -63.96736)
		(end 215.53932 -63.96736)
		(stroke
			(width 0.047498)
			(type default)
		)
		(layer "B.Cu")
	)
	(gr_arc
		(start 215.53932 -63.96736)
		(mid 215.734501 -63.928536)
		(end 215.9 -63.818008)
		(stroke
			(width 0.047498)
			(type default)
		)
		(layer "B.Cu")
	)
	(gr_line
		(start 215.566244 -372.51767)
		(end 215.617552 -372.466108)
		(stroke
			(width 0.047498)
			(type default)
		)
		(layer "B.Cu")
	)
	(gr_arc
		(start 215.74887 -475.4245)
		(mid 215.774286 -475.42266)
		(end 215.799162 -475.417134)
		(stroke
			(width 0.047498)
			(type default)
		)
		(layer "B.Cu")
	)
	(gr_arc
		(start 215.799162 -475.417134)
		(mid 215.890189 -475.353593)
		(end 215.925146 -475.248224)
		(stroke
			(width 0.047498)
			(type default)
		)
		(layer "B.Cu")
	)
	(gr_line
		(start 215.817958 -269.899638)
		(end 216.111582 -269.606014)
		(stroke
			(width 0.047498)
			(type default)
		)
		(layer "B.Cu")
	)
	(gr_line
		(start 215.893904 -166.783512)
		(end 216.197688 -166.479728)
		(stroke
			(width 0.047498)
			(type default)
		)
		(layer "B.Cu")
	)
	(gr_arc
		(start 215.899746 -475.7547)
		(mid 216.248483 -475.685289)
		(end 216.544144 -475.487746)
		(stroke
			(width 0.047498)
			(type default)
		)
		(layer "B.Cu")
	)
	(gr_line
		(start 215.9 -63.818008)
		(end 216.224612 -63.493396)
		(stroke
			(width 0.047498)
			(type default)
		)
		(layer "B.Cu")
	)
	(gr_line
		(start 216.286334 -372.646702)
		(end 216.481152 -372.451884)
		(stroke
			(width 0.047498)
			(type default)
		)
		(layer "B.Cu")
	)
	(gr_line
		(start 216.544144 -475.487746)
		(end 216.788746 -475.243144)
		(stroke
			(width 0.047498)
			(type default)
		)
		(layer "B.Cu")
	)
	(gr_arc
		(start 219.963746 -473.341446)
		(mid 220.128068 -473.273361)
		(end 220.196156 -473.109036)
		(stroke
			(width 0.047498)
			(type default)
		)
		(layer "B.Cu")
	)
	(gr_arc
		(start 220.196156 -473.86621)
		(mid 219.980912 -473.722395)
		(end 219.727018 -473.6719)
		(stroke
			(width 0.047498)
			(type default)
		)
		(layer "B.Cu")
	)
	(gr_line
		(start 220.196156 -472.90736)
		(end 220.196156 -473.109036)
		(stroke
			(width 0.047498)
			(type default)
		)
		(layer "B.Cu")
	)
	(gr_arc
		(start 222.554546 -61.2267)
		(mid 222.604781 -61.224465)
		(end 222.654622 -61.21781)
		(stroke
			(width 0.047498)
			(type default)
		)
		(layer "B.Cu")
	)
	(gr_arc
		(start 222.654622 -61.21781)
		(mid 222.789052 -61.19107)
		(end 222.903034 -61.11494)
		(stroke
			(width 0.047498)
			(type default)
		)
		(layer "B.Cu")
	)
	(gr_arc
		(start 222.716598 -267.254482)
		(mid 222.957992 -267.224384)
		(end 223.070928 -267.008864)
		(stroke
			(width 0.047498)
			(type default)
		)
		(layer "B.Cu")
	)
	(gr_arc
		(start 222.742506 -61.65596)
		(mid 222.632972 -61.582702)
		(end 222.503746 -61.5569)
		(stroke
			(width 0.047498)
			(type default)
		)
		(layer "B.Cu")
	)
	(gr_line
		(start 222.742506 -61.65596)
		(end 223.031812 -61.945012)
		(stroke
			(width 0.047498)
			(type default)
		)
		(layer "B.Cu")
	)
	(gr_arc
		(start 222.771716 -370.1923)
		(mid 222.951321 -370.117905)
		(end 223.025716 -369.9383)
		(stroke
			(width 0.047498)
			(type default)
		)
		(layer "B.Cu")
	)
	(gr_arc
		(start 222.778066 -164.244782)
		(mid 222.885279 -164.223456)
		(end 222.976186 -164.16274)
		(stroke
			(width 0.047498)
			(type default)
		)
		(layer "B.Cu")
	)
	(gr_line
		(start 222.903034 -61.11494)
		(end 223.031812 -60.986162)
		(stroke
			(width 0.047498)
			(type default)
		)
		(layer "B.Cu")
	)
	(gr_arc
		(start 222.922592 -164.6936)
		(mid 222.791266 -164.605811)
		(end 222.636334 -164.574982)
		(stroke
			(width 0.047498)
			(type default)
		)
		(layer "B.Cu")
	)
	(gr_line
		(start 222.922592 -164.6936)
		(end 223.163384 -164.934392)
		(stroke
			(width 0.047498)
			(type default)
		)
		(layer "B.Cu")
	)
	(gr_line
		(start 222.956374 -267.792962)
		(end 223.002856 -267.83919)
		(stroke
			(width 0.047498)
			(type default)
		)
		(layer "B.Cu")
	)
	(gr_arc
		(start 222.974662 -370.837714)
		(mid 222.882346 -370.614798)
		(end 222.659448 -370.5225)
		(stroke
			(width 0.047498)
			(type default)
		)
		(layer "B.Cu")
	)
	(gr_line
		(start 222.976186 -164.16274)
		(end 223.163384 -163.975542)
		(stroke
			(width 0.047498)
			(type default)
		)
		(layer "B.Cu")
	)
	(gr_line
		(start 223.070928 -267.008864)
		(end 223.071182 -266.97813)
		(stroke
			(width 0.047498)
			(type default)
		)
		(layer "B.Cu")
	)
	(gr_line
		(start 1.388872 -424.85564)
		(end 1.388872 -424.14444)
		(stroke
			(width 0.2)
			(type default)
		)
		(layer "In1.Cu")
	)
	(gr_line
		(start 1.388872 -424.14444)
		(end 4.995672 -424.14444)
		(stroke
			(width 0.2)
			(type default)
		)
		(layer "In1.Cu")
	)
	(gr_line
		(start 1.388872 -423.855642)
		(end 1.388872 -423.144442)
		(stroke
			(width 0.2)
			(type default)
		)
		(layer "In1.Cu")
	)
	(gr_line
		(start 1.388872 -423.144442)
		(end 4.995672 -423.144442)
		(stroke
			(width 0.2)
			(type default)
		)
		(layer "In1.Cu")
	)
	(gr_line
		(start 1.388872 -420.855648)
		(end 1.388872 -420.144448)
		(stroke
			(width 0.2)
			(type default)
		)
		(layer "In1.Cu")
	)
	(gr_line
		(start 1.388872 -420.144448)
		(end 4.995672 -420.144448)
		(stroke
			(width 0.2)
			(type default)
		)
		(layer "In1.Cu")
	)
	(gr_line
		(start 1.388872 -419.85565)
		(end 1.388872 -419.14445)
		(stroke
			(width 0.2)
			(type default)
		)
		(layer "In1.Cu")
	)
	(gr_line
		(start 1.388872 -419.14445)
		(end 4.995672 -419.14445)
		(stroke
			(width 0.2)
			(type default)
		)
		(layer "In1.Cu")
	)
	(gr_line
		(start 1.388872 -416.855656)
		(end 1.388872 -416.144456)
		(stroke
			(width 0.2)
			(type default)
		)
		(layer "In1.Cu")
	)
	(gr_line
		(start 1.388872 -416.144456)
		(end 4.995672 -416.144456)
		(stroke
			(width 0.2)
			(type default)
		)
		(layer "In1.Cu")
	)
	(gr_line
		(start 1.388872 -415.855658)
		(end 1.388872 -415.144458)
		(stroke
			(width 0.2)
			(type default)
		)
		(layer "In1.Cu")
	)
	(gr_line
		(start 1.388872 -415.144458)
		(end 4.995672 -415.144458)
		(stroke
			(width 0.2)
			(type default)
		)
		(layer "In1.Cu")
	)
	(gr_line
		(start 1.388872 -412.855664)
		(end 1.388872 -412.144464)
		(stroke
			(width 0.2)
			(type default)
		)
		(layer "In1.Cu")
	)
	(gr_line
		(start 1.388872 -412.144464)
		(end 4.995672 -412.144464)
		(stroke
			(width 0.2)
			(type default)
		)
		(layer "In1.Cu")
	)
	(gr_line
		(start 1.388872 -411.855666)
		(end 1.388872 -411.144466)
		(stroke
			(width 0.2)
			(type default)
		)
		(layer "In1.Cu")
	)
	(gr_line
		(start 1.388872 -411.144466)
		(end 4.995672 -411.144466)
		(stroke
			(width 0.2)
			(type default)
		)
		(layer "In1.Cu")
	)
	(gr_line
		(start 1.388872 -408.855672)
		(end 1.388872 -408.144472)
		(stroke
			(width 0.2)
			(type default)
		)
		(layer "In1.Cu")
	)
	(gr_line
		(start 1.388872 -408.144472)
		(end 4.995672 -408.144472)
		(stroke
			(width 0.2)
			(type default)
		)
		(layer "In1.Cu")
	)
	(gr_line
		(start 1.388872 -407.855674)
		(end 1.388872 -407.144474)
		(stroke
			(width 0.2)
			(type default)
		)
		(layer "In1.Cu")
	)
	(gr_line
		(start 1.388872 -407.144474)
		(end 4.995672 -407.144474)
		(stroke
			(width 0.2)
			(type default)
		)
		(layer "In1.Cu")
	)
	(gr_line
		(start 1.388872 -395.855698)
		(end 1.388872 -395.144498)
		(stroke
			(width 0.2)
			(type default)
		)
		(layer "In1.Cu")
	)
	(gr_line
		(start 1.388872 -395.144498)
		(end 4.995672 -395.144498)
		(stroke
			(width 0.2)
			(type default)
		)
		(layer "In1.Cu")
	)
	(gr_line
		(start 1.388872 -394.8557)
		(end 1.388872 -394.1445)
		(stroke
			(width 0.2)
			(type default)
		)
		(layer "In1.Cu")
	)
	(gr_line
		(start 1.388872 -394.1445)
		(end 4.995672 -394.1445)
		(stroke
			(width 0.2)
			(type default)
		)
		(layer "In1.Cu")
	)
	(gr_line
		(start 1.388872 -386.855716)
		(end 1.388872 -386.144516)
		(stroke
			(width 0.2)
			(type default)
		)
		(layer "In1.Cu")
	)
	(gr_line
		(start 1.388872 -386.144516)
		(end 4.995672 -386.144516)
		(stroke
			(width 0.2)
			(type default)
		)
		(layer "In1.Cu")
	)
	(gr_line
		(start 1.388872 -385.855718)
		(end 1.388872 -385.144518)
		(stroke
			(width 0.2)
			(type default)
		)
		(layer "In1.Cu")
	)
	(gr_line
		(start 1.388872 -385.144518)
		(end 4.995672 -385.144518)
		(stroke
			(width 0.2)
			(type default)
		)
		(layer "In1.Cu")
	)
	(gr_line
		(start 1.388872 -382.855724)
		(end 1.388872 -382.144524)
		(stroke
			(width 0.2)
			(type default)
		)
		(layer "In1.Cu")
	)
	(gr_line
		(start 1.388872 -382.144524)
		(end 4.995672 -382.144524)
		(stroke
			(width 0.2)
			(type default)
		)
		(layer "In1.Cu")
	)
	(gr_line
		(start 1.388872 -381.855726)
		(end 1.388872 -381.144526)
		(stroke
			(width 0.2)
			(type default)
		)
		(layer "In1.Cu")
	)
	(gr_line
		(start 1.388872 -381.144526)
		(end 4.995672 -381.144526)
		(stroke
			(width 0.2)
			(type default)
		)
		(layer "In1.Cu")
	)
	(gr_line
		(start 1.388872 -378.855732)
		(end 1.388872 -378.144532)
		(stroke
			(width 0.2)
			(type default)
		)
		(layer "In1.Cu")
	)
	(gr_line
		(start 1.388872 -378.144532)
		(end 4.995672 -378.144532)
		(stroke
			(width 0.2)
			(type default)
		)
		(layer "In1.Cu")
	)
	(gr_line
		(start 1.388872 -377.855734)
		(end 1.388872 -377.144534)
		(stroke
			(width 0.2)
			(type default)
		)
		(layer "In1.Cu")
	)
	(gr_line
		(start 1.388872 -377.144534)
		(end 4.995672 -377.144534)
		(stroke
			(width 0.2)
			(type default)
		)
		(layer "In1.Cu")
	)
	(gr_line
		(start 1.388872 -374.85574)
		(end 1.388872 -374.14454)
		(stroke
			(width 0.2)
			(type default)
		)
		(layer "In1.Cu")
	)
	(gr_line
		(start 1.388872 -374.14454)
		(end 4.995672 -374.14454)
		(stroke
			(width 0.2)
			(type default)
		)
		(layer "In1.Cu")
	)
	(gr_line
		(start 1.388872 -373.855742)
		(end 1.388872 -373.144542)
		(stroke
			(width 0.2)
			(type default)
		)
		(layer "In1.Cu")
	)
	(gr_line
		(start 1.388872 -373.144542)
		(end 4.995672 -373.144542)
		(stroke
			(width 0.2)
			(type default)
		)
		(layer "In1.Cu")
	)
	(gr_line
		(start 1.388872 -370.855748)
		(end 1.388872 -370.144548)
		(stroke
			(width 0.2)
			(type default)
		)
		(layer "In1.Cu")
	)
	(gr_line
		(start 1.388872 -370.144548)
		(end 4.995672 -370.144548)
		(stroke
			(width 0.2)
			(type default)
		)
		(layer "In1.Cu")
	)
	(gr_line
		(start 1.388872 -369.85575)
		(end 1.388872 -369.14455)
		(stroke
			(width 0.2)
			(type default)
		)
		(layer "In1.Cu")
	)
	(gr_line
		(start 1.388872 -369.14455)
		(end 4.995672 -369.14455)
		(stroke
			(width 0.2)
			(type default)
		)
		(layer "In1.Cu")
	)
	(gr_line
		(start 1.388872 -366.855756)
		(end 1.388872 -366.144556)
		(stroke
			(width 0.2)
			(type default)
		)
		(layer "In1.Cu")
	)
	(gr_line
		(start 1.388872 -366.144556)
		(end 4.995672 -366.144556)
		(stroke
			(width 0.2)
			(type default)
		)
		(layer "In1.Cu")
	)
	(gr_line
		(start 1.388872 -365.855758)
		(end 1.388872 -365.144558)
		(stroke
			(width 0.2)
			(type default)
		)
		(layer "In1.Cu")
	)
	(gr_line
		(start 1.388872 -365.144558)
		(end 4.995672 -365.144558)
		(stroke
			(width 0.2)
			(type default)
		)
		(layer "In1.Cu")
	)
	(gr_line
		(start 1.388872 -362.855764)
		(end 1.388872 -362.144564)
		(stroke
			(width 0.2)
			(type default)
		)
		(layer "In1.Cu")
	)
	(gr_line
		(start 1.388872 -362.144564)
		(end 4.995672 -362.144564)
		(stroke
			(width 0.2)
			(type default)
		)
		(layer "In1.Cu")
	)
	(gr_line
		(start 1.388872 -361.855766)
		(end 1.388872 -361.144566)
		(stroke
			(width 0.2)
			(type default)
		)
		(layer "In1.Cu")
	)
	(gr_line
		(start 1.388872 -361.144566)
		(end 4.995672 -361.144566)
		(stroke
			(width 0.2)
			(type default)
		)
		(layer "In1.Cu")
	)
	(gr_line
		(start 1.388872 -358.855518)
		(end 1.388872 -358.144318)
		(stroke
			(width 0.2)
			(type default)
		)
		(layer "In1.Cu")
	)
	(gr_line
		(start 1.388872 -358.144318)
		(end 4.995672 -358.144318)
		(stroke
			(width 0.2)
			(type default)
		)
		(layer "In1.Cu")
	)
	(gr_line
		(start 1.388872 -357.85552)
		(end 1.388872 -357.14432)
		(stroke
			(width 0.2)
			(type default)
		)
		(layer "In1.Cu")
	)
	(gr_line
		(start 1.388872 -357.14432)
		(end 4.995672 -357.14432)
		(stroke
			(width 0.2)
			(type default)
		)
		(layer "In1.Cu")
	)
	(gr_line
		(start 1.388872 -352.855276)
		(end 1.388872 -352.144076)
		(stroke
			(width 0.2)
			(type default)
		)
		(layer "In1.Cu")
	)
	(gr_line
		(start 1.388872 -352.144076)
		(end 4.995672 -352.144076)
		(stroke
			(width 0.2)
			(type default)
		)
		(layer "In1.Cu")
	)
	(gr_line
		(start 1.388872 -351.855278)
		(end 1.388872 -351.144078)
		(stroke
			(width 0.2)
			(type default)
		)
		(layer "In1.Cu")
	)
	(gr_line
		(start 1.388872 -351.144078)
		(end 4.995672 -351.144078)
		(stroke
			(width 0.2)
			(type default)
		)
		(layer "In1.Cu")
	)
	(gr_line
		(start 1.388872 -348.855284)
		(end 1.388872 -348.144084)
		(stroke
			(width 0.2)
			(type default)
		)
		(layer "In1.Cu")
	)
	(gr_line
		(start 1.388872 -348.144084)
		(end 4.995672 -348.144084)
		(stroke
			(width 0.2)
			(type default)
		)
		(layer "In1.Cu")
	)
	(gr_line
		(start 1.388872 -347.855286)
		(end 1.388872 -347.144086)
		(stroke
			(width 0.2)
			(type default)
		)
		(layer "In1.Cu")
	)
	(gr_line
		(start 1.388872 -347.144086)
		(end 4.995672 -347.144086)
		(stroke
			(width 0.2)
			(type default)
		)
		(layer "In1.Cu")
	)
	(gr_line
		(start 1.388872 -170.85564)
		(end 1.388872 -170.14444)
		(stroke
			(width 0.2)
			(type default)
		)
		(layer "In1.Cu")
	)
	(gr_line
		(start 1.388872 -170.14444)
		(end 4.995672 -170.14444)
		(stroke
			(width 0.2)
			(type default)
		)
		(layer "In1.Cu")
	)
	(gr_line
		(start 1.388872 -169.855642)
		(end 1.388872 -169.144442)
		(stroke
			(width 0.2)
			(type default)
		)
		(layer "In1.Cu")
	)
	(gr_line
		(start 1.388872 -169.144442)
		(end 4.995672 -169.144442)
		(stroke
			(width 0.2)
			(type default)
		)
		(layer "In1.Cu")
	)
	(gr_line
		(start 1.388872 -166.855648)
		(end 1.388872 -166.144448)
		(stroke
			(width 0.2)
			(type default)
		)
		(layer "In1.Cu")
	)
	(gr_line
		(start 1.388872 -166.144448)
		(end 4.995672 -166.144448)
		(stroke
			(width 0.2)
			(type default)
		)
		(layer "In1.Cu")
	)
	(gr_line
		(start 1.388872 -165.85565)
		(end 1.388872 -165.14445)
		(stroke
			(width 0.2)
			(type default)
		)
		(layer "In1.Cu")
	)
	(gr_line
		(start 1.388872 -165.14445)
		(end 4.995672 -165.14445)
		(stroke
			(width 0.2)
			(type default)
		)
		(layer "In1.Cu")
	)
	(gr_line
		(start 1.388872 -162.855656)
		(end 1.388872 -162.144456)
		(stroke
			(width 0.2)
			(type default)
		)
		(layer "In1.Cu")
	)
	(gr_line
		(start 1.388872 -162.144456)
		(end 4.995672 -162.144456)
		(stroke
			(width 0.2)
			(type default)
		)
		(layer "In1.Cu")
	)
	(gr_line
		(start 1.388872 -161.855658)
		(end 1.388872 -161.144458)
		(stroke
			(width 0.2)
			(type default)
		)
		(layer "In1.Cu")
	)
	(gr_line
		(start 1.388872 -161.144458)
		(end 4.995672 -161.144458)
		(stroke
			(width 0.2)
			(type default)
		)
		(layer "In1.Cu")
	)
	(gr_line
		(start 1.388872 -158.855664)
		(end 1.388872 -158.144464)
		(stroke
			(width 0.2)
			(type default)
		)
		(layer "In1.Cu")
	)
	(gr_line
		(start 1.388872 -158.144464)
		(end 4.995672 -158.144464)
		(stroke
			(width 0.2)
			(type default)
		)
		(layer "In1.Cu")
	)
	(gr_line
		(start 1.388872 -157.855666)
		(end 1.388872 -157.144466)
		(stroke
			(width 0.2)
			(type default)
		)
		(layer "In1.Cu")
	)
	(gr_line
		(start 1.388872 -157.144466)
		(end 4.995672 -157.144466)
		(stroke
			(width 0.2)
			(type default)
		)
		(layer "In1.Cu")
	)
	(gr_line
		(start 1.388872 -145.85569)
		(end 1.388872 -145.14449)
		(stroke
			(width 0.2)
			(type default)
		)
		(layer "In1.Cu")
	)
	(gr_line
		(start 1.388872 -145.14449)
		(end 4.995672 -145.14449)
		(stroke
			(width 0.2)
			(type default)
		)
		(layer "In1.Cu")
	)
	(gr_line
		(start 1.388872 -144.855692)
		(end 1.388872 -144.144492)
		(stroke
			(width 0.2)
			(type default)
		)
		(layer "In1.Cu")
	)
	(gr_line
		(start 1.388872 -144.144492)
		(end 4.995672 -144.144492)
		(stroke
			(width 0.2)
			(type default)
		)
		(layer "In1.Cu")
	)
	(gr_line
		(start 1.388872 -136.855708)
		(end 1.388872 -136.144508)
		(stroke
			(width 0.2)
			(type default)
		)
		(layer "In1.Cu")
	)
	(gr_line
		(start 1.388872 -136.144508)
		(end 4.995672 -136.144508)
		(stroke
			(width 0.2)
			(type default)
		)
		(layer "In1.Cu")
	)
	(gr_line
		(start 1.388872 -135.85571)
		(end 1.388872 -135.14451)
		(stroke
			(width 0.2)
			(type default)
		)
		(layer "In1.Cu")
	)
	(gr_line
		(start 1.388872 -135.14451)
		(end 4.995672 -135.14451)
		(stroke
			(width 0.2)
			(type default)
		)
		(layer "In1.Cu")
	)
	(gr_line
		(start 1.388872 -132.855716)
		(end 1.388872 -132.144516)
		(stroke
			(width 0.2)
			(type default)
		)
		(layer "In1.Cu")
	)
	(gr_line
		(start 1.388872 -132.144516)
		(end 4.995672 -132.144516)
		(stroke
			(width 0.2)
			(type default)
		)
		(layer "In1.Cu")
	)
	(gr_line
		(start 1.388872 -131.855718)
		(end 1.388872 -131.144518)
		(stroke
			(width 0.2)
			(type default)
		)
		(layer "In1.Cu")
	)
	(gr_line
		(start 1.388872 -131.144518)
		(end 4.995672 -131.144518)
		(stroke
			(width 0.2)
			(type default)
		)
		(layer "In1.Cu")
	)
	(gr_line
		(start 1.388872 -128.855724)
		(end 1.388872 -128.144524)
		(stroke
			(width 0.2)
			(type default)
		)
		(layer "In1.Cu")
	)
	(gr_line
		(start 1.388872 -128.144524)
		(end 4.995672 -128.144524)
		(stroke
			(width 0.2)
			(type default)
		)
		(layer "In1.Cu")
	)
	(gr_line
		(start 1.388872 -127.855726)
		(end 1.388872 -127.144526)
		(stroke
			(width 0.2)
			(type default)
		)
		(layer "In1.Cu")
	)
	(gr_line
		(start 1.388872 -127.144526)
		(end 4.995672 -127.144526)
		(stroke
			(width 0.2)
			(type default)
		)
		(layer "In1.Cu")
	)
	(gr_line
		(start 1.388872 -124.855732)
		(end 1.388872 -124.144532)
		(stroke
			(width 0.2)
			(type default)
		)
		(layer "In1.Cu")
	)
	(gr_line
		(start 1.388872 -124.144532)
		(end 4.995672 -124.144532)
		(stroke
			(width 0.2)
			(type default)
		)
		(layer "In1.Cu")
	)
	(gr_line
		(start 1.388872 -123.855734)
		(end 1.388872 -123.144534)
		(stroke
			(width 0.2)
			(type default)
		)
		(layer "In1.Cu")
	)
	(gr_line
		(start 1.388872 -123.144534)
		(end 4.995672 -123.144534)
		(stroke
			(width 0.2)
			(type default)
		)
		(layer "In1.Cu")
	)
	(gr_line
		(start 1.388872 -120.85574)
		(end 1.388872 -120.14454)
		(stroke
			(width 0.2)
			(type default)
		)
		(layer "In1.Cu")
	)
	(gr_line
		(start 1.388872 -120.14454)
		(end 4.995672 -120.14454)
		(stroke
			(width 0.2)
			(type default)
		)
		(layer "In1.Cu")
	)
	(gr_line
		(start 1.388872 -119.855742)
		(end 1.388872 -119.144542)
		(stroke
			(width 0.2)
			(type default)
		)
		(layer "In1.Cu")
	)
	(gr_line
		(start 1.388872 -119.144542)
		(end 4.995672 -119.144542)
		(stroke
			(width 0.2)
			(type default)
		)
		(layer "In1.Cu")
	)
	(gr_line
		(start 1.388872 -116.855748)
		(end 1.388872 -116.144548)
		(stroke
			(width 0.2)
			(type default)
		)
		(layer "In1.Cu")
	)
	(gr_line
		(start 1.388872 -116.144548)
		(end 4.995672 -116.144548)
		(stroke
			(width 0.2)
			(type default)
		)
		(layer "In1.Cu")
	)
	(gr_line
		(start 1.388872 -115.85575)
		(end 1.388872 -115.14455)
		(stroke
			(width 0.2)
			(type default)
		)
		(layer "In1.Cu")
	)
	(gr_line
		(start 1.388872 -115.14455)
		(end 4.995672 -115.14455)
		(stroke
			(width 0.2)
			(type default)
		)
		(layer "In1.Cu")
	)
	(gr_line
		(start 1.388872 -112.855756)
		(end 1.388872 -112.144556)
		(stroke
			(width 0.2)
			(type default)
		)
		(layer "In1.Cu")
	)
	(gr_line
		(start 1.388872 -112.144556)
		(end 4.995672 -112.144556)
		(stroke
			(width 0.2)
			(type default)
		)
		(layer "In1.Cu")
	)
	(gr_line
		(start 1.388872 -111.855758)
		(end 1.388872 -111.144558)
		(stroke
			(width 0.2)
			(type default)
		)
		(layer "In1.Cu")
	)
	(gr_line
		(start 1.388872 -111.144558)
		(end 4.995672 -111.144558)
		(stroke
			(width 0.2)
			(type default)
		)
		(layer "In1.Cu")
	)
	(gr_line
		(start 1.388872 -108.85551)
		(end 1.388872 -108.14431)
		(stroke
			(width 0.2)
			(type default)
		)
		(layer "In1.Cu")
	)
	(gr_line
		(start 1.388872 -108.14431)
		(end 4.995672 -108.14431)
		(stroke
			(width 0.2)
			(type default)
		)
		(layer "In1.Cu")
	)
	(gr_line
		(start 1.388872 -107.855512)
		(end 1.388872 -107.144312)
		(stroke
			(width 0.2)
			(type default)
		)
		(layer "In1.Cu")
	)
	(gr_line
		(start 1.388872 -107.144312)
		(end 4.995672 -107.144312)
		(stroke
			(width 0.2)
			(type default)
		)
		(layer "In1.Cu")
	)
	(gr_line
		(start 1.388872 -102.855268)
		(end 1.388872 -102.144068)
		(stroke
			(width 0.2)
			(type default)
		)
		(layer "In1.Cu")
	)
	(gr_line
		(start 1.388872 -102.144068)
		(end 4.995672 -102.144068)
		(stroke
			(width 0.2)
			(type default)
		)
		(layer "In1.Cu")
	)
	(gr_line
		(start 1.388872 -101.85527)
		(end 1.388872 -101.14407)
		(stroke
			(width 0.2)
			(type default)
		)
		(layer "In1.Cu")
	)
	(gr_line
		(start 1.388872 -101.14407)
		(end 4.995672 -101.14407)
		(stroke
			(width 0.2)
			(type default)
		)
		(layer "In1.Cu")
	)
	(gr_line
		(start 1.388872 -98.855276)
		(end 1.388872 -98.144076)
		(stroke
			(width 0.2)
			(type default)
		)
		(layer "In1.Cu")
	)
	(gr_line
		(start 1.388872 -98.144076)
		(end 4.995672 -98.144076)
		(stroke
			(width 0.2)
			(type default)
		)
		(layer "In1.Cu")
	)
	(gr_line
		(start 1.388872 -97.855278)
		(end 1.388872 -97.144078)
		(stroke
			(width 0.2)
			(type default)
		)
		(layer "In1.Cu")
	)
	(gr_line
		(start 1.388872 -97.144078)
		(end 4.995672 -97.144078)
		(stroke
			(width 0.2)
			(type default)
		)
		(layer "In1.Cu")
	)
	(gr_line
		(start 4.995672 -424.85564)
		(end 1.388872 -424.85564)
		(stroke
			(width 0.2)
			(type default)
		)
		(layer "In1.Cu")
	)
	(gr_line
		(start 4.995672 -424.14444)
		(end 4.995672 -424.85564)
		(stroke
			(width 0.2)
			(type default)
		)
		(layer "In1.Cu")
	)
	(gr_line
		(start 4.995672 -423.855642)
		(end 1.388872 -423.855642)
		(stroke
			(width 0.2)
			(type default)
		)
		(layer "In1.Cu")
	)
	(gr_line
		(start 4.995672 -423.144442)
		(end 4.995672 -423.855642)
		(stroke
			(width 0.2)
			(type default)
		)
		(layer "In1.Cu")
	)
	(gr_line
		(start 4.995672 -420.855648)
		(end 1.388872 -420.855648)
		(stroke
			(width 0.2)
			(type default)
		)
		(layer "In1.Cu")
	)
	(gr_line
		(start 4.995672 -420.144448)
		(end 4.995672 -420.855648)
		(stroke
			(width 0.2)
			(type default)
		)
		(layer "In1.Cu")
	)
	(gr_line
		(start 4.995672 -419.85565)
		(end 1.388872 -419.85565)
		(stroke
			(width 0.2)
			(type default)
		)
		(layer "In1.Cu")
	)
	(gr_line
		(start 4.995672 -419.14445)
		(end 4.995672 -419.85565)
		(stroke
			(width 0.2)
			(type default)
		)
		(layer "In1.Cu")
	)
	(gr_line
		(start 4.995672 -416.855656)
		(end 1.388872 -416.855656)
		(stroke
			(width 0.2)
			(type default)
		)
		(layer "In1.Cu")
	)
	(gr_line
		(start 4.995672 -416.144456)
		(end 4.995672 -416.855656)
		(stroke
			(width 0.2)
			(type default)
		)
		(layer "In1.Cu")
	)
	(gr_line
		(start 4.995672 -415.855658)
		(end 1.388872 -415.855658)
		(stroke
			(width 0.2)
			(type default)
		)
		(layer "In1.Cu")
	)
	(gr_line
		(start 4.995672 -415.144458)
		(end 4.995672 -415.855658)
		(stroke
			(width 0.2)
			(type default)
		)
		(layer "In1.Cu")
	)
	(gr_line
		(start 4.995672 -412.855664)
		(end 1.388872 -412.855664)
		(stroke
			(width 0.2)
			(type default)
		)
		(layer "In1.Cu")
	)
	(gr_line
		(start 4.995672 -412.144464)
		(end 4.995672 -412.855664)
		(stroke
			(width 0.2)
			(type default)
		)
		(layer "In1.Cu")
	)
	(gr_line
		(start 4.995672 -411.855666)
		(end 1.388872 -411.855666)
		(stroke
			(width 0.2)
			(type default)
		)
		(layer "In1.Cu")
	)
	(gr_line
		(start 4.995672 -411.144466)
		(end 4.995672 -411.855666)
		(stroke
			(width 0.2)
			(type default)
		)
		(layer "In1.Cu")
	)
	(gr_line
		(start 4.995672 -408.855672)
		(end 1.388872 -408.855672)
		(stroke
			(width 0.2)
			(type default)
		)
		(layer "In1.Cu")
	)
	(gr_line
		(start 4.995672 -408.144472)
		(end 4.995672 -408.855672)
		(stroke
			(width 0.2)
			(type default)
		)
		(layer "In1.Cu")
	)
	(gr_line
		(start 4.995672 -407.855674)
		(end 1.388872 -407.855674)
		(stroke
			(width 0.2)
			(type default)
		)
		(layer "In1.Cu")
	)
	(gr_line
		(start 4.995672 -407.144474)
		(end 4.995672 -407.855674)
		(stroke
			(width 0.2)
			(type default)
		)
		(layer "In1.Cu")
	)
	(gr_line
		(start 4.995672 -395.855698)
		(end 1.388872 -395.855698)
		(stroke
			(width 0.2)
			(type default)
		)
		(layer "In1.Cu")
	)
	(gr_line
		(start 4.995672 -395.144498)
		(end 4.995672 -395.855698)
		(stroke
			(width 0.2)
			(type default)
		)
		(layer "In1.Cu")
	)
	(gr_line
		(start 4.995672 -394.8557)
		(end 1.388872 -394.8557)
		(stroke
			(width 0.2)
			(type default)
		)
		(layer "In1.Cu")
	)
	(gr_line
		(start 4.995672 -394.1445)
		(end 4.995672 -394.8557)
		(stroke
			(width 0.2)
			(type default)
		)
		(layer "In1.Cu")
	)
	(gr_line
		(start 4.995672 -386.855716)
		(end 1.388872 -386.855716)
		(stroke
			(width 0.2)
			(type default)
		)
		(layer "In1.Cu")
	)
	(gr_line
		(start 4.995672 -386.144516)
		(end 4.995672 -386.855716)
		(stroke
			(width 0.2)
			(type default)
		)
		(layer "In1.Cu")
	)
	(gr_line
		(start 4.995672 -385.855718)
		(end 1.388872 -385.855718)
		(stroke
			(width 0.2)
			(type default)
		)
		(layer "In1.Cu")
	)
	(gr_line
		(start 4.995672 -385.144518)
		(end 4.995672 -385.855718)
		(stroke
			(width 0.2)
			(type default)
		)
		(layer "In1.Cu")
	)
	(gr_line
		(start 4.995672 -382.855724)
		(end 1.388872 -382.855724)
		(stroke
			(width 0.2)
			(type default)
		)
		(layer "In1.Cu")
	)
	(gr_line
		(start 4.995672 -382.144524)
		(end 4.995672 -382.855724)
		(stroke
			(width 0.2)
			(type default)
		)
		(layer "In1.Cu")
	)
	(gr_line
		(start 4.995672 -381.855726)
		(end 1.388872 -381.855726)
		(stroke
			(width 0.2)
			(type default)
		)
		(layer "In1.Cu")
	)
	(gr_line
		(start 4.995672 -381.144526)
		(end 4.995672 -381.855726)
		(stroke
			(width 0.2)
			(type default)
		)
		(layer "In1.Cu")
	)
	(gr_line
		(start 4.995672 -378.855732)
		(end 1.388872 -378.855732)
		(stroke
			(width 0.2)
			(type default)
		)
		(layer "In1.Cu")
	)
	(gr_line
		(start 4.995672 -378.144532)
		(end 4.995672 -378.855732)
		(stroke
			(width 0.2)
			(type default)
		)
		(layer "In1.Cu")
	)
	(gr_line
		(start 4.995672 -377.855734)
		(end 1.388872 -377.855734)
		(stroke
			(width 0.2)
			(type default)
		)
		(layer "In1.Cu")
	)
	(gr_line
		(start 4.995672 -377.144534)
		(end 4.995672 -377.855734)
		(stroke
			(width 0.2)
			(type default)
		)
		(layer "In1.Cu")
	)
	(gr_line
		(start 4.995672 -374.85574)
		(end 1.388872 -374.85574)
		(stroke
			(width 0.2)
			(type default)
		)
		(layer "In1.Cu")
	)
	(gr_line
		(start 4.995672 -374.14454)
		(end 4.995672 -374.85574)
		(stroke
			(width 0.2)
			(type default)
		)
		(layer "In1.Cu")
	)
	(gr_line
		(start 4.995672 -373.855742)
		(end 1.388872 -373.855742)
		(stroke
			(width 0.2)
			(type default)
		)
		(layer "In1.Cu")
	)
	(gr_line
		(start 4.995672 -373.144542)
		(end 4.995672 -373.855742)
		(stroke
			(width 0.2)
			(type default)
		)
		(layer "In1.Cu")
	)
	(gr_line
		(start 4.995672 -370.855748)
		(end 1.388872 -370.855748)
		(stroke
			(width 0.2)
			(type default)
		)
		(layer "In1.Cu")
	)
	(gr_line
		(start 4.995672 -370.144548)
		(end 4.995672 -370.855748)
		(stroke
			(width 0.2)
			(type default)
		)
		(layer "In1.Cu")
	)
	(gr_line
		(start 4.995672 -369.85575)
		(end 1.388872 -369.85575)
		(stroke
			(width 0.2)
			(type default)
		)
		(layer "In1.Cu")
	)
	(gr_line
		(start 4.995672 -369.14455)
		(end 4.995672 -369.85575)
		(stroke
			(width 0.2)
			(type default)
		)
		(layer "In1.Cu")
	)
	(gr_line
		(start 4.995672 -366.855756)
		(end 1.388872 -366.855756)
		(stroke
			(width 0.2)
			(type default)
		)
		(layer "In1.Cu")
	)
	(gr_line
		(start 4.995672 -366.144556)
		(end 4.995672 -366.855756)
		(stroke
			(width 0.2)
			(type default)
		)
		(layer "In1.Cu")
	)
	(gr_line
		(start 4.995672 -365.855758)
		(end 1.388872 -365.855758)
		(stroke
			(width 0.2)
			(type default)
		)
		(layer "In1.Cu")
	)
	(gr_line
		(start 4.995672 -365.144558)
		(end 4.995672 -365.855758)
		(stroke
			(width 0.2)
			(type default)
		)
		(layer "In1.Cu")
	)
	(gr_line
		(start 4.995672 -362.855764)
		(end 1.388872 -362.855764)
		(stroke
			(width 0.2)
			(type default)
		)
		(layer "In1.Cu")
	)
	(gr_line
		(start 4.995672 -362.144564)
		(end 4.995672 -362.855764)
		(stroke
			(width 0.2)
			(type default)
		)
		(layer "In1.Cu")
	)
	(gr_line
		(start 4.995672 -361.855766)
		(end 1.388872 -361.855766)
		(stroke
			(width 0.2)
			(type default)
		)
		(layer "In1.Cu")
	)
	(gr_line
		(start 4.995672 -361.144566)
		(end 4.995672 -361.855766)
		(stroke
			(width 0.2)
			(type default)
		)
		(layer "In1.Cu")
	)
	(gr_line
		(start 4.995672 -358.855518)
		(end 1.388872 -358.855518)
		(stroke
			(width 0.2)
			(type default)
		)
		(layer "In1.Cu")
	)
	(gr_line
		(start 4.995672 -358.144318)
		(end 4.995672 -358.855518)
		(stroke
			(width 0.2)
			(type default)
		)
		(layer "In1.Cu")
	)
	(gr_line
		(start 4.995672 -357.85552)
		(end 1.388872 -357.85552)
		(stroke
			(width 0.2)
			(type default)
		)
		(layer "In1.Cu")
	)
	(gr_line
		(start 4.995672 -357.14432)
		(end 4.995672 -357.85552)
		(stroke
			(width 0.2)
			(type default)
		)
		(layer "In1.Cu")
	)
	(gr_line
		(start 4.995672 -352.855276)
		(end 1.388872 -352.855276)
		(stroke
			(width 0.2)
			(type default)
		)
		(layer "In1.Cu")
	)
	(gr_line
		(start 4.995672 -352.144076)
		(end 4.995672 -352.855276)
		(stroke
			(width 0.2)
			(type default)
		)
		(layer "In1.Cu")
	)
	(gr_line
		(start 4.995672 -351.855278)
		(end 1.388872 -351.855278)
		(stroke
			(width 0.2)
			(type default)
		)
		(layer "In1.Cu")
	)
	(gr_line
		(start 4.995672 -351.144078)
		(end 4.995672 -351.855278)
		(stroke
			(width 0.2)
			(type default)
		)
		(layer "In1.Cu")
	)
	(gr_line
		(start 4.995672 -348.855284)
		(end 1.388872 -348.855284)
		(stroke
			(width 0.2)
			(type default)
		)
		(layer "In1.Cu")
	)
	(gr_line
		(start 4.995672 -348.144084)
		(end 4.995672 -348.855284)
		(stroke
			(width 0.2)
			(type default)
		)
		(layer "In1.Cu")
	)
	(gr_line
		(start 4.995672 -347.855286)
		(end 1.388872 -347.855286)
		(stroke
			(width 0.2)
			(type default)
		)
		(layer "In1.Cu")
	)
	(gr_line
		(start 4.995672 -347.144086)
		(end 4.995672 -347.855286)
		(stroke
			(width 0.2)
			(type default)
		)
		(layer "In1.Cu")
	)
	(gr_line
		(start 4.995672 -170.85564)
		(end 1.388872 -170.85564)
		(stroke
			(width 0.2)
			(type default)
		)
		(layer "In1.Cu")
	)
	(gr_line
		(start 4.995672 -170.14444)
		(end 4.995672 -170.85564)
		(stroke
			(width 0.2)
			(type default)
		)
		(layer "In1.Cu")
	)
	(gr_line
		(start 4.995672 -169.855642)
		(end 1.388872 -169.855642)
		(stroke
			(width 0.2)
			(type default)
		)
		(layer "In1.Cu")
	)
	(gr_line
		(start 4.995672 -169.144442)
		(end 4.995672 -169.855642)
		(stroke
			(width 0.2)
			(type default)
		)
		(layer "In1.Cu")
	)
	(gr_line
		(start 4.995672 -166.855648)
		(end 1.388872 -166.855648)
		(stroke
			(width 0.2)
			(type default)
		)
		(layer "In1.Cu")
	)
	(gr_line
		(start 4.995672 -166.144448)
		(end 4.995672 -166.855648)
		(stroke
			(width 0.2)
			(type default)
		)
		(layer "In1.Cu")
	)
	(gr_line
		(start 4.995672 -165.85565)
		(end 1.388872 -165.85565)
		(stroke
			(width 0.2)
			(type default)
		)
		(layer "In1.Cu")
	)
	(gr_line
		(start 4.995672 -165.14445)
		(end 4.995672 -165.85565)
		(stroke
			(width 0.2)
			(type default)
		)
		(layer "In1.Cu")
	)
	(gr_line
		(start 4.995672 -162.855656)
		(end 1.388872 -162.855656)
		(stroke
			(width 0.2)
			(type default)
		)
		(layer "In1.Cu")
	)
	(gr_line
		(start 4.995672 -162.144456)
		(end 4.995672 -162.855656)
		(stroke
			(width 0.2)
			(type default)
		)
		(layer "In1.Cu")
	)
	(gr_line
		(start 4.995672 -161.855658)
		(end 1.388872 -161.855658)
		(stroke
			(width 0.2)
			(type default)
		)
		(layer "In1.Cu")
	)
	(gr_line
		(start 4.995672 -161.144458)
		(end 4.995672 -161.855658)
		(stroke
			(width 0.2)
			(type default)
		)
		(layer "In1.Cu")
	)
	(gr_line
		(start 4.995672 -158.855664)
		(end 1.388872 -158.855664)
		(stroke
			(width 0.2)
			(type default)
		)
		(layer "In1.Cu")
	)
	(gr_line
		(start 4.995672 -158.144464)
		(end 4.995672 -158.855664)
		(stroke
			(width 0.2)
			(type default)
		)
		(layer "In1.Cu")
	)
	(gr_line
		(start 4.995672 -157.855666)
		(end 1.388872 -157.855666)
		(stroke
			(width 0.2)
			(type default)
		)
		(layer "In1.Cu")
	)
	(gr_line
		(start 4.995672 -157.144466)
		(end 4.995672 -157.855666)
		(stroke
			(width 0.2)
			(type default)
		)
		(layer "In1.Cu")
	)
	(gr_line
		(start 4.995672 -145.85569)
		(end 1.388872 -145.85569)
		(stroke
			(width 0.2)
			(type default)
		)
		(layer "In1.Cu")
	)
	(gr_line
		(start 4.995672 -145.14449)
		(end 4.995672 -145.85569)
		(stroke
			(width 0.2)
			(type default)
		)
		(layer "In1.Cu")
	)
	(gr_line
		(start 4.995672 -144.855692)
		(end 1.388872 -144.855692)
		(stroke
			(width 0.2)
			(type default)
		)
		(layer "In1.Cu")
	)
	(gr_line
		(start 4.995672 -144.144492)
		(end 4.995672 -144.855692)
		(stroke
			(width 0.2)
			(type default)
		)
		(layer "In1.Cu")
	)
	(gr_line
		(start 4.995672 -136.855708)
		(end 1.388872 -136.855708)
		(stroke
			(width 0.2)
			(type default)
		)
		(layer "In1.Cu")
	)
	(gr_line
		(start 4.995672 -136.144508)
		(end 4.995672 -136.855708)
		(stroke
			(width 0.2)
			(type default)
		)
		(layer "In1.Cu")
	)
	(gr_line
		(start 4.995672 -135.85571)
		(end 1.388872 -135.85571)
		(stroke
			(width 0.2)
			(type default)
		)
		(layer "In1.Cu")
	)
	(gr_line
		(start 4.995672 -135.14451)
		(end 4.995672 -135.85571)
		(stroke
			(width 0.2)
			(type default)
		)
		(layer "In1.Cu")
	)
	(gr_line
		(start 4.995672 -132.855716)
		(end 1.388872 -132.855716)
		(stroke
			(width 0.2)
			(type default)
		)
		(layer "In1.Cu")
	)
	(gr_line
		(start 4.995672 -132.144516)
		(end 4.995672 -132.855716)
		(stroke
			(width 0.2)
			(type default)
		)
		(layer "In1.Cu")
	)
	(gr_line
		(start 4.995672 -131.855718)
		(end 1.388872 -131.855718)
		(stroke
			(width 0.2)
			(type default)
		)
		(layer "In1.Cu")
	)
	(gr_line
		(start 4.995672 -131.144518)
		(end 4.995672 -131.855718)
		(stroke
			(width 0.2)
			(type default)
		)
		(layer "In1.Cu")
	)
	(gr_line
		(start 4.995672 -128.855724)
		(end 1.388872 -128.855724)
		(stroke
			(width 0.2)
			(type default)
		)
		(layer "In1.Cu")
	)
	(gr_line
		(start 4.995672 -128.144524)
		(end 4.995672 -128.855724)
		(stroke
			(width 0.2)
			(type default)
		)
		(layer "In1.Cu")
	)
	(gr_line
		(start 4.995672 -127.855726)
		(end 1.388872 -127.855726)
		(stroke
			(width 0.2)
			(type default)
		)
		(layer "In1.Cu")
	)
	(gr_line
		(start 4.995672 -127.144526)
		(end 4.995672 -127.855726)
		(stroke
			(width 0.2)
			(type default)
		)
		(layer "In1.Cu")
	)
	(gr_line
		(start 4.995672 -124.855732)
		(end 1.388872 -124.855732)
		(stroke
			(width 0.2)
			(type default)
		)
		(layer "In1.Cu")
	)
	(gr_line
		(start 4.995672 -124.144532)
		(end 4.995672 -124.855732)
		(stroke
			(width 0.2)
			(type default)
		)
		(layer "In1.Cu")
	)
	(gr_line
		(start 4.995672 -123.855734)
		(end 1.388872 -123.855734)
		(stroke
			(width 0.2)
			(type default)
		)
		(layer "In1.Cu")
	)
	(gr_line
		(start 4.995672 -123.144534)
		(end 4.995672 -123.855734)
		(stroke
			(width 0.2)
			(type default)
		)
		(layer "In1.Cu")
	)
	(gr_line
		(start 4.995672 -120.85574)
		(end 1.388872 -120.85574)
		(stroke
			(width 0.2)
			(type default)
		)
		(layer "In1.Cu")
	)
	(gr_line
		(start 4.995672 -120.14454)
		(end 4.995672 -120.85574)
		(stroke
			(width 0.2)
			(type default)
		)
		(layer "In1.Cu")
	)
	(gr_line
		(start 4.995672 -119.855742)
		(end 1.388872 -119.855742)
		(stroke
			(width 0.2)
			(type default)
		)
		(layer "In1.Cu")
	)
	(gr_line
		(start 4.995672 -119.144542)
		(end 4.995672 -119.855742)
		(stroke
			(width 0.2)
			(type default)
		)
		(layer "In1.Cu")
	)
	(gr_line
		(start 4.995672 -116.855748)
		(end 1.388872 -116.855748)
		(stroke
			(width 0.2)
			(type default)
		)
		(layer "In1.Cu")
	)
	(gr_line
		(start 4.995672 -116.144548)
		(end 4.995672 -116.855748)
		(stroke
			(width 0.2)
			(type default)
		)
		(layer "In1.Cu")
	)
	(gr_line
		(start 4.995672 -115.85575)
		(end 1.388872 -115.85575)
		(stroke
			(width 0.2)
			(type default)
		)
		(layer "In1.Cu")
	)
	(gr_line
		(start 4.995672 -115.14455)
		(end 4.995672 -115.85575)
		(stroke
			(width 0.2)
			(type default)
		)
		(layer "In1.Cu")
	)
	(gr_line
		(start 4.995672 -112.855756)
		(end 1.388872 -112.855756)
		(stroke
			(width 0.2)
			(type default)
		)
		(layer "In1.Cu")
	)
	(gr_line
		(start 4.995672 -112.144556)
		(end 4.995672 -112.855756)
		(stroke
			(width 0.2)
			(type default)
		)
		(layer "In1.Cu")
	)
	(gr_line
		(start 4.995672 -111.855758)
		(end 1.388872 -111.855758)
		(stroke
			(width 0.2)
			(type default)
		)
		(layer "In1.Cu")
	)
	(gr_line
		(start 4.995672 -111.144558)
		(end 4.995672 -111.855758)
		(stroke
			(width 0.2)
			(type default)
		)
		(layer "In1.Cu")
	)
	(gr_line
		(start 4.995672 -108.85551)
		(end 1.388872 -108.85551)
		(stroke
			(width 0.2)
			(type default)
		)
		(layer "In1.Cu")
	)
	(gr_line
		(start 4.995672 -108.14431)
		(end 4.995672 -108.85551)
		(stroke
			(width 0.2)
			(type default)
		)
		(layer "In1.Cu")
	)
	(gr_line
		(start 4.995672 -107.855512)
		(end 1.388872 -107.855512)
		(stroke
			(width 0.2)
			(type default)
		)
		(layer "In1.Cu")
	)
	(gr_line
		(start 4.995672 -107.144312)
		(end 4.995672 -107.855512)
		(stroke
			(width 0.2)
			(type default)
		)
		(layer "In1.Cu")
	)
	(gr_line
		(start 4.995672 -102.855268)
		(end 1.388872 -102.855268)
		(stroke
			(width 0.2)
			(type default)
		)
		(layer "In1.Cu")
	)
	(gr_line
		(start 4.995672 -102.144068)
		(end 4.995672 -102.855268)
		(stroke
			(width 0.2)
			(type default)
		)
		(layer "In1.Cu")
	)
	(gr_line
		(start 4.995672 -101.85527)
		(end 1.388872 -101.85527)
		(stroke
			(width 0.2)
			(type default)
		)
		(layer "In1.Cu")
	)
	(gr_line
		(start 4.995672 -101.14407)
		(end 4.995672 -101.85527)
		(stroke
			(width 0.2)
			(type default)
		)
		(layer "In1.Cu")
	)
	(gr_line
		(start 4.995672 -98.855276)
		(end 1.388872 -98.855276)
		(stroke
			(width 0.2)
			(type default)
		)
		(layer "In1.Cu")
	)
	(gr_line
		(start 4.995672 -98.144076)
		(end 4.995672 -98.855276)
		(stroke
			(width 0.2)
			(type default)
		)
		(layer "In1.Cu")
	)
	(gr_line
		(start 4.995672 -97.855278)
		(end 1.388872 -97.855278)
		(stroke
			(width 0.2)
			(type default)
		)
		(layer "In1.Cu")
	)
	(gr_line
		(start 4.995672 -97.144078)
		(end 4.995672 -97.855278)
		(stroke
			(width 0.2)
			(type default)
		)
		(layer "In1.Cu")
	)
	(gr_arc
		(start 5.894578 -348.491048)
		(mid 6.470396 -349.08363)
		(end 7.062978 -348.507812)
		(stroke
			(width 0.2)
			(type default)
		)
		(layer "In1.Cu")
	)
	(gr_line
		(start 5.907532 -347.577156)
		(end 5.894578 -348.491048)
		(stroke
			(width 0.2)
			(type default)
		)
		(layer "In1.Cu")
	)
	(gr_line
		(start 6.091936 -121.551954)
		(end 6.1468 -122.41403)
		(stroke
			(width 0.2)
			(type default)
		)
		(layer "In1.Cu")
	)
	(gr_arc
		(start 6.093206 -102.457504)
		(mid 6.679946 -103.044244)
		(end 7.266686 -102.457504)
		(stroke
			(width 0.2)
			(type default)
		)
		(layer "In1.Cu")
	)
	(gr_line
		(start 6.093206 -101.498654)
		(end 6.093206 -102.457504)
		(stroke
			(width 0.2)
			(type default)
		)
		(layer "In1.Cu")
	)
	(gr_arc
		(start 6.093206 -98.457766)
		(mid 6.679946 -99.044506)
		(end 7.266686 -98.457766)
		(stroke
			(width 0.2)
			(type default)
		)
		(layer "In1.Cu")
	)
	(gr_line
		(start 6.093206 -97.498916)
		(end 6.093206 -98.457766)
		(stroke
			(width 0.2)
			(type default)
		)
		(layer "In1.Cu")
	)
	(gr_line
		(start 6.094476 -121.5517)
		(end 6.091936 -121.551954)
		(stroke
			(width 0.2)
			(type default)
		)
		(layer "In1.Cu")
	)
	(gr_line
		(start 6.116574 -107.545378)
		(end 6.148324 -108.408216)
		(stroke
			(width 0.2)
			(type default)
		)
		(layer "In1.Cu")
	)
	(gr_arc
		(start 6.118606 -128.458214)
		(mid 6.705346 -129.044954)
		(end 7.292086 -128.458214)
		(stroke
			(width 0.2)
			(type default)
		)
		(layer "In1.Cu")
	)
	(gr_line
		(start 6.118606 -127.499364)
		(end 6.118606 -128.458214)
		(stroke
			(width 0.2)
			(type default)
		)
		(layer "In1.Cu")
	)
	(gr_line
		(start 6.119114 -107.545378)
		(end 6.116574 -107.545378)
		(stroke
			(width 0.2)
			(type default)
		)
		(layer "In1.Cu")
	)
	(gr_line
		(start 6.140704 -117.514624)
		(end 6.144006 -118.429532)
		(stroke
			(width 0.2)
			(type default)
		)
		(layer "In1.Cu")
	)
	(gr_line
		(start 6.142482 -111.613442)
		(end 6.16966 -112.476788)
		(stroke
			(width 0.2)
			(type default)
		)
		(layer "In1.Cu")
	)
	(gr_arc
		(start 6.144006 -118.429532)
		(mid 6.732778 -119.01424)
		(end 7.317486 -118.425468)
		(stroke
			(width 0.2)
			(type default)
		)
		(layer "In1.Cu")
	)
	(gr_line
		(start 6.1468 -122.41403)
		(end 6.14934 -122.413776)
		(stroke
			(width 0.2)
			(type default)
		)
		(layer "In1.Cu")
	)
	(gr_line
		(start 6.148324 -108.408216)
		(end 6.148578 -108.40847)
		(stroke
			(width 0.2)
			(type default)
		)
		(layer "In1.Cu")
	)
	(gr_line
		(start 6.148578 -108.40847)
		(end 6.150864 -108.40847)
		(stroke
			(width 0.2)
			(type default)
		)
		(layer "In1.Cu")
	)
	(gr_arc
		(start 6.14934 -122.413776)
		(mid 6.771894 -122.962162)
		(end 7.32028 -122.339608)
		(stroke
			(width 0.2)
			(type default)
		)
		(layer "In1.Cu")
	)
	(gr_arc
		(start 6.150864 -108.40847)
		(mid 6.758686 -108.973112)
		(end 7.323328 -108.36529)
		(stroke
			(width 0.2)
			(type default)
		)
		(layer "In1.Cu")
	)
	(gr_arc
		(start 6.164072 -162.459416)
		(mid 6.748272 -163.043616)
		(end 7.332472 -162.459416)
		(stroke
			(width 0.2)
			(type default)
		)
		(layer "In1.Cu")
	)
	(gr_line
		(start 6.164072 -161.5313)
		(end 6.164072 -162.459416)
		(stroke
			(width 0.2)
			(type default)
		)
		(layer "In1.Cu")
	)
	(gr_arc
		(start 6.169406 -134.442708)
		(mid 6.756146 -135.029448)
		(end 7.342886 -134.442708)
		(stroke
			(width 0.2)
			(type default)
		)
		(layer "In1.Cu")
	)
	(gr_line
		(start 6.169406 -133.514592)
		(end 6.169406 -134.442708)
		(stroke
			(width 0.2)
			(type default)
		)
		(layer "In1.Cu")
	)
	(gr_arc
		(start 6.16966 -112.476788)
		(mid 6.774688 -113.044732)
		(end 7.342632 -112.439704)
		(stroke
			(width 0.2)
			(type default)
		)
		(layer "In1.Cu")
	)
	(gr_line
		(start 6.205474 -165.630606)
		(end 6.272022 -166.797228)
		(stroke
			(width 0.2)
			(type default)
		)
		(layer "In1.Cu")
	)
	(gr_line
		(start 6.208014 -165.630352)
		(end 6.205474 -165.630606)
		(stroke
			(width 0.2)
			(type default)
		)
		(layer "In1.Cu")
	)
	(gr_line
		(start 6.21792 -116.441982)
		(end 6.22046 -116.441982)
		(stroke
			(width 0.2)
			(type default)
		)
		(layer "In1.Cu")
	)
	(gr_arc
		(start 6.22046 -116.441982)
		(mid 6.79069 -117.044724)
		(end 7.393432 -116.474494)
		(stroke
			(width 0.2)
			(type default)
		)
		(layer "In1.Cu")
	)
	(gr_line
		(start 6.24332 -115.515644)
		(end 6.21792 -116.441982)
		(stroke
			(width 0.2)
			(type default)
		)
		(layer "In1.Cu")
	)
	(gr_line
		(start 6.24586 -115.515644)
		(end 6.24332 -115.515644)
		(stroke
			(width 0.2)
			(type default)
		)
		(layer "In1.Cu")
	)
	(gr_line
		(start 6.272022 -166.797228)
		(end 6.274562 -166.796974)
		(stroke
			(width 0.2)
			(type default)
		)
		(layer "In1.Cu")
	)
	(gr_arc
		(start 6.274562 -166.796974)
		(mid 6.89102 -167.346884)
		(end 7.44093 -166.730426)
		(stroke
			(width 0.2)
			(type default)
		)
		(layer "In1.Cu")
	)
	(gr_arc
		(start 6.400546 -158.459678)
		(mid 6.984746 -159.043878)
		(end 7.568946 -158.459678)
		(stroke
			(width 0.2)
			(type default)
		)
		(layer "In1.Cu")
	)
	(gr_line
		(start 6.400546 -157.531562)
		(end 6.400546 -158.459678)
		(stroke
			(width 0.2)
			(type default)
		)
		(layer "In1.Cu")
	)
	(gr_arc
		(start 6.445758 -170.459654)
		(mid 7.032498 -171.046394)
		(end 7.619238 -170.459654)
		(stroke
			(width 0.2)
			(type default)
		)
		(layer "In1.Cu")
	)
	(gr_line
		(start 6.445758 -169.531538)
		(end 6.445758 -170.459654)
		(stroke
			(width 0.2)
			(type default)
		)
		(layer "In1.Cu")
	)
	(gr_arc
		(start 6.862318 -398.756378)
		(mid 6.30555 -399.366994)
		(end 6.916166 -399.923762)
		(stroke
			(width 0.2)
			(type default)
		)
		(layer "In1.Cu")
	)
	(gr_line
		(start 6.916166 -399.923762)
		(end 7.77875 -399.884138)
		(stroke
			(width 0.2)
			(type default)
		)
		(layer "In1.Cu")
	)
	(gr_line
		(start 7.003796 -352.786442)
		(end 7.004812 -352.788728)
		(stroke
			(width 0.2)
			(type default)
		)
		(layer "In1.Cu")
	)
	(gr_line
		(start 7.00405 -352.786188)
		(end 7.003796 -352.786442)
		(stroke
			(width 0.2)
			(type default)
		)
		(layer "In1.Cu")
	)
	(gr_arc
		(start 7.004812 -352.788728)
		(mid 6.70054 -353.560934)
		(end 7.47268 -353.864926)
		(stroke
			(width 0.2)
			(type default)
		)
		(layer "In1.Cu")
	)
	(gr_line
		(start 7.062978 -348.507812)
		(end 7.075932 -347.594174)
		(stroke
			(width 0.2)
			(type default)
		)
		(layer "In1.Cu")
	)
	(gr_arc
		(start 7.075932 -347.594174)
		(mid 6.500241 -347.001594)
		(end 5.907532 -347.577156)
		(stroke
			(width 0.2)
			(type default)
		)
		(layer "In1.Cu")
	)
	(gr_arc
		(start 7.215886 -413.544512)
		(mid 7.007016 -414.313851)
		(end 7.778242 -414.516062)
		(stroke
			(width 0.2)
			(type default)
		)
		(layer "In1.Cu")
	)
	(gr_line
		(start 7.249922 -422.467532)
		(end 8.113014 -422.489884)
		(stroke
			(width 0.2)
			(type default)
		)
		(layer "In1.Cu")
	)
	(gr_line
		(start 7.249922 -422.464992)
		(end 7.249922 -422.467532)
		(stroke
			(width 0.2)
			(type default)
		)
		(layer "In1.Cu")
	)
	(gr_line
		(start 7.265162 -368.402616)
		(end 8.127746 -368.441224)
		(stroke
			(width 0.2)
			(type default)
		)
		(layer "In1.Cu")
	)
	(gr_arc
		(start 7.265416 -121.477532)
		(mid 6.642862 -120.929146)
		(end 6.094476 -121.5517)
		(stroke
			(width 0.2)
			(type default)
		)
		(layer "In1.Cu")
	)
	(gr_line
		(start 7.266686 -102.457504)
		(end 7.266686 -101.498908)
		(stroke
			(width 0.2)
			(type default)
		)
		(layer "In1.Cu")
	)
	(gr_arc
		(start 7.266686 -101.498908)
		(mid 6.680073 -100.911914)
		(end 6.093206 -101.498654)
		(stroke
			(width 0.2)
			(type default)
		)
		(layer "In1.Cu")
	)
	(gr_line
		(start 7.266686 -98.457766)
		(end 7.266686 -97.49917)
		(stroke
			(width 0.2)
			(type default)
		)
		(layer "In1.Cu")
	)
	(gr_arc
		(start 7.266686 -97.49917)
		(mid 6.680073 -96.912176)
		(end 6.093206 -97.498916)
		(stroke
			(width 0.2)
			(type default)
		)
		(layer "In1.Cu")
	)
	(gr_line
		(start 7.267702 -121.477278)
		(end 7.265416 -121.477532)
		(stroke
			(width 0.2)
			(type default)
		)
		(layer "In1.Cu")
	)
	(gr_line
		(start 7.267956 -121.477532)
		(end 7.267702 -121.477278)
		(stroke
			(width 0.2)
			(type default)
		)
		(layer "In1.Cu")
	)
	(gr_arc
		(start 7.278878 -421.34282)
		(mid 6.703314 -421.889428)
		(end 7.249922 -422.464992)
		(stroke
			(width 0.2)
			(type default)
		)
		(layer "In1.Cu")
	)
	(gr_line
		(start 7.278878 -421.34028)
		(end 7.278878 -421.34282)
		(stroke
			(width 0.2)
			(type default)
		)
		(layer "In1.Cu")
	)
	(gr_arc
		(start 7.291578 -107.502198)
		(mid 6.683756 -106.937556)
		(end 6.119114 -107.545378)
		(stroke
			(width 0.2)
			(type default)
		)
		(layer "In1.Cu")
	)
	(gr_line
		(start 7.292086 -128.458214)
		(end 7.292086 -127.499618)
		(stroke
			(width 0.2)
			(type default)
		)
		(layer "In1.Cu")
	)
	(gr_arc
		(start 7.292086 -127.499618)
		(mid 6.705473 -126.912624)
		(end 6.118606 -127.499364)
		(stroke
			(width 0.2)
			(type default)
		)
		(layer "In1.Cu")
	)
	(gr_line
		(start 7.294118 -107.502198)
		(end 7.291578 -107.502198)
		(stroke
			(width 0.2)
			(type default)
		)
		(layer "In1.Cu")
	)
	(gr_arc
		(start 7.312914 -367.331752)
		(mid 6.753606 -367.843308)
		(end 7.265162 -368.402616)
		(stroke
			(width 0.2)
			(type default)
		)
		(layer "In1.Cu")
	)
	(gr_arc
		(start 7.314184 -117.510814)
		(mid 6.725539 -116.926106)
		(end 6.140704 -117.514624)
		(stroke
			(width 0.2)
			(type default)
		)
		(layer "In1.Cu")
	)
	(gr_arc
		(start 7.315454 -111.576612)
		(mid 6.710553 -111.008664)
		(end 6.142482 -111.613442)
		(stroke
			(width 0.2)
			(type default)
		)
		(layer "In1.Cu")
	)
	(gr_line
		(start 7.317486 -118.425468)
		(end 7.314184 -117.510814)
		(stroke
			(width 0.2)
			(type default)
		)
		(layer "In1.Cu")
	)
	(gr_line
		(start 7.32028 -122.339608)
		(end 7.32282 -122.339354)
		(stroke
			(width 0.2)
			(type default)
		)
		(layer "In1.Cu")
	)
	(gr_line
		(start 7.32282 -122.339354)
		(end 7.267956 -121.477532)
		(stroke
			(width 0.2)
			(type default)
		)
		(layer "In1.Cu")
	)
	(gr_line
		(start 7.323328 -108.36529)
		(end 7.325868 -108.36529)
		(stroke
			(width 0.2)
			(type default)
		)
		(layer "In1.Cu")
	)
	(gr_line
		(start 7.325868 -108.36529)
		(end 7.294118 -107.502198)
		(stroke
			(width 0.2)
			(type default)
		)
		(layer "In1.Cu")
	)
	(gr_line
		(start 7.332472 -162.459416)
		(end 7.332472 -161.531554)
		(stroke
			(width 0.2)
			(type default)
		)
		(layer "In1.Cu")
	)
	(gr_arc
		(start 7.332472 -161.531554)
		(mid 6.748399 -160.9471)
		(end 6.164072 -161.5313)
		(stroke
			(width 0.2)
			(type default)
		)
		(layer "In1.Cu")
	)
	(gr_line
		(start 7.340346 -410.396436)
		(end 8.203946 -410.396436)
		(stroke
			(width 0.2)
			(type default)
		)
		(layer "In1.Cu")
	)
	(gr_arc
		(start 7.340346 -409.273756)
		(mid 6.779006 -409.835096)
		(end 7.340346 -410.396436)
		(stroke
			(width 0.2)
			(type default)
		)
		(layer "In1.Cu")
	)
	(gr_line
		(start 7.3406 -409.273756)
		(end 7.340346 -409.273756)
		(stroke
			(width 0.2)
			(type default)
		)
		(layer "In1.Cu")
	)
	(gr_line
		(start 7.342632 -112.439704)
		(end 7.315454 -111.576612)
		(stroke
			(width 0.2)
			(type default)
		)
		(layer "In1.Cu")
	)
	(gr_line
		(start 7.342886 -134.442708)
		(end 7.342886 -133.514846)
		(stroke
			(width 0.2)
			(type default)
		)
		(layer "In1.Cu")
	)
	(gr_arc
		(start 7.342886 -133.514846)
		(mid 6.756273 -132.927852)
		(end 6.169406 -133.514592)
		(stroke
			(width 0.2)
			(type default)
		)
		(layer "In1.Cu")
	)
	(gr_arc
		(start 7.351776 -357.949754)
		(mid 6.7818 -358.54767)
		(end 7.379716 -359.117646)
		(stroke
			(width 0.2)
			(type default)
		)
		(layer "In1.Cu")
	)
	(gr_line
		(start 7.351776 -357.947214)
		(end 7.351776 -357.949754)
		(stroke
			(width 0.2)
			(type default)
		)
		(layer "In1.Cu")
	)
	(gr_line
		(start 7.358888 -424.590464)
		(end 8.22071 -424.642788)
		(stroke
			(width 0.2)
			(type default)
		)
		(layer "In1.Cu")
	)
	(gr_line
		(start 7.359142 -424.587924)
		(end 7.358888 -424.590464)
		(stroke
			(width 0.2)
			(type default)
		)
		(layer "In1.Cu")
	)
	(gr_arc
		(start 7.374382 -165.563804)
		(mid 6.757924 -165.013894)
		(end 6.208014 -165.630352)
		(stroke
			(width 0.2)
			(type default)
		)
		(layer "In1.Cu")
	)
	(gr_line
		(start 7.375398 -363.918246)
		(end 7.376922 -363.920278)
		(stroke
			(width 0.2)
			(type default)
		)
		(layer "In1.Cu")
	)
	(gr_line
		(start 7.376668 -165.563804)
		(end 7.374382 -165.563804)
		(stroke
			(width 0.2)
			(type default)
		)
		(layer "In1.Cu")
	)
	(gr_arc
		(start 7.376922 -363.920278)
		(mid 7.291324 -364.745524)
		(end 8.11657 -364.831122)
		(stroke
			(width 0.2)
			(type default)
		)
		(layer "In1.Cu")
	)
	(gr_line
		(start 7.376922 -165.563804)
		(end 7.376668 -165.563804)
		(stroke
			(width 0.2)
			(type default)
		)
		(layer "In1.Cu")
	)
	(gr_line
		(start 7.379716 -359.120186)
		(end 8.25627 -359.099358)
		(stroke
			(width 0.2)
			(type default)
		)
		(layer "In1.Cu")
	)
	(gr_line
		(start 7.379716 -359.117646)
		(end 7.379716 -359.120186)
		(stroke
			(width 0.2)
			(type default)
		)
		(layer "In1.Cu")
	)
	(gr_line
		(start 7.393432 -116.474494)
		(end 7.395972 -116.474494)
		(stroke
			(width 0.2)
			(type default)
		)
		(layer "In1.Cu")
	)
	(gr_line
		(start 7.395972 -116.474494)
		(end 7.421372 -115.54841)
		(stroke
			(width 0.2)
			(type default)
		)
		(layer "In1.Cu")
	)
	(gr_arc
		(start 7.418832 -115.548156)
		(mid 6.848602 -114.945414)
		(end 6.24586 -115.515644)
		(stroke
			(width 0.2)
			(type default)
		)
		(layer "In1.Cu")
	)
	(gr_line
		(start 7.421118 -115.548156)
		(end 7.418832 -115.548156)
		(stroke
			(width 0.2)
			(type default)
		)
		(layer "In1.Cu")
	)
	(gr_line
		(start 7.421372 -115.54841)
		(end 7.421118 -115.548156)
		(stroke
			(width 0.2)
			(type default)
		)
		(layer "In1.Cu")
	)
	(gr_arc
		(start 7.423658 -423.518076)
		(mid 6.856476 -424.020742)
		(end 7.359142 -424.587924)
		(stroke
			(width 0.2)
			(type default)
		)
		(layer "In1.Cu")
	)
	(gr_line
		(start 7.423912 -423.515536)
		(end 7.423658 -423.518076)
		(stroke
			(width 0.2)
			(type default)
		)
		(layer "In1.Cu")
	)
	(gr_line
		(start 7.44093 -166.730426)
		(end 7.44347 -166.730172)
		(stroke
			(width 0.2)
			(type default)
		)
		(layer "In1.Cu")
	)
	(gr_line
		(start 7.44347 -166.730172)
		(end 7.376922 -165.563804)
		(stroke
			(width 0.2)
			(type default)
		)
		(layer "In1.Cu")
	)
	(gr_line
		(start 7.47268 -353.864926)
		(end 7.473696 -353.867212)
		(stroke
			(width 0.2)
			(type default)
		)
		(layer "In1.Cu")
	)
	(gr_line
		(start 7.473696 -353.867212)
		(end 8.447532 -353.443794)
		(stroke
			(width 0.2)
			(type default)
		)
		(layer "In1.Cu")
	)
	(gr_line
		(start 7.516622 -418.417248)
		(end 8.380222 -418.429694)
		(stroke
			(width 0.2)
			(type default)
		)
		(layer "In1.Cu")
	)
	(gr_arc
		(start 7.53364 -417.243768)
		(mid 6.93852 -417.821999)
		(end 7.516622 -418.417248)
		(stroke
			(width 0.2)
			(type default)
		)
		(layer "In1.Cu")
	)
	(gr_arc
		(start 7.566406 -386.461)
		(mid 8.127746 -387.02234)
		(end 8.689086 -386.461)
		(stroke
			(width 0.2)
			(type default)
		)
		(layer "In1.Cu")
	)
	(gr_line
		(start 7.566406 -385.532884)
		(end 7.566406 -386.461)
		(stroke
			(width 0.2)
			(type default)
		)
		(layer "In1.Cu")
	)
	(gr_line
		(start 7.568946 -158.459678)
		(end 7.568946 -157.531816)
		(stroke
			(width 0.2)
			(type default)
		)
		(layer "In1.Cu")
	)
	(gr_arc
		(start 7.568946 -157.531816)
		(mid 6.984873 -156.947362)
		(end 6.400546 -157.531562)
		(stroke
			(width 0.2)
			(type default)
		)
		(layer "In1.Cu")
	)
	(gr_line
		(start 7.619238 -170.459654)
		(end 7.619238 -169.531792)
		(stroke
			(width 0.2)
			(type default)
		)
		(layer "In1.Cu")
	)
	(gr_arc
		(start 7.619238 -169.531792)
		(mid 7.032625 -168.944798)
		(end 6.445758 -169.531538)
		(stroke
			(width 0.2)
			(type default)
		)
		(layer "In1.Cu")
	)
	(gr_line
		(start 7.623048 -384.608832)
		(end 8.485886 -384.647186)
		(stroke
			(width 0.2)
			(type default)
		)
		(layer "In1.Cu")
	)
	(gr_arc
		(start 7.675626 -383.436368)
		(mid 7.063238 -383.996311)
		(end 7.623048 -384.608832)
		(stroke
			(width 0.2)
			(type default)
		)
		(layer "In1.Cu")
	)
	(gr_line
		(start 7.689088 -372.065804)
		(end 8.587486 -372.107206)
		(stroke
			(width 0.2)
			(type default)
		)
		(layer "In1.Cu")
	)
	(gr_line
		(start 7.725156 -398.716754)
		(end 6.862318 -398.756378)
		(stroke
			(width 0.2)
			(type default)
		)
		(layer "In1.Cu")
	)
	(gr_arc
		(start 7.74319 -370.89334)
		(mid 7.13004 -371.452521)
		(end 7.689088 -372.065804)
		(stroke
			(width 0.2)
			(type default)
		)
		(layer "In1.Cu")
	)
	(gr_line
		(start 7.746746 -380.96444)
		(end 8.660892 -380.96444)
		(stroke
			(width 0.2)
			(type default)
		)
		(layer "In1.Cu")
	)
	(gr_arc
		(start 7.746746 -379.79096)
		(mid 7.160006 -380.3777)
		(end 7.746746 -380.96444)
		(stroke
			(width 0.2)
			(type default)
		)
		(layer "In1.Cu")
	)
	(gr_line
		(start 7.778242 -414.516062)
		(end 8.581898 -414.041336)
		(stroke
			(width 0.2)
			(type default)
		)
		(layer "In1.Cu")
	)
	(gr_arc
		(start 7.77875 -399.884138)
		(mid 8.335766 -399.273649)
		(end 7.725156 -398.716754)
		(stroke
			(width 0.2)
			(type default)
		)
		(layer "In1.Cu")
	)
	(gr_line
		(start 7.817104 -375.905268)
		(end 7.817358 -375.907808)
		(stroke
			(width 0.2)
			(type default)
		)
		(layer "In1.Cu")
	)
	(gr_arc
		(start 7.817358 -375.907808)
		(mid 7.340854 -376.497088)
		(end 7.930134 -376.973592)
		(stroke
			(width 0.2)
			(type default)
		)
		(layer "In1.Cu")
	)
	(gr_line
		(start 7.930134 -376.973592)
		(end 7.930388 -376.976132)
		(stroke
			(width 0.2)
			(type default)
		)
		(layer "In1.Cu")
	)
	(gr_line
		(start 7.930388 -376.976132)
		(end 8.810498 -376.882914)
		(stroke
			(width 0.2)
			(type default)
		)
		(layer "In1.Cu")
	)
	(gr_line
		(start 7.977632 -352.36277)
		(end 7.00405 -352.786188)
		(stroke
			(width 0.2)
			(type default)
		)
		(layer "In1.Cu")
	)
	(gr_line
		(start 7.978648 -352.365056)
		(end 7.977632 -352.36277)
		(stroke
			(width 0.2)
			(type default)
		)
		(layer "In1.Cu")
	)
	(gr_line
		(start 8.010906 -413.074612)
		(end 7.215886 -413.544512)
		(stroke
			(width 0.2)
			(type default)
		)
		(layer "In1.Cu")
	)
	(gr_line
		(start 8.062976 -363.359954)
		(end 7.375398 -363.918246)
		(stroke
			(width 0.2)
			(type default)
		)
		(layer "In1.Cu")
	)
	(gr_line
		(start 8.0645 -363.361986)
		(end 8.062976 -363.359954)
		(stroke
			(width 0.2)
			(type default)
		)
		(layer "In1.Cu")
	)
	(gr_line
		(start 8.113014 -422.489884)
		(end 8.113268 -422.48963)
		(stroke
			(width 0.2)
			(type default)
		)
		(layer "In1.Cu")
	)
	(gr_line
		(start 8.113268 -422.48963)
		(end 8.113268 -422.487344)
		(stroke
			(width 0.2)
			(type default)
		)
		(layer "In1.Cu")
	)
	(gr_arc
		(start 8.113268 -422.487344)
		(mid 8.688832 -421.940736)
		(end 8.142224 -421.365172)
		(stroke
			(width 0.2)
			(type default)
		)
		(layer "In1.Cu")
	)
	(gr_line
		(start 8.11657 -364.831122)
		(end 8.118094 -364.833154)
		(stroke
			(width 0.2)
			(type default)
		)
		(layer "In1.Cu")
	)
	(gr_line
		(start 8.118094 -364.833154)
		(end 8.805672 -364.275116)
		(stroke
			(width 0.2)
			(type default)
		)
		(layer "In1.Cu")
	)
	(gr_arc
		(start 8.127746 -368.441224)
		(mid 8.687314 -367.929795)
		(end 8.175752 -367.37036)
		(stroke
			(width 0.2)
			(type default)
		)
		(layer "In1.Cu")
	)
	(gr_line
		(start 8.142224 -421.365172)
		(end 8.142224 -421.362632)
		(stroke
			(width 0.2)
			(type default)
		)
		(layer "In1.Cu")
	)
	(gr_line
		(start 8.142224 -421.362632)
		(end 7.278878 -421.34028)
		(stroke
			(width 0.2)
			(type default)
		)
		(layer "In1.Cu")
	)
	(gr_line
		(start 8.175752 -367.37036)
		(end 7.312914 -367.331752)
		(stroke
			(width 0.2)
			(type default)
		)
		(layer "In1.Cu")
	)
	(gr_arc
		(start 8.203946 -410.396436)
		(mid 8.765286 -409.835096)
		(end 8.203946 -409.273756)
		(stroke
			(width 0.2)
			(type default)
		)
		(layer "In1.Cu")
	)
	(gr_line
		(start 8.203946 -409.273756)
		(end 7.3406 -409.273756)
		(stroke
			(width 0.2)
			(type default)
		)
		(layer "In1.Cu")
	)
	(gr_line
		(start 8.22071 -424.642788)
		(end 8.220964 -424.642534)
		(stroke
			(width 0.2)
			(type default)
		)
		(layer "In1.Cu")
	)
	(gr_line
		(start 8.220964 -424.642534)
		(end 8.221218 -424.640248)
		(stroke
			(width 0.2)
			(type default)
		)
		(layer "In1.Cu")
	)
	(gr_arc
		(start 8.221218 -424.640248)
		(mid 8.7884 -424.137582)
		(end 8.285734 -423.5704)
		(stroke
			(width 0.2)
			(type default)
		)
		(layer "In1.Cu")
	)
	(gr_line
		(start 8.228584 -357.928926)
		(end 8.228584 -357.926386)
		(stroke
			(width 0.2)
			(type default)
		)
		(layer "In1.Cu")
	)
	(gr_line
		(start 8.228584 -357.926386)
		(end 7.351776 -357.947214)
		(stroke
			(width 0.2)
			(type default)
		)
		(layer "In1.Cu")
	)
	(gr_line
		(start 8.25627 -359.099358)
		(end 8.256524 -359.099104)
		(stroke
			(width 0.2)
			(type default)
		)
		(layer "In1.Cu")
	)
	(gr_line
		(start 8.256524 -359.099104)
		(end 8.256524 -359.096818)
		(stroke
			(width 0.2)
			(type default)
		)
		(layer "In1.Cu")
	)
	(gr_arc
		(start 8.256524 -359.096818)
		(mid 8.8265 -358.498902)
		(end 8.228584 -357.928926)
		(stroke
			(width 0.2)
			(type default)
		)
		(layer "In1.Cu")
	)
	(gr_line
		(start 8.285734 -423.5704)
		(end 8.285988 -423.56786)
		(stroke
			(width 0.2)
			(type default)
		)
		(layer "In1.Cu")
	)
	(gr_line
		(start 8.285988 -423.56786)
		(end 7.423912 -423.515536)
		(stroke
			(width 0.2)
			(type default)
		)
		(layer "In1.Cu")
	)
	(gr_arc
		(start 8.380222 -418.429694)
		(mid 8.975344 -417.851336)
		(end 8.396986 -417.256214)
		(stroke
			(width 0.2)
			(type default)
		)
		(layer "In1.Cu")
	)
	(gr_line
		(start 8.396986 -417.256214)
		(end 7.53364 -417.243768)
		(stroke
			(width 0.2)
			(type default)
		)
		(layer "In1.Cu")
	)
	(gr_arc
		(start 8.446516 -353.441508)
		(mid 8.750808 -352.669348)
		(end 7.978648 -352.365056)
		(stroke
			(width 0.2)
			(type default)
		)
		(layer "In1.Cu")
	)
	(gr_line
		(start 8.447532 -353.443794)
		(end 8.446516 -353.441508)
		(stroke
			(width 0.2)
			(type default)
		)
		(layer "In1.Cu")
	)
	(gr_arc
		(start 8.485886 -384.647186)
		(mid 9.09828 -384.087116)
		(end 8.53821 -383.474722)
		(stroke
			(width 0.2)
			(type default)
		)
		(layer "In1.Cu")
	)
	(gr_line
		(start 8.53821 -383.474722)
		(end 7.675626 -383.436368)
		(stroke
			(width 0.2)
			(type default)
		)
		(layer "In1.Cu")
	)
	(gr_arc
		(start 8.581898 -414.041336)
		(mid 8.779764 -413.272478)
		(end 8.010906 -413.074612)
		(stroke
			(width 0.2)
			(type default)
		)
		(layer "In1.Cu")
	)
	(gr_arc
		(start 8.587486 -372.107206)
		(mid 9.200642 -371.547898)
		(end 8.641334 -370.934742)
		(stroke
			(width 0.2)
			(type default)
		)
		(layer "In1.Cu")
	)
	(gr_line
		(start 8.641334 -370.934742)
		(end 7.74319 -370.89334)
		(stroke
			(width 0.2)
			(type default)
		)
		(layer "In1.Cu")
	)
	(gr_line
		(start 8.660892 -380.96444)
		(end 8.661146 -380.96444)
		(stroke
			(width 0.2)
			(type default)
		)
		(layer "In1.Cu")
	)
	(gr_arc
		(start 8.661146 -380.96444)
		(mid 9.247886 -380.3777)
		(end 8.661146 -379.79096)
		(stroke
			(width 0.2)
			(type default)
		)
		(layer "In1.Cu")
	)
	(gr_line
		(start 8.661146 -379.79096)
		(end 7.746746 -379.79096)
		(stroke
			(width 0.2)
			(type default)
		)
		(layer "In1.Cu")
	)
	(gr_arc
		(start 8.684006 -132.4737)
		(mid 9.270746 -133.06044)
		(end 9.857486 -132.4737)
		(stroke
			(width 0.2)
			(type default)
		)
		(layer "In1.Cu")
	)
	(gr_line
		(start 8.684006 -131.51485)
		(end 8.684006 -132.4737)
		(stroke
			(width 0.2)
			(type default)
		)
		(layer "In1.Cu")
	)
	(gr_line
		(start 8.689086 -386.461)
		(end 8.689086 -385.533138)
		(stroke
			(width 0.2)
			(type default)
		)
		(layer "In1.Cu")
	)
	(gr_arc
		(start 8.689086 -385.533138)
		(mid 8.127873 -384.971544)
		(end 7.566406 -385.532884)
		(stroke
			(width 0.2)
			(type default)
		)
		(layer "In1.Cu")
	)
	(gr_line
		(start 8.697468 -375.81205)
		(end 7.817104 -375.905268)
		(stroke
			(width 0.2)
			(type default)
		)
		(layer "In1.Cu")
	)
	(gr_line
		(start 8.697722 -375.81459)
		(end 8.697468 -375.81205)
		(stroke
			(width 0.2)
			(type default)
		)
		(layer "In1.Cu")
	)
	(gr_arc
		(start 8.804148 -364.27283)
		(mid 8.889746 -363.447584)
		(end 8.0645 -363.361986)
		(stroke
			(width 0.2)
			(type default)
		)
		(layer "In1.Cu")
	)
	(gr_line
		(start 8.805672 -364.275116)
		(end 8.805672 -364.274608)
		(stroke
			(width 0.2)
			(type default)
		)
		(layer "In1.Cu")
	)
	(gr_line
		(start 8.805672 -364.274608)
		(end 8.804148 -364.27283)
		(stroke
			(width 0.2)
			(type default)
		)
		(layer "In1.Cu")
	)
	(gr_line
		(start 8.810498 -376.882914)
		(end 8.810752 -376.88266)
		(stroke
			(width 0.2)
			(type default)
		)
		(layer "In1.Cu")
	)
	(gr_arc
		(start 8.810498 -376.880374)
		(mid 9.287002 -376.291094)
		(end 8.697722 -375.81459)
		(stroke
			(width 0.2)
			(type default)
		)
		(layer "In1.Cu")
	)
	(gr_line
		(start 8.810752 -376.88266)
		(end 8.810498 -376.880374)
		(stroke
			(width 0.2)
			(type default)
		)
		(layer "In1.Cu")
	)
	(gr_line
		(start 9.857486 -132.4737)
		(end 9.857486 -131.515104)
		(stroke
			(width 0.2)
			(type default)
		)
		(layer "In1.Cu")
	)
	(gr_arc
		(start 9.857486 -131.515104)
		(mid 9.270873 -130.92811)
		(end 8.684006 -131.51485)
		(stroke
			(width 0.2)
			(type default)
		)
		(layer "In1.Cu")
	)
	(gr_arc
		(start 11.066018 -439.032904)
		(mid 11.652631 -439.619898)
		(end 12.239498 -439.033158)
		(stroke
			(width 0.2)
			(type default)
		)
		(layer "In1.Cu")
	)
	(gr_line
		(start 11.066018 -438.105042)
		(end 11.066018 -439.032904)
		(stroke
			(width 0.2)
			(type default)
		)
		(layer "In1.Cu")
	)
	(gr_line
		(start 11.0744 -441.81014)
		(end 11.937746 -441.81014)
		(stroke
			(width 0.2)
			(type default)
		)
		(layer "In1.Cu")
	)
	(gr_arc
		(start 11.0744 -440.63666)
		(mid 10.48766 -441.2234)
		(end 11.0744 -441.81014)
		(stroke
			(width 0.2)
			(type default)
		)
		(layer "In1.Cu")
	)
	(gr_line
		(start 11.937746 -441.81014)
		(end 11.938 -441.81014)
		(stroke
			(width 0.2)
			(type default)
		)
		(layer "In1.Cu")
	)
	(gr_arc
		(start 11.938 -441.81014)
		(mid 12.52474 -441.2234)
		(end 11.938 -440.63666)
		(stroke
			(width 0.2)
			(type default)
		)
		(layer "In1.Cu")
	)
	(gr_line
		(start 11.938 -440.63666)
		(end 11.0744 -440.63666)
		(stroke
			(width 0.2)
			(type default)
		)
		(layer "In1.Cu")
	)
	(gr_arc
		(start 12.192254 -177.578004)
		(mid 12.757404 -178.180746)
		(end 13.360146 -177.615596)
		(stroke
			(width 0.2)
			(type default)
		)
		(layer "In1.Cu")
	)
	(gr_line
		(start 12.220194 -176.714658)
		(end 12.192254 -177.578004)
		(stroke
			(width 0.2)
			(type default)
		)
		(layer "In1.Cu")
	)
	(gr_line
		(start 12.239498 -439.033158)
		(end 12.239498 -438.105042)
		(stroke
			(width 0.2)
			(type default)
		)
		(layer "In1.Cu")
	)
	(gr_arc
		(start 12.239498 -438.105042)
		(mid 11.652758 -437.518302)
		(end 11.066018 -438.105042)
		(stroke
			(width 0.2)
			(type default)
		)
		(layer "In1.Cu")
	)
	(gr_line
		(start 13.360146 -177.615596)
		(end 13.388086 -176.752504)
		(stroke
			(width 0.2)
			(type default)
		)
		(layer "In1.Cu")
	)
	(gr_arc
		(start 13.388086 -176.752504)
		(mid 12.823063 -176.149766)
		(end 12.220194 -176.714658)
		(stroke
			(width 0.2)
			(type default)
		)
		(layer "In1.Cu")
	)
	(gr_arc
		(start 14.653006 -136.536938)
		(mid 15.238984 -137.12444)
		(end 15.826486 -136.538462)
		(stroke
			(width 0.2)
			(type default)
		)
		(layer "In1.Cu")
	)
	(gr_line
		(start 14.654022 -135.673338)
		(end 14.653006 -136.536938)
		(stroke
			(width 0.2)
			(type default)
		)
		(layer "In1.Cu")
	)
	(gr_arc
		(start 15.770098 -120.508268)
		(mid 16.355822 -121.096024)
		(end 16.943578 -120.5103)
		(stroke
			(width 0.2)
			(type default)
		)
		(layer "In1.Cu")
	)
	(gr_line
		(start 15.771622 -119.644668)
		(end 15.770098 -120.508268)
		(stroke
			(width 0.2)
			(type default)
		)
		(layer "In1.Cu")
	)
	(gr_line
		(start 15.826486 -136.538462)
		(end 15.827502 -135.675116)
		(stroke
			(width 0.2)
			(type default)
		)
		(layer "In1.Cu")
	)
	(gr_arc
		(start 15.827502 -135.675116)
		(mid 15.241651 -135.087614)
		(end 14.654022 -135.673338)
		(stroke
			(width 0.2)
			(type default)
		)
		(layer "In1.Cu")
	)
	(gr_line
		(start 16.943578 -120.5103)
		(end 16.945102 -119.646954)
		(stroke
			(width 0.2)
			(type default)
		)
		(layer "In1.Cu")
	)
	(gr_arc
		(start 16.945102 -119.646954)
		(mid 16.359505 -119.059198)
		(end 15.771622 -119.644668)
		(stroke
			(width 0.2)
			(type default)
		)
		(layer "In1.Cu")
	)
	(gr_line
		(start 18.64741 -445.26073)
		(end 18.64741 -444.75273)
		(stroke
			(width 0.2)
			(type default)
		)
		(layer "In1.Cu")
	)
	(gr_line
		(start 18.64741 -444.75273)
		(end 20.55241 -444.75273)
		(stroke
			(width 0.2)
			(type default)
		)
		(layer "In1.Cu")
	)
	(gr_line
		(start 18.64741 -444.460884)
		(end 18.64741 -443.952884)
		(stroke
			(width 0.2)
			(type default)
		)
		(layer "In1.Cu")
	)
	(gr_line
		(start 18.64741 -443.952884)
		(end 20.55241 -443.952884)
		(stroke
			(width 0.2)
			(type default)
		)
		(layer "In1.Cu")
	)
	(gr_line
		(start 18.64741 -442.860684)
		(end 18.64741 -442.352684)
		(stroke
			(width 0.2)
			(type default)
		)
		(layer "In1.Cu")
	)
	(gr_line
		(start 18.64741 -442.352684)
		(end 20.55241 -442.352684)
		(stroke
			(width 0.2)
			(type default)
		)
		(layer "In1.Cu")
	)
	(gr_line
		(start 18.64741 -442.060838)
		(end 18.64741 -441.552838)
		(stroke
			(width 0.2)
			(type default)
		)
		(layer "In1.Cu")
	)
	(gr_line
		(start 18.64741 -441.552838)
		(end 20.55241 -441.552838)
		(stroke
			(width 0.2)
			(type default)
		)
		(layer "In1.Cu")
	)
	(gr_line
		(start 18.64741 -342.260682)
		(end 18.64741 -341.752682)
		(stroke
			(width 0.2)
			(type default)
		)
		(layer "In1.Cu")
	)
	(gr_line
		(start 18.64741 -341.752682)
		(end 20.55241 -341.752682)
		(stroke
			(width 0.2)
			(type default)
		)
		(layer "In1.Cu")
	)
	(gr_line
		(start 18.64741 -341.460836)
		(end 18.64741 -340.952836)
		(stroke
			(width 0.2)
			(type default)
		)
		(layer "In1.Cu")
	)
	(gr_line
		(start 18.64741 -340.952836)
		(end 20.55241 -340.952836)
		(stroke
			(width 0.2)
			(type default)
		)
		(layer "In1.Cu")
	)
	(gr_line
		(start 18.64741 -339.860636)
		(end 18.64741 -339.352636)
		(stroke
			(width 0.2)
			(type default)
		)
		(layer "In1.Cu")
	)
	(gr_line
		(start 18.64741 -339.352636)
		(end 20.55241 -339.352636)
		(stroke
			(width 0.2)
			(type default)
		)
		(layer "In1.Cu")
	)
	(gr_line
		(start 18.64741 -339.06079)
		(end 18.64741 -338.55279)
		(stroke
			(width 0.2)
			(type default)
		)
		(layer "In1.Cu")
	)
	(gr_line
		(start 18.64741 -338.55279)
		(end 20.55241 -338.55279)
		(stroke
			(width 0.2)
			(type default)
		)
		(layer "In1.Cu")
	)
	(gr_line
		(start 18.64741 -239.260634)
		(end 18.64741 -238.752634)
		(stroke
			(width 0.2)
			(type default)
		)
		(layer "In1.Cu")
	)
	(gr_line
		(start 18.64741 -238.752634)
		(end 20.55241 -238.752634)
		(stroke
			(width 0.2)
			(type default)
		)
		(layer "In1.Cu")
	)
	(gr_line
		(start 18.64741 -238.460788)
		(end 18.64741 -237.952788)
		(stroke
			(width 0.2)
			(type default)
		)
		(layer "In1.Cu")
	)
	(gr_line
		(start 18.64741 -237.952788)
		(end 20.55241 -237.952788)
		(stroke
			(width 0.2)
			(type default)
		)
		(layer "In1.Cu")
	)
	(gr_line
		(start 18.64741 -236.860588)
		(end 18.64741 -236.352588)
		(stroke
			(width 0.2)
			(type default)
		)
		(layer "In1.Cu")
	)
	(gr_line
		(start 18.64741 -236.352588)
		(end 20.55241 -236.352588)
		(stroke
			(width 0.2)
			(type default)
		)
		(layer "In1.Cu")
	)
	(gr_line
		(start 18.64741 -236.060742)
		(end 18.64741 -235.552742)
		(stroke
			(width 0.2)
			(type default)
		)
		(layer "In1.Cu")
	)
	(gr_line
		(start 18.64741 -235.552742)
		(end 20.55241 -235.552742)
		(stroke
			(width 0.2)
			(type default)
		)
		(layer "In1.Cu")
	)
	(gr_line
		(start 18.64741 -136.260586)
		(end 18.64741 -135.752586)
		(stroke
			(width 0.2)
			(type default)
		)
		(layer "In1.Cu")
	)
	(gr_line
		(start 18.64741 -135.752586)
		(end 20.55241 -135.752586)
		(stroke
			(width 0.2)
			(type default)
		)
		(layer "In1.Cu")
	)
	(gr_line
		(start 18.64741 -135.46074)
		(end 18.64741 -134.95274)
		(stroke
			(width 0.2)
			(type default)
		)
		(layer "In1.Cu")
	)
	(gr_line
		(start 18.64741 -134.95274)
		(end 20.55241 -134.95274)
		(stroke
			(width 0.2)
			(type default)
		)
		(layer "In1.Cu")
	)
	(gr_line
		(start 18.64741 -133.86054)
		(end 18.64741 -133.35254)
		(stroke
			(width 0.2)
			(type default)
		)
		(layer "In1.Cu")
	)
	(gr_line
		(start 18.64741 -133.35254)
		(end 20.55241 -133.35254)
		(stroke
			(width 0.2)
			(type default)
		)
		(layer "In1.Cu")
	)
	(gr_line
		(start 18.64741 -133.060694)
		(end 18.64741 -132.552694)
		(stroke
			(width 0.2)
			(type default)
		)
		(layer "In1.Cu")
	)
	(gr_line
		(start 18.64741 -132.552694)
		(end 20.55241 -132.552694)
		(stroke
			(width 0.2)
			(type default)
		)
		(layer "In1.Cu")
	)
	(gr_line
		(start 18.64741 -33.260538)
		(end 18.64741 -32.752538)
		(stroke
			(width 0.2)
			(type default)
		)
		(layer "In1.Cu")
	)
	(gr_line
		(start 18.64741 -32.752538)
		(end 20.55241 -32.752538)
		(stroke
			(width 0.2)
			(type default)
		)
		(layer "In1.Cu")
	)
	(gr_line
		(start 18.64741 -32.460692)
		(end 18.64741 -31.952692)
		(stroke
			(width 0.2)
			(type default)
		)
		(layer "In1.Cu")
	)
	(gr_line
		(start 18.64741 -31.952692)
		(end 20.55241 -31.952692)
		(stroke
			(width 0.2)
			(type default)
		)
		(layer "In1.Cu")
	)
	(gr_line
		(start 18.64741 -30.860492)
		(end 18.64741 -30.352492)
		(stroke
			(width 0.2)
			(type default)
		)
		(layer "In1.Cu")
	)
	(gr_line
		(start 18.64741 -30.352492)
		(end 20.55241 -30.352492)
		(stroke
			(width 0.2)
			(type default)
		)
		(layer "In1.Cu")
	)
	(gr_line
		(start 18.64741 -30.060646)
		(end 18.64741 -29.552646)
		(stroke
			(width 0.2)
			(type default)
		)
		(layer "In1.Cu")
	)
	(gr_line
		(start 18.64741 -29.552646)
		(end 20.55241 -29.552646)
		(stroke
			(width 0.2)
			(type default)
		)
		(layer "In1.Cu")
	)
	(gr_line
		(start 19.557746 -169.33164)
		(end 20.446492 -169.33164)
		(stroke
			(width 0.2)
			(type default)
		)
		(layer "In1.Cu")
	)
	(gr_arc
		(start 19.557746 -168.25976)
		(mid 19.021806 -168.7957)
		(end 19.557746 -169.33164)
		(stroke
			(width 0.2)
			(type default)
		)
		(layer "In1.Cu")
	)
	(gr_arc
		(start 20.446492 -169.33164)
		(mid 20.982686 -168.795827)
		(end 20.446746 -168.25976)
		(stroke
			(width 0.2)
			(type default)
		)
		(layer "In1.Cu")
	)
	(gr_line
		(start 20.446746 -168.25976)
		(end 19.557746 -168.25976)
		(stroke
			(width 0.2)
			(type default)
		)
		(layer "In1.Cu")
	)
	(gr_line
		(start 20.55241 -445.26073)
		(end 18.64741 -445.26073)
		(stroke
			(width 0.2)
			(type default)
		)
		(layer "In1.Cu")
	)
	(gr_line
		(start 20.55241 -444.75273)
		(end 20.55241 -445.26073)
		(stroke
			(width 0.2)
			(type default)
		)
		(layer "In1.Cu")
	)
	(gr_line
		(start 20.55241 -444.460884)
		(end 18.64741 -444.460884)
		(stroke
			(width 0.2)
			(type default)
		)
		(layer "In1.Cu")
	)
	(gr_line
		(start 20.55241 -443.952884)
		(end 20.55241 -444.460884)
		(stroke
			(width 0.2)
			(type default)
		)
		(layer "In1.Cu")
	)
	(gr_line
		(start 20.55241 -442.860684)
		(end 18.64741 -442.860684)
		(stroke
			(width 0.2)
			(type default)
		)
		(layer "In1.Cu")
	)
	(gr_line
		(start 20.55241 -442.352684)
		(end 20.55241 -442.860684)
		(stroke
			(width 0.2)
			(type default)
		)
		(layer "In1.Cu")
	)
	(gr_line
		(start 20.55241 -442.060838)
		(end 18.64741 -442.060838)
		(stroke
			(width 0.2)
			(type default)
		)
		(layer "In1.Cu")
	)
	(gr_line
		(start 20.55241 -441.552838)
		(end 20.55241 -442.060838)
		(stroke
			(width 0.2)
			(type default)
		)
		(layer "In1.Cu")
	)
	(gr_line
		(start 20.55241 -342.260682)
		(end 18.64741 -342.260682)
		(stroke
			(width 0.2)
			(type default)
		)
		(layer "In1.Cu")
	)
	(gr_line
		(start 20.55241 -341.752682)
		(end 20.55241 -342.260682)
		(stroke
			(width 0.2)
			(type default)
		)
		(layer "In1.Cu")
	)
	(gr_line
		(start 20.55241 -341.460836)
		(end 18.64741 -341.460836)
		(stroke
			(width 0.2)
			(type default)
		)
		(layer "In1.Cu")
	)
	(gr_line
		(start 20.55241 -340.952836)
		(end 20.55241 -341.460836)
		(stroke
			(width 0.2)
			(type default)
		)
		(layer "In1.Cu")
	)
	(gr_line
		(start 20.55241 -339.860636)
		(end 18.64741 -339.860636)
		(stroke
			(width 0.2)
			(type default)
		)
		(layer "In1.Cu")
	)
	(gr_line
		(start 20.55241 -339.352636)
		(end 20.55241 -339.860636)
		(stroke
			(width 0.2)
			(type default)
		)
		(layer "In1.Cu")
	)
	(gr_line
		(start 20.55241 -339.06079)
		(end 18.64741 -339.06079)
		(stroke
			(width 0.2)
			(type default)
		)
		(layer "In1.Cu")
	)
	(gr_line
		(start 20.55241 -338.55279)
		(end 20.55241 -339.06079)
		(stroke
			(width 0.2)
			(type default)
		)
		(layer "In1.Cu")
	)
	(gr_line
		(start 20.55241 -239.260634)
		(end 18.64741 -239.260634)
		(stroke
			(width 0.2)
			(type default)
		)
		(layer "In1.Cu")
	)
	(gr_line
		(start 20.55241 -238.752634)
		(end 20.55241 -239.260634)
		(stroke
			(width 0.2)
			(type default)
		)
		(layer "In1.Cu")
	)
	(gr_line
		(start 20.55241 -238.460788)
		(end 18.64741 -238.460788)
		(stroke
			(width 0.2)
			(type default)
		)
		(layer "In1.Cu")
	)
	(gr_line
		(start 20.55241 -237.952788)
		(end 20.55241 -238.460788)
		(stroke
			(width 0.2)
			(type default)
		)
		(layer "In1.Cu")
	)
	(gr_line
		(start 20.55241 -236.860588)
		(end 18.64741 -236.860588)
		(stroke
			(width 0.2)
			(type default)
		)
		(layer "In1.Cu")
	)
	(gr_line
		(start 20.55241 -236.352588)
		(end 20.55241 -236.860588)
		(stroke
			(width 0.2)
			(type default)
		)
		(layer "In1.Cu")
	)
	(gr_line
		(start 20.55241 -236.060742)
		(end 18.64741 -236.060742)
		(stroke
			(width 0.2)
			(type default)
		)
		(layer "In1.Cu")
	)
	(gr_line
		(start 20.55241 -235.552742)
		(end 20.55241 -236.060742)
		(stroke
			(width 0.2)
			(type default)
		)
		(layer "In1.Cu")
	)
	(gr_line
		(start 20.55241 -136.260586)
		(end 18.64741 -136.260586)
		(stroke
			(width 0.2)
			(type default)
		)
		(layer "In1.Cu")
	)
	(gr_line
		(start 20.55241 -135.752586)
		(end 20.55241 -136.260586)
		(stroke
			(width 0.2)
			(type default)
		)
		(layer "In1.Cu")
	)
	(gr_line
		(start 20.55241 -135.46074)
		(end 18.64741 -135.46074)
		(stroke
			(width 0.2)
			(type default)
		)
		(layer "In1.Cu")
	)
	(gr_line
		(start 20.55241 -134.95274)
		(end 20.55241 -135.46074)
		(stroke
			(width 0.2)
			(type default)
		)
		(layer "In1.Cu")
	)
	(gr_line
		(start 20.55241 -133.86054)
		(end 18.64741 -133.86054)
		(stroke
			(width 0.2)
			(type default)
		)
		(layer "In1.Cu")
	)
	(gr_line
		(start 20.55241 -133.35254)
		(end 20.55241 -133.86054)
		(stroke
			(width 0.2)
			(type default)
		)
		(layer "In1.Cu")
	)
	(gr_line
		(start 20.55241 -133.060694)
		(end 18.64741 -133.060694)
		(stroke
			(width 0.2)
			(type default)
		)
		(layer "In1.Cu")
	)
	(gr_line
		(start 20.55241 -132.552694)
		(end 20.55241 -133.060694)
		(stroke
			(width 0.2)
			(type default)
		)
		(layer "In1.Cu")
	)
	(gr_line
		(start 20.55241 -33.260538)
		(end 18.64741 -33.260538)
		(stroke
			(width 0.2)
			(type default)
		)
		(layer "In1.Cu")
	)
	(gr_line
		(start 20.55241 -32.752538)
		(end 20.55241 -33.260538)
		(stroke
			(width 0.2)
			(type default)
		)
		(layer "In1.Cu")
	)
	(gr_line
		(start 20.55241 -32.460692)
		(end 18.64741 -32.460692)
		(stroke
			(width 0.2)
			(type default)
		)
		(layer "In1.Cu")
	)
	(gr_line
		(start 20.55241 -31.952692)
		(end 20.55241 -32.460692)
		(stroke
			(width 0.2)
			(type default)
		)
		(layer "In1.Cu")
	)
	(gr_line
		(start 20.55241 -30.860492)
		(end 18.64741 -30.860492)
		(stroke
			(width 0.2)
			(type default)
		)
		(layer "In1.Cu")
	)
	(gr_line
		(start 20.55241 -30.352492)
		(end 20.55241 -30.860492)
		(stroke
			(width 0.2)
			(type default)
		)
		(layer "In1.Cu")
	)
	(gr_line
		(start 20.55241 -30.060646)
		(end 18.64741 -30.060646)
		(stroke
			(width 0.2)
			(type default)
		)
		(layer "In1.Cu")
	)
	(gr_line
		(start 20.55241 -29.552646)
		(end 20.55241 -30.060646)
		(stroke
			(width 0.2)
			(type default)
		)
		(layer "In1.Cu")
	)
	(gr_line
		(start 20.555966 -453.256904)
		(end 20.555966 -452.596504)
		(stroke
			(width 0.2)
			(type default)
		)
		(layer "In1.Cu")
	)
	(gr_line
		(start 20.555966 -452.596504)
		(end 22.943566 -452.596504)
		(stroke
			(width 0.2)
			(type default)
		)
		(layer "In1.Cu")
	)
	(gr_line
		(start 20.555966 -451.986904)
		(end 20.555966 -451.326504)
		(stroke
			(width 0.2)
			(type default)
		)
		(layer "In1.Cu")
	)
	(gr_line
		(start 20.555966 -451.326504)
		(end 22.943566 -451.326504)
		(stroke
			(width 0.2)
			(type default)
		)
		(layer "In1.Cu")
	)
	(gr_line
		(start 20.555966 -449.446904)
		(end 20.555966 -448.786504)
		(stroke
			(width 0.2)
			(type default)
		)
		(layer "In1.Cu")
	)
	(gr_line
		(start 20.555966 -448.786504)
		(end 22.943566 -448.786504)
		(stroke
			(width 0.2)
			(type default)
		)
		(layer "In1.Cu")
	)
	(gr_line
		(start 20.555966 -448.176904)
		(end 20.555966 -447.516504)
		(stroke
			(width 0.2)
			(type default)
		)
		(layer "In1.Cu")
	)
	(gr_line
		(start 20.555966 -447.516504)
		(end 22.943566 -447.516504)
		(stroke
			(width 0.2)
			(type default)
		)
		(layer "In1.Cu")
	)
	(gr_line
		(start 20.555966 -350.256856)
		(end 20.555966 -349.596456)
		(stroke
			(width 0.2)
			(type default)
		)
		(layer "In1.Cu")
	)
	(gr_line
		(start 20.555966 -349.596456)
		(end 22.943566 -349.596456)
		(stroke
			(width 0.2)
			(type default)
		)
		(layer "In1.Cu")
	)
	(gr_line
		(start 20.555966 -348.986856)
		(end 20.555966 -348.326456)
		(stroke
			(width 0.2)
			(type default)
		)
		(layer "In1.Cu")
	)
	(gr_line
		(start 20.555966 -348.326456)
		(end 22.943566 -348.326456)
		(stroke
			(width 0.2)
			(type default)
		)
		(layer "In1.Cu")
	)
	(gr_line
		(start 20.555966 -346.446856)
		(end 20.555966 -345.786456)
		(stroke
			(width 0.2)
			(type default)
		)
		(layer "In1.Cu")
	)
	(gr_line
		(start 20.555966 -345.786456)
		(end 22.943566 -345.786456)
		(stroke
			(width 0.2)
			(type default)
		)
		(layer "In1.Cu")
	)
	(gr_line
		(start 20.555966 -345.176856)
		(end 20.555966 -344.516456)
		(stroke
			(width 0.2)
			(type default)
		)
		(layer "In1.Cu")
	)
	(gr_line
		(start 20.555966 -344.516456)
		(end 22.943566 -344.516456)
		(stroke
			(width 0.2)
			(type default)
		)
		(layer "In1.Cu")
	)
	(gr_line
		(start 20.555966 -247.256808)
		(end 20.555966 -246.596408)
		(stroke
			(width 0.2)
			(type default)
		)
		(layer "In1.Cu")
	)
	(gr_line
		(start 20.555966 -246.596408)
		(end 22.943566 -246.596408)
		(stroke
			(width 0.2)
			(type default)
		)
		(layer "In1.Cu")
	)
	(gr_line
		(start 20.555966 -245.986808)
		(end 20.555966 -245.326408)
		(stroke
			(width 0.2)
			(type default)
		)
		(layer "In1.Cu")
	)
	(gr_line
		(start 20.555966 -245.326408)
		(end 22.943566 -245.326408)
		(stroke
			(width 0.2)
			(type default)
		)
		(layer "In1.Cu")
	)
	(gr_line
		(start 20.555966 -243.446808)
		(end 20.555966 -242.786408)
		(stroke
			(width 0.2)
			(type default)
		)
		(layer "In1.Cu")
	)
	(gr_line
		(start 20.555966 -242.786408)
		(end 22.943566 -242.786408)
		(stroke
			(width 0.2)
			(type default)
		)
		(layer "In1.Cu")
	)
	(gr_line
		(start 20.555966 -242.176808)
		(end 20.555966 -241.516408)
		(stroke
			(width 0.2)
			(type default)
		)
		(layer "In1.Cu")
	)
	(gr_line
		(start 20.555966 -241.516408)
		(end 22.943566 -241.516408)
		(stroke
			(width 0.2)
			(type default)
		)
		(layer "In1.Cu")
	)
	(gr_line
		(start 20.555966 -144.25676)
		(end 20.555966 -143.59636)
		(stroke
			(width 0.2)
			(type default)
		)
		(layer "In1.Cu")
	)
	(gr_line
		(start 20.555966 -143.59636)
		(end 22.943566 -143.59636)
		(stroke
			(width 0.2)
			(type default)
		)
		(layer "In1.Cu")
	)
	(gr_line
		(start 20.555966 -142.98676)
		(end 20.555966 -142.32636)
		(stroke
			(width 0.2)
			(type default)
		)
		(layer "In1.Cu")
	)
	(gr_line
		(start 20.555966 -142.32636)
		(end 22.943566 -142.32636)
		(stroke
			(width 0.2)
			(type default)
		)
		(layer "In1.Cu")
	)
	(gr_line
		(start 20.555966 -140.44676)
		(end 20.555966 -139.78636)
		(stroke
			(width 0.2)
			(type default)
		)
		(layer "In1.Cu")
	)
	(gr_line
		(start 20.555966 -139.78636)
		(end 22.943566 -139.78636)
		(stroke
			(width 0.2)
			(type default)
		)
		(layer "In1.Cu")
	)
	(gr_line
		(start 20.555966 -139.17676)
		(end 20.555966 -138.51636)
		(stroke
			(width 0.2)
			(type default)
		)
		(layer "In1.Cu")
	)
	(gr_line
		(start 20.555966 -138.51636)
		(end 22.943566 -138.51636)
		(stroke
			(width 0.2)
			(type default)
		)
		(layer "In1.Cu")
	)
	(gr_line
		(start 20.555966 -41.256712)
		(end 20.555966 -40.596312)
		(stroke
			(width 0.2)
			(type default)
		)
		(layer "In1.Cu")
	)
	(gr_line
		(start 20.555966 -40.596312)
		(end 22.943566 -40.596312)
		(stroke
			(width 0.2)
			(type default)
		)
		(layer "In1.Cu")
	)
	(gr_line
		(start 20.555966 -39.986712)
		(end 20.555966 -39.326312)
		(stroke
			(width 0.2)
			(type default)
		)
		(layer "In1.Cu")
	)
	(gr_line
		(start 20.555966 -39.326312)
		(end 22.943566 -39.326312)
		(stroke
			(width 0.2)
			(type default)
		)
		(layer "In1.Cu")
	)
	(gr_line
		(start 20.555966 -37.446712)
		(end 20.555966 -36.786312)
		(stroke
			(width 0.2)
			(type default)
		)
		(layer "In1.Cu")
	)
	(gr_line
		(start 20.555966 -36.786312)
		(end 22.943566 -36.786312)
		(stroke
			(width 0.2)
			(type default)
		)
		(layer "In1.Cu")
	)
	(gr_line
		(start 20.555966 -36.176712)
		(end 20.555966 -35.516312)
		(stroke
			(width 0.2)
			(type default)
		)
		(layer "In1.Cu")
	)
	(gr_line
		(start 20.555966 -35.516312)
		(end 22.943566 -35.516312)
		(stroke
			(width 0.2)
			(type default)
		)
		(layer "In1.Cu")
	)
	(gr_line
		(start 21.053044 -444.232792)
		(end 21.090382 -445.095376)
		(stroke
			(width 0.2)
			(type default)
		)
		(layer "In1.Cu")
	)
	(gr_arc
		(start 21.090382 -445.095376)
		(mid 21.701887 -445.656457)
		(end 22.262846 -445.04483)
		(stroke
			(width 0.2)
			(type default)
		)
		(layer "In1.Cu")
	)
	(gr_arc
		(start 21.26107 -238.799624)
		(mid 21.774529 -239.451657)
		(end 22.426422 -238.938054)
		(stroke
			(width 0.2)
			(type default)
		)
		(layer "In1.Cu")
	)
	(gr_arc
		(start 21.307806 -136.15035)
		(mid 21.894546 -136.73709)
		(end 22.481286 -136.15035)
		(stroke
			(width 0.2)
			(type default)
		)
		(layer "In1.Cu")
	)
	(gr_line
		(start 21.307806 -135.1915)
		(end 21.307806 -136.15035)
		(stroke
			(width 0.2)
			(type default)
		)
		(layer "In1.Cu")
	)
	(gr_line
		(start 21.36267 -237.941612)
		(end 21.26107 -238.799624)
		(stroke
			(width 0.2)
			(type default)
		)
		(layer "In1.Cu")
	)
	(gr_line
		(start 21.411184 -32.240474)
		(end 21.487384 -33.209738)
		(stroke
			(width 0.2)
			(type default)
		)
		(layer "In1.Cu")
	)
	(gr_arc
		(start 21.48586 -342.045036)
		(mid 22.069933 -342.62949)
		(end 22.65426 -342.04529)
		(stroke
			(width 0.2)
			(type default)
		)
		(layer "In1.Cu")
	)
	(gr_line
		(start 21.48586 -341.08644)
		(end 21.48586 -342.045036)
		(stroke
			(width 0.2)
			(type default)
		)
		(layer "In1.Cu")
	)
	(gr_arc
		(start 21.487384 -33.209738)
		(mid 22.118192 -33.74897)
		(end 22.657308 -33.118044)
		(stroke
			(width 0.2)
			(type default)
		)
		(layer "In1.Cu")
	)
	(gr_arc
		(start 22.225508 -444.181992)
		(mid 21.613876 -443.62116)
		(end 21.053044 -444.232792)
		(stroke
			(width 0.2)
			(type default)
		)
		(layer "In1.Cu")
	)
	(gr_line
		(start 22.262846 -445.04483)
		(end 22.225508 -444.181992)
		(stroke
			(width 0.2)
			(type default)
		)
		(layer "In1.Cu")
	)
	(gr_line
		(start 22.426422 -238.938054)
		(end 22.528022 -238.079788)
		(stroke
			(width 0.2)
			(type default)
		)
		(layer "In1.Cu")
	)
	(gr_line
		(start 22.481286 -136.15035)
		(end 22.481286 -135.191754)
		(stroke
			(width 0.2)
			(type default)
		)
		(layer "In1.Cu")
	)
	(gr_arc
		(start 22.481286 -135.191754)
		(mid 21.894673 -134.60476)
		(end 21.307806 -135.1915)
		(stroke
			(width 0.2)
			(type default)
		)
		(layer "In1.Cu")
	)
	(gr_arc
		(start 22.528022 -238.079788)
		(mid 22.014434 -237.428024)
		(end 21.36267 -237.941612)
		(stroke
			(width 0.2)
			(type default)
		)
		(layer "In1.Cu")
	)
	(gr_arc
		(start 22.581108 -32.148526)
		(mid 21.950172 -31.609538)
		(end 21.411184 -32.240474)
		(stroke
			(width 0.2)
			(type default)
		)
		(layer "In1.Cu")
	)
	(gr_line
		(start 22.65426 -342.04529)
		(end 22.65426 -341.08644)
		(stroke
			(width 0.2)
			(type default)
		)
		(layer "In1.Cu")
	)
	(gr_arc
		(start 22.65426 -341.08644)
		(mid 22.07006 -340.50224)
		(end 21.48586 -341.08644)
		(stroke
			(width 0.2)
			(type default)
		)
		(layer "In1.Cu")
	)
	(gr_line
		(start 22.657308 -33.118044)
		(end 22.581108 -32.148526)
		(stroke
			(width 0.2)
			(type default)
		)
		(layer "In1.Cu")
	)
	(gr_line
		(start 22.943566 -453.256904)
		(end 20.555966 -453.256904)
		(stroke
			(width 0.2)
			(type default)
		)
		(layer "In1.Cu")
	)
	(gr_line
		(start 22.943566 -452.596504)
		(end 22.943566 -453.256904)
		(stroke
			(width 0.2)
			(type default)
		)
		(layer "In1.Cu")
	)
	(gr_line
		(start 22.943566 -451.986904)
		(end 20.555966 -451.986904)
		(stroke
			(width 0.2)
			(type default)
		)
		(layer "In1.Cu")
	)
	(gr_line
		(start 22.943566 -451.326504)
		(end 22.943566 -451.986904)
		(stroke
			(width 0.2)
			(type default)
		)
		(layer "In1.Cu")
	)
	(gr_line
		(start 22.943566 -449.446904)
		(end 20.555966 -449.446904)
		(stroke
			(width 0.2)
			(type default)
		)
		(layer "In1.Cu")
	)
	(gr_line
		(start 22.943566 -448.786504)
		(end 22.943566 -449.446904)
		(stroke
			(width 0.2)
			(type default)
		)
		(layer "In1.Cu")
	)
	(gr_line
		(start 22.943566 -448.176904)
		(end 20.555966 -448.176904)
		(stroke
			(width 0.2)
			(type default)
		)
		(layer "In1.Cu")
	)
	(gr_line
		(start 22.943566 -447.516504)
		(end 22.943566 -448.176904)
		(stroke
			(width 0.2)
			(type default)
		)
		(layer "In1.Cu")
	)
	(gr_line
		(start 22.943566 -350.256856)
		(end 20.555966 -350.256856)
		(stroke
			(width 0.2)
			(type default)
		)
		(layer "In1.Cu")
	)
	(gr_line
		(start 22.943566 -349.596456)
		(end 22.943566 -350.256856)
		(stroke
			(width 0.2)
			(type default)
		)
		(layer "In1.Cu")
	)
	(gr_line
		(start 22.943566 -348.986856)
		(end 20.555966 -348.986856)
		(stroke
			(width 0.2)
			(type default)
		)
		(layer "In1.Cu")
	)
	(gr_line
		(start 22.943566 -348.326456)
		(end 22.943566 -348.986856)
		(stroke
			(width 0.2)
			(type default)
		)
		(layer "In1.Cu")
	)
	(gr_line
		(start 22.943566 -346.446856)
		(end 20.555966 -346.446856)
		(stroke
			(width 0.2)
			(type default)
		)
		(layer "In1.Cu")
	)
	(gr_line
		(start 22.943566 -345.786456)
		(end 22.943566 -346.446856)
		(stroke
			(width 0.2)
			(type default)
		)
		(layer "In1.Cu")
	)
	(gr_line
		(start 22.943566 -345.176856)
		(end 20.555966 -345.176856)
		(stroke
			(width 0.2)
			(type default)
		)
		(layer "In1.Cu")
	)
	(gr_line
		(start 22.943566 -344.516456)
		(end 22.943566 -345.176856)
		(stroke
			(width 0.2)
			(type default)
		)
		(layer "In1.Cu")
	)
	(gr_line
		(start 22.943566 -247.256808)
		(end 20.555966 -247.256808)
		(stroke
			(width 0.2)
			(type default)
		)
		(layer "In1.Cu")
	)
	(gr_line
		(start 22.943566 -246.596408)
		(end 22.943566 -247.256808)
		(stroke
			(width 0.2)
			(type default)
		)
		(layer "In1.Cu")
	)
	(gr_line
		(start 22.943566 -245.986808)
		(end 20.555966 -245.986808)
		(stroke
			(width 0.2)
			(type default)
		)
		(layer "In1.Cu")
	)
	(gr_line
		(start 22.943566 -245.326408)
		(end 22.943566 -245.986808)
		(stroke
			(width 0.2)
			(type default)
		)
		(layer "In1.Cu")
	)
	(gr_line
		(start 22.943566 -243.446808)
		(end 20.555966 -243.446808)
		(stroke
			(width 0.2)
			(type default)
		)
		(layer "In1.Cu")
	)
	(gr_line
		(start 22.943566 -242.786408)
		(end 22.943566 -243.446808)
		(stroke
			(width 0.2)
			(type default)
		)
		(layer "In1.Cu")
	)
	(gr_line
		(start 22.943566 -242.176808)
		(end 20.555966 -242.176808)
		(stroke
			(width 0.2)
			(type default)
		)
		(layer "In1.Cu")
	)
	(gr_line
		(start 22.943566 -241.516408)
		(end 22.943566 -242.176808)
		(stroke
			(width 0.2)
			(type default)
		)
		(layer "In1.Cu")
	)
	(gr_line
		(start 22.943566 -144.25676)
		(end 20.555966 -144.25676)
		(stroke
			(width 0.2)
			(type default)
		)
		(layer "In1.Cu")
	)
	(gr_line
		(start 22.943566 -143.59636)
		(end 22.943566 -144.25676)
		(stroke
			(width 0.2)
			(type default)
		)
		(layer "In1.Cu")
	)
	(gr_line
		(start 22.943566 -142.98676)
		(end 20.555966 -142.98676)
		(stroke
			(width 0.2)
			(type default)
		)
		(layer "In1.Cu")
	)
	(gr_line
		(start 22.943566 -142.32636)
		(end 22.943566 -142.98676)
		(stroke
			(width 0.2)
			(type default)
		)
		(layer "In1.Cu")
	)
	(gr_line
		(start 22.943566 -140.44676)
		(end 20.555966 -140.44676)
		(stroke
			(width 0.2)
			(type default)
		)
		(layer "In1.Cu")
	)
	(gr_line
		(start 22.943566 -139.78636)
		(end 22.943566 -140.44676)
		(stroke
			(width 0.2)
			(type default)
		)
		(layer "In1.Cu")
	)
	(gr_line
		(start 22.943566 -139.17676)
		(end 20.555966 -139.17676)
		(stroke
			(width 0.2)
			(type default)
		)
		(layer "In1.Cu")
	)
	(gr_line
		(start 22.943566 -138.51636)
		(end 22.943566 -139.17676)
		(stroke
			(width 0.2)
			(type default)
		)
		(layer "In1.Cu")
	)
	(gr_line
		(start 22.943566 -41.256712)
		(end 20.555966 -41.256712)
		(stroke
			(width 0.2)
			(type default)
		)
		(layer "In1.Cu")
	)
	(gr_line
		(start 22.943566 -40.596312)
		(end 22.943566 -41.256712)
		(stroke
			(width 0.2)
			(type default)
		)
		(layer "In1.Cu")
	)
	(gr_line
		(start 22.943566 -39.986712)
		(end 20.555966 -39.986712)
		(stroke
			(width 0.2)
			(type default)
		)
		(layer "In1.Cu")
	)
	(gr_line
		(start 22.943566 -39.326312)
		(end 22.943566 -39.986712)
		(stroke
			(width 0.2)
			(type default)
		)
		(layer "In1.Cu")
	)
	(gr_line
		(start 22.943566 -37.446712)
		(end 20.555966 -37.446712)
		(stroke
			(width 0.2)
			(type default)
		)
		(layer "In1.Cu")
	)
	(gr_line
		(start 22.943566 -36.786312)
		(end 22.943566 -37.446712)
		(stroke
			(width 0.2)
			(type default)
		)
		(layer "In1.Cu")
	)
	(gr_line
		(start 22.943566 -36.176712)
		(end 20.555966 -36.176712)
		(stroke
			(width 0.2)
			(type default)
		)
		(layer "In1.Cu")
	)
	(gr_line
		(start 22.943566 -35.516312)
		(end 22.943566 -36.176712)
		(stroke
			(width 0.2)
			(type default)
		)
		(layer "In1.Cu")
	)
	(gr_arc
		(start 24.052022 -349.878904)
		(mid 24.606504 -350.496378)
		(end 25.223978 -349.941896)
		(stroke
			(width 0.2)
			(type default)
		)
		(layer "In1.Cu")
	)
	(gr_line
		(start 24.110188 -348.796102)
		(end 24.052022 -349.878904)
		(stroke
			(width 0.2)
			(type default)
		)
		(layer "In1.Cu")
	)
	(gr_line
		(start 24.257 -130.99034)
		(end 25.1206 -130.99034)
		(stroke
			(width 0.2)
			(type default)
		)
		(layer "In1.Cu")
	)
	(gr_arc
		(start 24.257 -129.81686)
		(mid 23.67026 -130.4036)
		(end 24.257 -130.99034)
		(stroke
			(width 0.2)
			(type default)
		)
		(layer "In1.Cu")
	)
	(gr_rect
		(start 24.844756 -236.16666)
		(end 26.752042 -237.0328)
		(stroke
			(width 0)
			(type default)
		)
		(fill no)
		(layer "In1.Cu")
	)
	(gr_rect
		(start 24.844756 -235.27766)
		(end 26.752042 -236.1438)
		(stroke
			(width 0)
			(type default)
		)
		(fill no)
		(layer "In1.Cu")
	)
	(gr_rect
		(start 25.043638 -339.154262)
		(end 26.950924 -340.020402)
		(stroke
			(width 0)
			(type default)
		)
		(fill no)
		(layer "In1.Cu")
	)
	(gr_rect
		(start 25.043638 -338.265262)
		(end 26.950924 -339.131402)
		(stroke
			(width 0)
			(type default)
		)
		(fill no)
		(layer "In1.Cu")
	)
	(gr_rect
		(start 25.073356 -139.519406)
		(end 26.980642 -140.385546)
		(stroke
			(width 0)
			(type default)
		)
		(fill no)
		(layer "In1.Cu")
	)
	(gr_rect
		(start 25.073356 -138.630406)
		(end 26.980642 -139.496546)
		(stroke
			(width 0)
			(type default)
		)
		(fill no)
		(layer "In1.Cu")
	)
	(gr_rect
		(start 25.087072 -36.411154)
		(end 26.994358 -37.277294)
		(stroke
			(width 0)
			(type default)
		)
		(fill no)
		(layer "In1.Cu")
	)
	(gr_rect
		(start 25.087072 -35.522154)
		(end 26.994358 -36.388294)
		(stroke
			(width 0)
			(type default)
		)
		(fill no)
		(layer "In1.Cu")
	)
	(gr_arc
		(start 25.1206 -130.99034)
		(mid 25.70734 -130.4036)
		(end 25.1206 -129.81686)
		(stroke
			(width 0.2)
			(type default)
		)
		(layer "In1.Cu")
	)
	(gr_line
		(start 25.1206 -129.81686)
		(end 24.257 -129.81686)
		(stroke
			(width 0.2)
			(type default)
		)
		(layer "In1.Cu")
	)
	(gr_rect
		(start 25.200356 -133.169406)
		(end 27.107642 -134.035546)
		(stroke
			(width 0)
			(type default)
		)
		(fill no)
		(layer "In1.Cu")
	)
	(gr_rect
		(start 25.200356 -132.280406)
		(end 27.107642 -133.146546)
		(stroke
			(width 0)
			(type default)
		)
		(fill no)
		(layer "In1.Cu")
	)
	(gr_line
		(start 25.223978 -349.941896)
		(end 25.282144 -348.859348)
		(stroke
			(width 0.2)
			(type default)
		)
		(layer "In1.Cu")
	)
	(gr_arc
		(start 25.282144 -348.859348)
		(mid 24.727789 -348.241881)
		(end 24.110188 -348.796102)
		(stroke
			(width 0.2)
			(type default)
		)
		(layer "In1.Cu")
	)
	(gr_rect
		(start 25.341072 -442.303154)
		(end 27.248358 -443.169294)
		(stroke
			(width 0)
			(type default)
		)
		(fill no)
		(layer "In1.Cu")
	)
	(gr_rect
		(start 25.341072 -441.414154)
		(end 27.248358 -442.280294)
		(stroke
			(width 0)
			(type default)
		)
		(fill no)
		(layer "In1.Cu")
	)
	(gr_arc
		(start 25.41016 -342.431116)
		(mid 25.9969 -343.017856)
		(end 26.58364 -342.431116)
		(stroke
			(width 0.2)
			(type default)
		)
		(layer "In1.Cu")
	)
	(gr_line
		(start 25.41016 -341.503)
		(end 25.41016 -342.431116)
		(stroke
			(width 0.2)
			(type default)
		)
		(layer "In1.Cu")
	)
	(gr_rect
		(start 25.606756 -242.51666)
		(end 27.514042 -243.3828)
		(stroke
			(width 0)
			(type default)
		)
		(fill no)
		(layer "In1.Cu")
	)
	(gr_rect
		(start 25.606756 -241.62766)
		(end 27.514042 -242.4938)
		(stroke
			(width 0)
			(type default)
		)
		(fill no)
		(layer "In1.Cu")
	)
	(gr_rect
		(start 25.849072 -448.526154)
		(end 27.756358 -449.392294)
		(stroke
			(width 0)
			(type default)
		)
		(fill no)
		(layer "In1.Cu")
	)
	(gr_rect
		(start 25.849072 -447.637154)
		(end 27.756358 -448.503294)
		(stroke
			(width 0)
			(type default)
		)
		(fill no)
		(layer "In1.Cu")
	)
	(gr_rect
		(start 25.932638 -345.504262)
		(end 27.839924 -346.370402)
		(stroke
			(width 0)
			(type default)
		)
		(fill no)
		(layer "In1.Cu")
	)
	(gr_rect
		(start 25.932638 -344.615262)
		(end 27.839924 -345.481402)
		(stroke
			(width 0)
			(type default)
		)
		(fill no)
		(layer "In1.Cu")
	)
	(gr_line
		(start 26.06675 -365.929672)
		(end 26.083006 -367.02365)
		(stroke
			(width 0.2)
			(type default)
		)
		(layer "In1.Cu")
	)
	(gr_arc
		(start 26.083006 -367.02365)
		(mid 26.678382 -367.601754)
		(end 27.256486 -367.006378)
		(stroke
			(width 0.2)
			(type default)
		)
		(layer "In1.Cu")
	)
	(gr_rect
		(start 26.230072 -32.474154)
		(end 28.137358 -33.340294)
		(stroke
			(width 0)
			(type default)
		)
		(fill no)
		(layer "In1.Cu")
	)
	(gr_rect
		(start 26.230072 -31.585154)
		(end 28.137358 -32.451294)
		(stroke
			(width 0)
			(type default)
		)
		(fill no)
		(layer "In1.Cu")
	)
	(gr_line
		(start 26.344626 -342.851994)
		(end 28.251912 -342.851994)
		(stroke
			(width 0.2)
			(type default)
		)
		(layer "In1.Cu")
	)
	(gr_line
		(start 26.344626 -341.096854)
		(end 26.344626 -342.851994)
		(stroke
			(width 0.2)
			(type default)
		)
		(layer "In1.Cu")
	)
	(gr_line
		(start 26.58364 -342.431116)
		(end 26.58364 -341.503254)
		(stroke
			(width 0.2)
			(type default)
		)
		(layer "In1.Cu")
	)
	(gr_arc
		(start 26.58364 -341.503254)
		(mid 25.997027 -340.91626)
		(end 25.41016 -341.503)
		(stroke
			(width 0.2)
			(type default)
		)
		(layer "In1.Cu")
	)
	(gr_arc
		(start 27.061414 -236.59719)
		(mid 27.602942 -237.226094)
		(end 28.231846 -236.684566)
		(stroke
			(width 0.2)
			(type default)
		)
		(layer "In1.Cu")
	)
	(gr_line
		(start 27.12593 -235.731812)
		(end 27.061414 -236.59719)
		(stroke
			(width 0.2)
			(type default)
		)
		(layer "In1.Cu")
	)
	(gr_arc
		(start 27.157172 -339.620606)
		(mid 27.743785 -340.2076)
		(end 28.330652 -339.62086)
		(stroke
			(width 0.2)
			(type default)
		)
		(layer "In1.Cu")
	)
	(gr_line
		(start 27.157172 -338.66201)
		(end 27.157172 -339.620606)
		(stroke
			(width 0.2)
			(type default)
		)
		(layer "In1.Cu")
	)
	(gr_line
		(start 27.19832 -441.860432)
		(end 27.22372 -442.876178)
		(stroke
			(width 0.2)
			(type default)
		)
		(layer "In1.Cu")
	)
	(gr_line
		(start 27.20086 -441.860432)
		(end 27.19832 -441.860432)
		(stroke
			(width 0.2)
			(type default)
		)
		(layer "In1.Cu")
	)
	(gr_line
		(start 27.22372 -442.876178)
		(end 27.223974 -442.876432)
		(stroke
			(width 0.2)
			(type default)
		)
		(layer "In1.Cu")
	)
	(gr_line
		(start 27.223974 -442.876432)
		(end 27.22626 -442.876432)
		(stroke
			(width 0.2)
			(type default)
		)
		(layer "In1.Cu")
	)
	(gr_arc
		(start 27.22626 -442.876432)
		(mid 27.827478 -443.448186)
		(end 28.399232 -442.846968)
		(stroke
			(width 0.2)
			(type default)
		)
		(layer "In1.Cu")
	)
	(gr_arc
		(start 27.24023 -365.912654)
		(mid 26.644981 -365.334548)
		(end 26.06675 -365.929672)
		(stroke
			(width 0.2)
			(type default)
		)
		(layer "In1.Cu")
	)
	(gr_line
		(start 27.256486 -367.006378)
		(end 27.24023 -365.912654)
		(stroke
			(width 0.2)
			(type default)
		)
		(layer "In1.Cu")
	)
	(gr_line
		(start 27.980894 -345.078304)
		(end 28.12288 -345.93022)
		(stroke
			(width 0.2)
			(type default)
		)
		(layer "In1.Cu")
	)
	(gr_arc
		(start 28.12288 -345.93022)
		(mid 28.798266 -346.412566)
		(end 29.280612 -345.73718)
		(stroke
			(width 0.2)
			(type default)
		)
		(layer "In1.Cu")
	)
	(gr_line
		(start 28.231846 -236.684566)
		(end 28.296362 -235.819442)
		(stroke
			(width 0.2)
			(type default)
		)
		(layer "In1.Cu")
	)
	(gr_arc
		(start 28.24226 -342.431116)
		(mid 28.829 -343.017856)
		(end 29.41574 -342.431116)
		(stroke
			(width 0.2)
			(type default)
		)
		(layer "In1.Cu")
	)
	(gr_line
		(start 28.24226 -341.503)
		(end 28.24226 -342.431116)
		(stroke
			(width 0.2)
			(type default)
		)
		(layer "In1.Cu")
	)
	(gr_line
		(start 28.251912 -342.851994)
		(end 28.251912 -341.096854)
		(stroke
			(width 0.2)
			(type default)
		)
		(layer "In1.Cu")
	)
	(gr_line
		(start 28.251912 -341.096854)
		(end 26.344626 -341.096854)
		(stroke
			(width 0.2)
			(type default)
		)
		(layer "In1.Cu")
	)
	(gr_arc
		(start 28.296362 -235.819442)
		(mid 27.75496 -235.190547)
		(end 27.12593 -235.731812)
		(stroke
			(width 0.2)
			(type default)
		)
		(layer "In1.Cu")
	)
	(gr_line
		(start 28.330652 -339.62086)
		(end 28.330652 -338.66201)
		(stroke
			(width 0.2)
			(type default)
		)
		(layer "In1.Cu")
	)
	(gr_arc
		(start 28.330652 -338.66201)
		(mid 27.743912 -338.07527)
		(end 27.157172 -338.66201)
		(stroke
			(width 0.2)
			(type default)
		)
		(layer "In1.Cu")
	)
	(gr_arc
		(start 28.373832 -441.830968)
		(mid 27.772614 -441.259214)
		(end 27.20086 -441.860432)
		(stroke
			(width 0.2)
			(type default)
		)
		(layer "In1.Cu")
	)
	(gr_line
		(start 28.376372 -441.830968)
		(end 28.373832 -441.830968)
		(stroke
			(width 0.2)
			(type default)
		)
		(layer "In1.Cu")
	)
	(gr_line
		(start 28.399232 -442.846968)
		(end 28.401772 -442.846968)
		(stroke
			(width 0.2)
			(type default)
		)
		(layer "In1.Cu")
	)
	(gr_line
		(start 28.401772 -442.846968)
		(end 28.376372 -441.830968)
		(stroke
			(width 0.2)
			(type default)
		)
		(layer "In1.Cu")
	)
	(gr_arc
		(start 28.896564 -33.0327)
		(mid 29.432504 -33.56864)
		(end 29.968444 -33.0327)
		(stroke
			(width 0.2)
			(type default)
		)
		(layer "In1.Cu")
	)
	(gr_line
		(start 28.896564 -31.997142)
		(end 28.896564 -33.0327)
		(stroke
			(width 0.2)
			(type default)
		)
		(layer "In1.Cu")
	)
	(gr_arc
		(start 29.138626 -344.885518)
		(mid 28.463364 -344.403151)
		(end 27.980894 -345.078304)
		(stroke
			(width 0.2)
			(type default)
		)
		(layer "In1.Cu")
	)
	(gr_arc
		(start 29.23032 -363.213904)
		(mid 29.81706 -363.800644)
		(end 30.4038 -363.213904)
		(stroke
			(width 0.2)
			(type default)
		)
		(layer "In1.Cu")
	)
	(gr_line
		(start 29.23032 -362.255054)
		(end 29.23032 -363.213904)
		(stroke
			(width 0.2)
			(type default)
		)
		(layer "In1.Cu")
	)
	(gr_line
		(start 29.280612 -345.73718)
		(end 29.138626 -344.885518)
		(stroke
			(width 0.2)
			(type default)
		)
		(layer "In1.Cu")
	)
	(gr_line
		(start 29.41574 -342.431116)
		(end 29.41574 -341.503254)
		(stroke
			(width 0.2)
			(type default)
		)
		(layer "In1.Cu")
	)
	(gr_arc
		(start 29.41574 -341.503254)
		(mid 28.829127 -340.91626)
		(end 28.24226 -341.503)
		(stroke
			(width 0.2)
			(type default)
		)
		(layer "In1.Cu")
	)
	(gr_line
		(start 29.968444 -33.0327)
		(end 29.968444 -31.997396)
		(stroke
			(width 0.2)
			(type default)
		)
		(layer "In1.Cu")
	)
	(gr_arc
		(start 29.968444 -31.997396)
		(mid 29.432631 -31.461202)
		(end 28.896564 -31.997142)
		(stroke
			(width 0.2)
			(type default)
		)
		(layer "In1.Cu")
	)
	(gr_line
		(start 30.4038 -363.213904)
		(end 30.4038 -362.255308)
		(stroke
			(width 0.2)
			(type default)
		)
		(layer "In1.Cu")
	)
	(gr_arc
		(start 30.4038 -362.255308)
		(mid 29.817187 -361.668314)
		(end 29.23032 -362.255054)
		(stroke
			(width 0.2)
			(type default)
		)
		(layer "In1.Cu")
	)
	(gr_line
		(start 30.503368 -64.11595)
		(end 30.503622 -64.116204)
		(stroke
			(width 0.2)
			(type default)
		)
		(layer "In1.Cu")
	)
	(gr_line
		(start 30.503622 -64.116204)
		(end 30.505908 -64.116458)
		(stroke
			(width 0.2)
			(type default)
		)
		(layer "In1.Cu")
	)
	(gr_arc
		(start 30.505908 -64.116458)
		(mid 31.022544 -64.765682)
		(end 31.671768 -64.249046)
		(stroke
			(width 0.2)
			(type default)
		)
		(layer "In1.Cu")
	)
	(gr_line
		(start 30.605476 -63.217552)
		(end 30.503368 -64.11595)
		(stroke
			(width 0.2)
			(type default)
		)
		(layer "In1.Cu")
	)
	(gr_line
		(start 30.608016 -63.217806)
		(end 30.605476 -63.217552)
		(stroke
			(width 0.2)
			(type default)
		)
		(layer "In1.Cu")
	)
	(gr_line
		(start 30.753558 -475.23273)
		(end 30.804104 -476.09506)
		(stroke
			(width 0.2)
			(type default)
		)
		(layer "In1.Cu")
	)
	(gr_line
		(start 30.756098 -475.232476)
		(end 30.753558 -475.23273)
		(stroke
			(width 0.2)
			(type default)
		)
		(layer "In1.Cu")
	)
	(gr_line
		(start 30.804104 -476.09506)
		(end 30.806644 -476.094806)
		(stroke
			(width 0.2)
			(type default)
		)
		(layer "In1.Cu")
	)
	(gr_arc
		(start 30.806644 -476.094806)
		(mid 31.426658 -476.64624)
		(end 31.978092 -476.026226)
		(stroke
			(width 0.2)
			(type default)
		)
		(layer "In1.Cu")
	)
	(gr_arc
		(start 30.909006 -267.728446)
		(mid 31.495619 -268.31544)
		(end 32.082486 -267.7287)
		(stroke
			(width 0.2)
			(type default)
		)
		(layer "In1.Cu")
	)
	(gr_line
		(start 30.909006 -266.8651)
		(end 30.909006 -267.728446)
		(stroke
			(width 0.2)
			(type default)
		)
		(layer "In1.Cu")
	)
	(gr_line
		(start 30.912308 -372.184168)
		(end 31.034736 -373.248428)
		(stroke
			(width 0.2)
			(type default)
		)
		(layer "In1.Cu")
	)
	(gr_line
		(start 30.914848 -372.183914)
		(end 30.912308 -372.184168)
		(stroke
			(width 0.2)
			(type default)
		)
		(layer "In1.Cu")
	)
	(gr_arc
		(start 31.016702 -274.618958)
		(mid 31.603442 -275.205698)
		(end 32.190182 -274.618958)
		(stroke
			(width 0.2)
			(type default)
		)
		(layer "In1.Cu")
	)
	(gr_line
		(start 31.016702 -273.690842)
		(end 31.016702 -274.618958)
		(stroke
			(width 0.2)
			(type default)
		)
		(layer "In1.Cu")
	)
	(gr_line
		(start 31.034736 -373.248428)
		(end 31.03499 -373.248682)
		(stroke
			(width 0.2)
			(type default)
		)
		(layer "In1.Cu")
	)
	(gr_line
		(start 31.03499 -373.248682)
		(end 31.037276 -373.248428)
		(stroke
			(width 0.2)
			(type default)
		)
		(layer "In1.Cu")
	)
	(gr_arc
		(start 31.037276 -373.248428)
		(mid 31.630874 -373.719598)
		(end 32.102044 -373.126)
		(stroke
			(width 0.2)
			(type default)
		)
		(layer "In1.Cu")
	)
	(gr_arc
		(start 31.290006 -162.2933)
		(mid 31.876746 -162.88004)
		(end 32.463486 -162.2933)
		(stroke
			(width 0.2)
			(type default)
		)
		(layer "In1.Cu")
	)
	(gr_line
		(start 31.290006 -161.4297)
		(end 31.290006 -162.2933)
		(stroke
			(width 0.2)
			(type default)
		)
		(layer "In1.Cu")
	)
	(gr_line
		(start 31.671768 -64.249046)
		(end 31.674308 -64.2493)
		(stroke
			(width 0.2)
			(type default)
		)
		(layer "In1.Cu")
	)
	(gr_line
		(start 31.674308 -64.2493)
		(end 31.776416 -63.350648)
		(stroke
			(width 0.2)
			(type default)
		)
		(layer "In1.Cu")
	)
	(gr_arc
		(start 31.773876 -63.350394)
		(mid 31.25724 -62.70117)
		(end 30.608016 -63.217806)
		(stroke
			(width 0.2)
			(type default)
		)
		(layer "In1.Cu")
	)
	(gr_line
		(start 31.776416 -63.350648)
		(end 31.773876 -63.350394)
		(stroke
			(width 0.2)
			(type default)
		)
		(layer "In1.Cu")
	)
	(gr_rect
		(start 31.917386 -372.755668)
		(end 33.824672 -373.621808)
		(stroke
			(width 0)
			(type default)
		)
		(fill no)
		(layer "In1.Cu")
	)
	(gr_rect
		(start 31.917386 -371.866668)
		(end 33.824672 -372.732808)
		(stroke
			(width 0)
			(type default)
		)
		(fill no)
		(layer "In1.Cu")
	)
	(gr_rect
		(start 31.917386 -366.532668)
		(end 33.824672 -367.398808)
		(stroke
			(width 0)
			(type default)
		)
		(fill no)
		(layer "In1.Cu")
	)
	(gr_rect
		(start 31.917386 -365.643668)
		(end 33.824672 -366.509808)
		(stroke
			(width 0)
			(type default)
		)
		(fill no)
		(layer "In1.Cu")
	)
	(gr_arc
		(start 31.927546 -475.163896)
		(mid 31.307532 -474.612462)
		(end 30.756098 -475.232476)
		(stroke
			(width 0.2)
			(type default)
		)
		(layer "In1.Cu")
	)
	(gr_line
		(start 31.929832 -475.163642)
		(end 31.927546 -475.163896)
		(stroke
			(width 0.2)
			(type default)
		)
		(layer "In1.Cu")
	)
	(gr_line
		(start 31.930086 -475.163896)
		(end 31.929832 -475.163642)
		(stroke
			(width 0.2)
			(type default)
		)
		(layer "In1.Cu")
	)
	(gr_line
		(start 31.978092 -476.026226)
		(end 31.980632 -476.025972)
		(stroke
			(width 0.2)
			(type default)
		)
		(layer "In1.Cu")
	)
	(gr_arc
		(start 31.979616 -372.061486)
		(mid 31.386018 -371.590316)
		(end 30.914848 -372.183914)
		(stroke
			(width 0.2)
			(type default)
		)
		(layer "In1.Cu")
	)
	(gr_line
		(start 31.980632 -476.025972)
		(end 31.930086 -475.163896)
		(stroke
			(width 0.2)
			(type default)
		)
		(layer "In1.Cu")
	)
	(gr_line
		(start 31.982156 -372.061232)
		(end 31.979616 -372.061486)
		(stroke
			(width 0.2)
			(type default)
		)
		(layer "In1.Cu")
	)
	(gr_rect
		(start 32.072072 -63.716154)
		(end 33.979358 -64.582294)
		(stroke
			(width 0)
			(type default)
		)
		(fill no)
		(layer "In1.Cu")
	)
	(gr_rect
		(start 32.072072 -62.827154)
		(end 33.979358 -63.693294)
		(stroke
			(width 0)
			(type default)
		)
		(fill no)
		(layer "In1.Cu")
	)
	(gr_rect
		(start 32.072072 -57.493154)
		(end 33.979358 -58.359294)
		(stroke
			(width 0)
			(type default)
		)
		(fill no)
		(layer "In1.Cu")
	)
	(gr_rect
		(start 32.072072 -56.604154)
		(end 33.979358 -57.470294)
		(stroke
			(width 0)
			(type default)
		)
		(fill no)
		(layer "In1.Cu")
	)
	(gr_line
		(start 32.082486 -267.7287)
		(end 32.082486 -266.8651)
		(stroke
			(width 0.2)
			(type default)
		)
		(layer "In1.Cu")
	)
	(gr_arc
		(start 32.082486 -266.8651)
		(mid 31.495746 -266.27836)
		(end 30.909006 -266.8651)
		(stroke
			(width 0.2)
			(type default)
		)
		(layer "In1.Cu")
	)
	(gr_rect
		(start 32.095694 -475.62897)
		(end 34.00298 -476.49511)
		(stroke
			(width 0)
			(type default)
		)
		(fill no)
		(layer "In1.Cu")
	)
	(gr_rect
		(start 32.095694 -474.73997)
		(end 34.00298 -475.60611)
		(stroke
			(width 0)
			(type default)
		)
		(fill no)
		(layer "In1.Cu")
	)
	(gr_rect
		(start 32.095694 -469.40597)
		(end 34.00298 -470.27211)
		(stroke
			(width 0)
			(type default)
		)
		(fill no)
		(layer "In1.Cu")
	)
	(gr_rect
		(start 32.095694 -468.51697)
		(end 34.00298 -469.38311)
		(stroke
			(width 0)
			(type default)
		)
		(fill no)
		(layer "In1.Cu")
	)
	(gr_line
		(start 32.102044 -373.126)
		(end 32.104584 -373.125746)
		(stroke
			(width 0.2)
			(type default)
		)
		(layer "In1.Cu")
	)
	(gr_line
		(start 32.104584 -373.125746)
		(end 31.982156 -372.061232)
		(stroke
			(width 0.2)
			(type default)
		)
		(layer "In1.Cu")
	)
	(gr_line
		(start 32.190182 -274.618958)
		(end 32.190182 -273.691096)
		(stroke
			(width 0.2)
			(type default)
		)
		(layer "In1.Cu")
	)
	(gr_arc
		(start 32.190182 -273.691096)
		(mid 31.603569 -273.104102)
		(end 31.016702 -273.690842)
		(stroke
			(width 0.2)
			(type default)
		)
		(layer "In1.Cu")
	)
	(gr_rect
		(start 32.313626 -274.167854)
		(end 34.220912 -275.033994)
		(stroke
			(width 0)
			(type default)
		)
		(fill no)
		(layer "In1.Cu")
	)
	(gr_rect
		(start 32.313626 -273.278854)
		(end 34.220912 -274.144994)
		(stroke
			(width 0)
			(type default)
		)
		(fill no)
		(layer "In1.Cu")
	)
	(gr_rect
		(start 32.326072 -269.710154)
		(end 34.233358 -270.576294)
		(stroke
			(width 0)
			(type default)
		)
		(fill no)
		(layer "In1.Cu")
	)
	(gr_rect
		(start 32.326072 -268.821154)
		(end 34.233358 -269.687294)
		(stroke
			(width 0)
			(type default)
		)
		(fill no)
		(layer "In1.Cu")
	)
	(gr_rect
		(start 32.326072 -263.487154)
		(end 34.233358 -264.353294)
		(stroke
			(width 0)
			(type default)
		)
		(fill no)
		(layer "In1.Cu")
	)
	(gr_rect
		(start 32.326072 -262.598154)
		(end 34.233358 -263.464294)
		(stroke
			(width 0)
			(type default)
		)
		(fill no)
		(layer "In1.Cu")
	)
	(gr_arc
		(start 32.361886 -163.402518)
		(mid 31.945616 -164.123487)
		(end 32.66948 -164.53485)
		(stroke
			(width 0.2)
			(type default)
		)
		(layer "In1.Cu")
	)
	(gr_line
		(start 32.463486 -162.2933)
		(end 32.463486 -161.429954)
		(stroke
			(width 0.2)
			(type default)
		)
		(layer "In1.Cu")
	)
	(gr_arc
		(start 32.463486 -161.429954)
		(mid 31.876873 -160.84296)
		(end 31.290006 -161.4297)
		(stroke
			(width 0.2)
			(type default)
		)
		(layer "In1.Cu")
	)
	(gr_line
		(start 32.66948 -164.53485)
		(end 33.533334 -164.29355)
		(stroke
			(width 0.2)
			(type default)
		)
		(layer "In1.Cu")
	)
	(gr_rect
		(start 32.945578 -166.716964)
		(end 34.852864 -167.583104)
		(stroke
			(width 0)
			(type default)
		)
		(fill no)
		(layer "In1.Cu")
	)
	(gr_rect
		(start 32.945578 -165.827964)
		(end 34.852864 -166.694104)
		(stroke
			(width 0)
			(type default)
		)
		(fill no)
		(layer "In1.Cu")
	)
	(gr_rect
		(start 32.945578 -160.493964)
		(end 34.852864 -161.360104)
		(stroke
			(width 0)
			(type default)
		)
		(fill no)
		(layer "In1.Cu")
	)
	(gr_rect
		(start 32.945578 -159.604964)
		(end 34.852864 -160.471104)
		(stroke
			(width 0)
			(type default)
		)
		(fill no)
		(layer "In1.Cu")
	)
	(gr_line
		(start 33.217866 -163.16325)
		(end 32.361886 -163.402518)
		(stroke
			(width 0.2)
			(type default)
		)
		(layer "In1.Cu")
	)
	(gr_arc
		(start 33.533334 -164.29355)
		(mid 33.94075 -163.570666)
		(end 33.217866 -163.16325)
		(stroke
			(width 0.2)
			(type default)
		)
		(layer "In1.Cu")
	)
	(gr_arc
		(start 34.332418 -274.618196)
		(mid 34.918396 -275.205698)
		(end 35.505898 -274.61972)
		(stroke
			(width 0.2)
			(type default)
		)
		(layer "In1.Cu")
	)
	(gr_line
		(start 34.333434 -273.698716)
		(end 34.332418 -274.618196)
		(stroke
			(width 0.2)
			(type default)
		)
		(layer "In1.Cu")
	)
	(gr_arc
		(start 34.465006 -473.748354)
		(mid 35.051746 -474.335094)
		(end 35.638486 -473.748354)
		(stroke
			(width 0.2)
			(type default)
		)
		(layer "In1.Cu")
	)
	(gr_line
		(start 34.465006 -472.820238)
		(end 34.465006 -473.748354)
		(stroke
			(width 0.2)
			(type default)
		)
		(layer "In1.Cu")
	)
	(gr_line
		(start 35.505898 -274.61972)
		(end 35.506914 -273.700494)
		(stroke
			(width 0.2)
			(type default)
		)
		(layer "In1.Cu")
	)
	(gr_arc
		(start 35.506914 -273.700494)
		(mid 34.921063 -273.112992)
		(end 34.333434 -273.698716)
		(stroke
			(width 0.2)
			(type default)
		)
		(layer "In1.Cu")
	)
	(gr_line
		(start 35.638486 -473.748354)
		(end 35.638486 -472.820492)
		(stroke
			(width 0.2)
			(type default)
		)
		(layer "In1.Cu")
	)
	(gr_arc
		(start 35.638486 -472.820492)
		(mid 35.051873 -472.233498)
		(end 34.465006 -472.820238)
		(stroke
			(width 0.2)
			(type default)
		)
		(layer "In1.Cu")
	)
	(gr_line
		(start 35.707574 -370.823998)
		(end 35.710114 -370.823998)
		(stroke
			(width 0.2)
			(type default)
		)
		(layer "In1.Cu")
	)
	(gr_arc
		(start 35.710114 -370.823998)
		(mid 36.280598 -371.426486)
		(end 36.883086 -370.856002)
		(stroke
			(width 0.2)
			(type default)
		)
		(layer "In1.Cu")
	)
	(gr_line
		(start 35.73272 -369.90274)
		(end 35.707574 -370.823998)
		(stroke
			(width 0.2)
			(type default)
		)
		(layer "In1.Cu")
	)
	(gr_line
		(start 35.73526 -369.90274)
		(end 35.73272 -369.90274)
		(stroke
			(width 0.2)
			(type default)
		)
		(layer "In1.Cu")
	)
	(gr_arc
		(start 36.049712 -164.879274)
		(mid 36.636452 -165.466014)
		(end 37.223192 -164.879274)
		(stroke
			(width 0.2)
			(type default)
		)
		(layer "In1.Cu")
	)
	(gr_line
		(start 36.049712 -163.920424)
		(end 36.049712 -164.879274)
		(stroke
			(width 0.2)
			(type default)
		)
		(layer "In1.Cu")
	)
	(gr_line
		(start 36.883086 -370.856002)
		(end 36.885626 -370.856002)
		(stroke
			(width 0.2)
			(type default)
		)
		(layer "In1.Cu")
	)
	(gr_line
		(start 36.885626 -370.856002)
		(end 36.910772 -369.934998)
		(stroke
			(width 0.2)
			(type default)
		)
		(layer "In1.Cu")
	)
	(gr_arc
		(start 36.908232 -369.934744)
		(mid 36.337748 -369.332256)
		(end 35.73526 -369.90274)
		(stroke
			(width 0.2)
			(type default)
		)
		(layer "In1.Cu")
	)
	(gr_line
		(start 36.910518 -369.934744)
		(end 36.908232 -369.934744)
		(stroke
			(width 0.2)
			(type default)
		)
		(layer "In1.Cu")
	)
	(gr_line
		(start 36.910772 -369.934998)
		(end 36.910518 -369.934744)
		(stroke
			(width 0.2)
			(type default)
		)
		(layer "In1.Cu")
	)
	(gr_line
		(start 37.05606 -470.477088)
		(end 37.05606 -469.816688)
		(stroke
			(width 0.2)
			(type default)
		)
		(layer "In1.Cu")
	)
	(gr_line
		(start 37.05606 -469.816688)
		(end 39.44366 -469.816688)
		(stroke
			(width 0.2)
			(type default)
		)
		(layer "In1.Cu")
	)
	(gr_line
		(start 37.05606 -469.207088)
		(end 37.05606 -468.546688)
		(stroke
			(width 0.2)
			(type default)
		)
		(layer "In1.Cu")
	)
	(gr_line
		(start 37.05606 -468.546688)
		(end 39.44366 -468.546688)
		(stroke
			(width 0.2)
			(type default)
		)
		(layer "In1.Cu")
	)
	(gr_line
		(start 37.05606 -466.667088)
		(end 37.05606 -466.006688)
		(stroke
			(width 0.2)
			(type default)
		)
		(layer "In1.Cu")
	)
	(gr_line
		(start 37.05606 -466.006688)
		(end 39.44366 -466.006688)
		(stroke
			(width 0.2)
			(type default)
		)
		(layer "In1.Cu")
	)
	(gr_line
		(start 37.05606 -465.397088)
		(end 37.05606 -464.736688)
		(stroke
			(width 0.2)
			(type default)
		)
		(layer "In1.Cu")
	)
	(gr_line
		(start 37.05606 -464.736688)
		(end 39.44366 -464.736688)
		(stroke
			(width 0.2)
			(type default)
		)
		(layer "In1.Cu")
	)
	(gr_line
		(start 37.05606 -367.47704)
		(end 37.05606 -366.81664)
		(stroke
			(width 0.2)
			(type default)
		)
		(layer "In1.Cu")
	)
	(gr_line
		(start 37.05606 -366.81664)
		(end 39.44366 -366.81664)
		(stroke
			(width 0.2)
			(type default)
		)
		(layer "In1.Cu")
	)
	(gr_line
		(start 37.05606 -366.20704)
		(end 37.05606 -365.54664)
		(stroke
			(width 0.2)
			(type default)
		)
		(layer "In1.Cu")
	)
	(gr_line
		(start 37.05606 -365.54664)
		(end 39.44366 -365.54664)
		(stroke
			(width 0.2)
			(type default)
		)
		(layer "In1.Cu")
	)
	(gr_line
		(start 37.05606 -363.66704)
		(end 37.05606 -363.00664)
		(stroke
			(width 0.2)
			(type default)
		)
		(layer "In1.Cu")
	)
	(gr_line
		(start 37.05606 -363.00664)
		(end 39.44366 -363.00664)
		(stroke
			(width 0.2)
			(type default)
		)
		(layer "In1.Cu")
	)
	(gr_line
		(start 37.05606 -362.39704)
		(end 37.05606 -361.73664)
		(stroke
			(width 0.2)
			(type default)
		)
		(layer "In1.Cu")
	)
	(gr_line
		(start 37.05606 -361.73664)
		(end 39.44366 -361.73664)
		(stroke
			(width 0.2)
			(type default)
		)
		(layer "In1.Cu")
	)
	(gr_line
		(start 37.05606 -264.476992)
		(end 37.05606 -263.816592)
		(stroke
			(width 0.2)
			(type default)
		)
		(layer "In1.Cu")
	)
	(gr_line
		(start 37.05606 -263.816592)
		(end 39.44366 -263.816592)
		(stroke
			(width 0.2)
			(type default)
		)
		(layer "In1.Cu")
	)
	(gr_line
		(start 37.05606 -263.206992)
		(end 37.05606 -262.546592)
		(stroke
			(width 0.2)
			(type default)
		)
		(layer "In1.Cu")
	)
	(gr_line
		(start 37.05606 -262.546592)
		(end 39.44366 -262.546592)
		(stroke
			(width 0.2)
			(type default)
		)
		(layer "In1.Cu")
	)
	(gr_line
		(start 37.05606 -260.666992)
		(end 37.05606 -260.006592)
		(stroke
			(width 0.2)
			(type default)
		)
		(layer "In1.Cu")
	)
	(gr_line
		(start 37.05606 -260.006592)
		(end 39.44366 -260.006592)
		(stroke
			(width 0.2)
			(type default)
		)
		(layer "In1.Cu")
	)
	(gr_line
		(start 37.05606 -259.396992)
		(end 37.05606 -258.736592)
		(stroke
			(width 0.2)
			(type default)
		)
		(layer "In1.Cu")
	)
	(gr_line
		(start 37.05606 -258.736592)
		(end 39.44366 -258.736592)
		(stroke
			(width 0.2)
			(type default)
		)
		(layer "In1.Cu")
	)
	(gr_line
		(start 37.05606 -161.476944)
		(end 37.05606 -160.816544)
		(stroke
			(width 0.2)
			(type default)
		)
		(layer "In1.Cu")
	)
	(gr_line
		(start 37.05606 -160.816544)
		(end 39.44366 -160.816544)
		(stroke
			(width 0.2)
			(type default)
		)
		(layer "In1.Cu")
	)
	(gr_line
		(start 37.05606 -160.206944)
		(end 37.05606 -159.546544)
		(stroke
			(width 0.2)
			(type default)
		)
		(layer "In1.Cu")
	)
	(gr_line
		(start 37.05606 -159.546544)
		(end 39.44366 -159.546544)
		(stroke
			(width 0.2)
			(type default)
		)
		(layer "In1.Cu")
	)
	(gr_line
		(start 37.05606 -157.666944)
		(end 37.05606 -157.006544)
		(stroke
			(width 0.2)
			(type default)
		)
		(layer "In1.Cu")
	)
	(gr_line
		(start 37.05606 -157.006544)
		(end 39.44366 -157.006544)
		(stroke
			(width 0.2)
			(type default)
		)
		(layer "In1.Cu")
	)
	(gr_line
		(start 37.05606 -156.396944)
		(end 37.05606 -155.736544)
		(stroke
			(width 0.2)
			(type default)
		)
		(layer "In1.Cu")
	)
	(gr_line
		(start 37.05606 -155.736544)
		(end 39.44366 -155.736544)
		(stroke
			(width 0.2)
			(type default)
		)
		(layer "In1.Cu")
	)
	(gr_line
		(start 37.05606 -58.476896)
		(end 37.05606 -57.816496)
		(stroke
			(width 0.2)
			(type default)
		)
		(layer "In1.Cu")
	)
	(gr_line
		(start 37.05606 -57.816496)
		(end 39.44366 -57.816496)
		(stroke
			(width 0.2)
			(type default)
		)
		(layer "In1.Cu")
	)
	(gr_line
		(start 37.05606 -57.206896)
		(end 37.05606 -56.546496)
		(stroke
			(width 0.2)
			(type default)
		)
		(layer "In1.Cu")
	)
	(gr_line
		(start 37.05606 -56.546496)
		(end 39.44366 -56.546496)
		(stroke
			(width 0.2)
			(type default)
		)
		(layer "In1.Cu")
	)
	(gr_line
		(start 37.05606 -54.666896)
		(end 37.05606 -54.006496)
		(stroke
			(width 0.2)
			(type default)
		)
		(layer "In1.Cu")
	)
	(gr_line
		(start 37.05606 -54.006496)
		(end 39.44366 -54.006496)
		(stroke
			(width 0.2)
			(type default)
		)
		(layer "In1.Cu")
	)
	(gr_line
		(start 37.05606 -53.396896)
		(end 37.05606 -52.736496)
		(stroke
			(width 0.2)
			(type default)
		)
		(layer "In1.Cu")
	)
	(gr_line
		(start 37.05606 -52.736496)
		(end 39.44366 -52.736496)
		(stroke
			(width 0.2)
			(type default)
		)
		(layer "In1.Cu")
	)
	(gr_line
		(start 37.223192 -164.879274)
		(end 37.223192 -163.920678)
		(stroke
			(width 0.2)
			(type default)
		)
		(layer "In1.Cu")
	)
	(gr_arc
		(start 37.223192 -163.920678)
		(mid 36.636579 -163.333684)
		(end 36.049712 -163.920424)
		(stroke
			(width 0.2)
			(type default)
		)
		(layer "In1.Cu")
	)
	(gr_arc
		(start 37.513006 -61.850016)
		(mid 38.099746 -62.436756)
		(end 38.686486 -61.850016)
		(stroke
			(width 0.2)
			(type default)
		)
		(layer "In1.Cu")
	)
	(gr_line
		(start 37.513006 -60.891166)
		(end 37.513006 -61.850016)
		(stroke
			(width 0.2)
			(type default)
		)
		(layer "In1.Cu")
	)
	(gr_line
		(start 38.686486 -61.850016)
		(end 38.686486 -60.89142)
		(stroke
			(width 0.2)
			(type default)
		)
		(layer "In1.Cu")
	)
	(gr_arc
		(start 38.686486 -60.89142)
		(mid 38.099873 -60.304426)
		(end 37.513006 -60.891166)
		(stroke
			(width 0.2)
			(type default)
		)
		(layer "In1.Cu")
	)
	(gr_line
		(start 39.44366 -470.477088)
		(end 37.05606 -470.477088)
		(stroke
			(width 0.2)
			(type default)
		)
		(layer "In1.Cu")
	)
	(gr_line
		(start 39.44366 -469.816688)
		(end 39.44366 -470.477088)
		(stroke
			(width 0.2)
			(type default)
		)
		(layer "In1.Cu")
	)
	(gr_line
		(start 39.44366 -469.207088)
		(end 37.05606 -469.207088)
		(stroke
			(width 0.2)
			(type default)
		)
		(layer "In1.Cu")
	)
	(gr_line
		(start 39.44366 -468.546688)
		(end 39.44366 -469.207088)
		(stroke
			(width 0.2)
			(type default)
		)
		(layer "In1.Cu")
	)
	(gr_line
		(start 39.44366 -466.667088)
		(end 37.05606 -466.667088)
		(stroke
			(width 0.2)
			(type default)
		)
		(layer "In1.Cu")
	)
	(gr_line
		(start 39.44366 -466.006688)
		(end 39.44366 -466.667088)
		(stroke
			(width 0.2)
			(type default)
		)
		(layer "In1.Cu")
	)
	(gr_line
		(start 39.44366 -465.397088)
		(end 37.05606 -465.397088)
		(stroke
			(width 0.2)
			(type default)
		)
		(layer "In1.Cu")
	)
	(gr_line
		(start 39.44366 -464.736688)
		(end 39.44366 -465.397088)
		(stroke
			(width 0.2)
			(type default)
		)
		(layer "In1.Cu")
	)
	(gr_line
		(start 39.44366 -367.47704)
		(end 37.05606 -367.47704)
		(stroke
			(width 0.2)
			(type default)
		)
		(layer "In1.Cu")
	)
	(gr_line
		(start 39.44366 -366.81664)
		(end 39.44366 -367.47704)
		(stroke
			(width 0.2)
			(type default)
		)
		(layer "In1.Cu")
	)
	(gr_line
		(start 39.44366 -366.20704)
		(end 37.05606 -366.20704)
		(stroke
			(width 0.2)
			(type default)
		)
		(layer "In1.Cu")
	)
	(gr_line
		(start 39.44366 -365.54664)
		(end 39.44366 -366.20704)
		(stroke
			(width 0.2)
			(type default)
		)
		(layer "In1.Cu")
	)
	(gr_line
		(start 39.44366 -363.66704)
		(end 37.05606 -363.66704)
		(stroke
			(width 0.2)
			(type default)
		)
		(layer "In1.Cu")
	)
	(gr_line
		(start 39.44366 -363.00664)
		(end 39.44366 -363.66704)
		(stroke
			(width 0.2)
			(type default)
		)
		(layer "In1.Cu")
	)
	(gr_line
		(start 39.44366 -362.39704)
		(end 37.05606 -362.39704)
		(stroke
			(width 0.2)
			(type default)
		)
		(layer "In1.Cu")
	)
	(gr_line
		(start 39.44366 -361.73664)
		(end 39.44366 -362.39704)
		(stroke
			(width 0.2)
			(type default)
		)
		(layer "In1.Cu")
	)
	(gr_line
		(start 39.44366 -264.476992)
		(end 37.05606 -264.476992)
		(stroke
			(width 0.2)
			(type default)
		)
		(layer "In1.Cu")
	)
	(gr_line
		(start 39.44366 -263.816592)
		(end 39.44366 -264.476992)
		(stroke
			(width 0.2)
			(type default)
		)
		(layer "In1.Cu")
	)
	(gr_line
		(start 39.44366 -263.206992)
		(end 37.05606 -263.206992)
		(stroke
			(width 0.2)
			(type default)
		)
		(layer "In1.Cu")
	)
	(gr_line
		(start 39.44366 -262.546592)
		(end 39.44366 -263.206992)
		(stroke
			(width 0.2)
			(type default)
		)
		(layer "In1.Cu")
	)
	(gr_line
		(start 39.44366 -260.666992)
		(end 37.05606 -260.666992)
		(stroke
			(width 0.2)
			(type default)
		)
		(layer "In1.Cu")
	)
	(gr_line
		(start 39.44366 -260.006592)
		(end 39.44366 -260.666992)
		(stroke
			(width 0.2)
			(type default)
		)
		(layer "In1.Cu")
	)
	(gr_line
		(start 39.44366 -259.396992)
		(end 37.05606 -259.396992)
		(stroke
			(width 0.2)
			(type default)
		)
		(layer "In1.Cu")
	)
	(gr_line
		(start 39.44366 -258.736592)
		(end 39.44366 -259.396992)
		(stroke
			(width 0.2)
			(type default)
		)
		(layer "In1.Cu")
	)
	(gr_line
		(start 39.44366 -161.476944)
		(end 37.05606 -161.476944)
		(stroke
			(width 0.2)
			(type default)
		)
		(layer "In1.Cu")
	)
	(gr_line
		(start 39.44366 -160.816544)
		(end 39.44366 -161.476944)
		(stroke
			(width 0.2)
			(type default)
		)
		(layer "In1.Cu")
	)
	(gr_line
		(start 39.44366 -160.206944)
		(end 37.05606 -160.206944)
		(stroke
			(width 0.2)
			(type default)
		)
		(layer "In1.Cu")
	)
	(gr_line
		(start 39.44366 -159.546544)
		(end 39.44366 -160.206944)
		(stroke
			(width 0.2)
			(type default)
		)
		(layer "In1.Cu")
	)
	(gr_line
		(start 39.44366 -157.666944)
		(end 37.05606 -157.666944)
		(stroke
			(width 0.2)
			(type default)
		)
		(layer "In1.Cu")
	)
	(gr_line
		(start 39.44366 -157.006544)
		(end 39.44366 -157.666944)
		(stroke
			(width 0.2)
			(type default)
		)
		(layer "In1.Cu")
	)
	(gr_line
		(start 39.44366 -156.396944)
		(end 37.05606 -156.396944)
		(stroke
			(width 0.2)
			(type default)
		)
		(layer "In1.Cu")
	)
	(gr_line
		(start 39.44366 -155.736544)
		(end 39.44366 -156.396944)
		(stroke
			(width 0.2)
			(type default)
		)
		(layer "In1.Cu")
	)
	(gr_line
		(start 39.44366 -58.476896)
		(end 37.05606 -58.476896)
		(stroke
			(width 0.2)
			(type default)
		)
		(layer "In1.Cu")
	)
	(gr_line
		(start 39.44366 -57.816496)
		(end 39.44366 -58.476896)
		(stroke
			(width 0.2)
			(type default)
		)
		(layer "In1.Cu")
	)
	(gr_line
		(start 39.44366 -57.206896)
		(end 37.05606 -57.206896)
		(stroke
			(width 0.2)
			(type default)
		)
		(layer "In1.Cu")
	)
	(gr_line
		(start 39.44366 -56.546496)
		(end 39.44366 -57.206896)
		(stroke
			(width 0.2)
			(type default)
		)
		(layer "In1.Cu")
	)
	(gr_line
		(start 39.44366 -54.666896)
		(end 37.05606 -54.666896)
		(stroke
			(width 0.2)
			(type default)
		)
		(layer "In1.Cu")
	)
	(gr_line
		(start 39.44366 -54.006496)
		(end 39.44366 -54.666896)
		(stroke
			(width 0.2)
			(type default)
		)
		(layer "In1.Cu")
	)
	(gr_line
		(start 39.44366 -53.396896)
		(end 37.05606 -53.396896)
		(stroke
			(width 0.2)
			(type default)
		)
		(layer "In1.Cu")
	)
	(gr_line
		(start 39.44366 -52.736496)
		(end 39.44366 -53.396896)
		(stroke
			(width 0.2)
			(type default)
		)
		(layer "In1.Cu")
	)
	(gr_line
		(start 39.447216 -476.440754)
		(end 39.447216 -475.932754)
		(stroke
			(width 0.2)
			(type default)
		)
		(layer "In1.Cu")
	)
	(gr_line
		(start 39.447216 -475.932754)
		(end 41.352216 -475.932754)
		(stroke
			(width 0.2)
			(type default)
		)
		(layer "In1.Cu")
	)
	(gr_line
		(start 39.447216 -475.640908)
		(end 39.447216 -475.132908)
		(stroke
			(width 0.2)
			(type default)
		)
		(layer "In1.Cu")
	)
	(gr_line
		(start 39.447216 -475.132908)
		(end 41.352216 -475.132908)
		(stroke
			(width 0.2)
			(type default)
		)
		(layer "In1.Cu")
	)
	(gr_line
		(start 39.447216 -474.040708)
		(end 39.447216 -473.532708)
		(stroke
			(width 0.2)
			(type default)
		)
		(layer "In1.Cu")
	)
	(gr_line
		(start 39.447216 -473.532708)
		(end 41.352216 -473.532708)
		(stroke
			(width 0.2)
			(type default)
		)
		(layer "In1.Cu")
	)
	(gr_line
		(start 39.447216 -473.240862)
		(end 39.447216 -472.732862)
		(stroke
			(width 0.2)
			(type default)
		)
		(layer "In1.Cu")
	)
	(gr_line
		(start 39.447216 -472.732862)
		(end 41.352216 -472.732862)
		(stroke
			(width 0.2)
			(type default)
		)
		(layer "In1.Cu")
	)
	(gr_line
		(start 39.447216 -373.440706)
		(end 39.447216 -372.932706)
		(stroke
			(width 0.2)
			(type default)
		)
		(layer "In1.Cu")
	)
	(gr_line
		(start 39.447216 -372.932706)
		(end 41.352216 -372.932706)
		(stroke
			(width 0.2)
			(type default)
		)
		(layer "In1.Cu")
	)
	(gr_line
		(start 39.447216 -372.64086)
		(end 39.447216 -372.13286)
		(stroke
			(width 0.2)
			(type default)
		)
		(layer "In1.Cu")
	)
	(gr_line
		(start 39.447216 -372.13286)
		(end 41.352216 -372.13286)
		(stroke
			(width 0.2)
			(type default)
		)
		(layer "In1.Cu")
	)
	(gr_line
		(start 39.447216 -371.04066)
		(end 39.447216 -370.53266)
		(stroke
			(width 0.2)
			(type default)
		)
		(layer "In1.Cu")
	)
	(gr_line
		(start 39.447216 -370.53266)
		(end 41.352216 -370.53266)
		(stroke
			(width 0.2)
			(type default)
		)
		(layer "In1.Cu")
	)
	(gr_line
		(start 39.447216 -370.240814)
		(end 39.447216 -369.732814)
		(stroke
			(width 0.2)
			(type default)
		)
		(layer "In1.Cu")
	)
	(gr_line
		(start 39.447216 -369.732814)
		(end 41.352216 -369.732814)
		(stroke
			(width 0.2)
			(type default)
		)
		(layer "In1.Cu")
	)
	(gr_line
		(start 39.447216 -270.440658)
		(end 39.447216 -269.932658)
		(stroke
			(width 0.2)
			(type default)
		)
		(layer "In1.Cu")
	)
	(gr_line
		(start 39.447216 -269.932658)
		(end 41.352216 -269.932658)
		(stroke
			(width 0.2)
			(type default)
		)
		(layer "In1.Cu")
	)
	(gr_line
		(start 39.447216 -269.640812)
		(end 39.447216 -269.132812)
		(stroke
			(width 0.2)
			(type default)
		)
		(layer "In1.Cu")
	)
	(gr_line
		(start 39.447216 -269.132812)
		(end 41.352216 -269.132812)
		(stroke
			(width 0.2)
			(type default)
		)
		(layer "In1.Cu")
	)
	(gr_line
		(start 39.447216 -268.040612)
		(end 39.447216 -267.532612)
		(stroke
			(width 0.2)
			(type default)
		)
		(layer "In1.Cu")
	)
	(gr_line
		(start 39.447216 -267.532612)
		(end 41.352216 -267.532612)
		(stroke
			(width 0.2)
			(type default)
		)
		(layer "In1.Cu")
	)
	(gr_line
		(start 39.447216 -267.240766)
		(end 39.447216 -266.732766)
		(stroke
			(width 0.2)
			(type default)
		)
		(layer "In1.Cu")
	)
	(gr_line
		(start 39.447216 -266.732766)
		(end 41.352216 -266.732766)
		(stroke
			(width 0.2)
			(type default)
		)
		(layer "In1.Cu")
	)
	(gr_line
		(start 39.447216 -167.44061)
		(end 39.447216 -166.93261)
		(stroke
			(width 0.2)
			(type default)
		)
		(layer "In1.Cu")
	)
	(gr_line
		(start 39.447216 -166.93261)
		(end 41.352216 -166.93261)
		(stroke
			(width 0.2)
			(type default)
		)
		(layer "In1.Cu")
	)
	(gr_line
		(start 39.447216 -166.640764)
		(end 39.447216 -166.132764)
		(stroke
			(width 0.2)
			(type default)
		)
		(layer "In1.Cu")
	)
	(gr_line
		(start 39.447216 -166.132764)
		(end 41.352216 -166.132764)
		(stroke
			(width 0.2)
			(type default)
		)
		(layer "In1.Cu")
	)
	(gr_line
		(start 39.447216 -165.040564)
		(end 39.447216 -164.532564)
		(stroke
			(width 0.2)
			(type default)
		)
		(layer "In1.Cu")
	)
	(gr_line
		(start 39.447216 -164.532564)
		(end 41.352216 -164.532564)
		(stroke
			(width 0.2)
			(type default)
		)
		(layer "In1.Cu")
	)
	(gr_line
		(start 39.447216 -164.240718)
		(end 39.447216 -163.732718)
		(stroke
			(width 0.2)
			(type default)
		)
		(layer "In1.Cu")
	)
	(gr_line
		(start 39.447216 -163.732718)
		(end 41.352216 -163.732718)
		(stroke
			(width 0.2)
			(type default)
		)
		(layer "In1.Cu")
	)
	(gr_line
		(start 39.447216 -64.440562)
		(end 39.447216 -63.932562)
		(stroke
			(width 0.2)
			(type default)
		)
		(layer "In1.Cu")
	)
	(gr_line
		(start 39.447216 -63.932562)
		(end 41.352216 -63.932562)
		(stroke
			(width 0.2)
			(type default)
		)
		(layer "In1.Cu")
	)
	(gr_line
		(start 39.447216 -63.640716)
		(end 39.447216 -63.132716)
		(stroke
			(width 0.2)
			(type default)
		)
		(layer "In1.Cu")
	)
	(gr_line
		(start 39.447216 -63.132716)
		(end 41.352216 -63.132716)
		(stroke
			(width 0.2)
			(type default)
		)
		(layer "In1.Cu")
	)
	(gr_line
		(start 39.447216 -62.040516)
		(end 39.447216 -61.532516)
		(stroke
			(width 0.2)
			(type default)
		)
		(layer "In1.Cu")
	)
	(gr_line
		(start 39.447216 -61.532516)
		(end 41.352216 -61.532516)
		(stroke
			(width 0.2)
			(type default)
		)
		(layer "In1.Cu")
	)
	(gr_line
		(start 39.447216 -61.24067)
		(end 39.447216 -60.73267)
		(stroke
			(width 0.2)
			(type default)
		)
		(layer "In1.Cu")
	)
	(gr_line
		(start 39.447216 -60.73267)
		(end 41.352216 -60.73267)
		(stroke
			(width 0.2)
			(type default)
		)
		(layer "In1.Cu")
	)
	(gr_line
		(start 41.352216 -476.440754)
		(end 39.447216 -476.440754)
		(stroke
			(width 0.2)
			(type default)
		)
		(layer "In1.Cu")
	)
	(gr_line
		(start 41.352216 -475.932754)
		(end 41.352216 -476.440754)
		(stroke
			(width 0.2)
			(type default)
		)
		(layer "In1.Cu")
	)
	(gr_line
		(start 41.352216 -475.640908)
		(end 39.447216 -475.640908)
		(stroke
			(width 0.2)
			(type default)
		)
		(layer "In1.Cu")
	)
	(gr_line
		(start 41.352216 -475.132908)
		(end 41.352216 -475.640908)
		(stroke
			(width 0.2)
			(type default)
		)
		(layer "In1.Cu")
	)
	(gr_line
		(start 41.352216 -474.040708)
		(end 39.447216 -474.040708)
		(stroke
			(width 0.2)
			(type default)
		)
		(layer "In1.Cu")
	)
	(gr_line
		(start 41.352216 -473.532708)
		(end 41.352216 -474.040708)
		(stroke
			(width 0.2)
			(type default)
		)
		(layer "In1.Cu")
	)
	(gr_line
		(start 41.352216 -473.240862)
		(end 39.447216 -473.240862)
		(stroke
			(width 0.2)
			(type default)
		)
		(layer "In1.Cu")
	)
	(gr_line
		(start 41.352216 -472.732862)
		(end 41.352216 -473.240862)
		(stroke
			(width 0.2)
			(type default)
		)
		(layer "In1.Cu")
	)
	(gr_line
		(start 41.352216 -373.440706)
		(end 39.447216 -373.440706)
		(stroke
			(width 0.2)
			(type default)
		)
		(layer "In1.Cu")
	)
	(gr_line
		(start 41.352216 -372.932706)
		(end 41.352216 -373.440706)
		(stroke
			(width 0.2)
			(type default)
		)
		(layer "In1.Cu")
	)
	(gr_line
		(start 41.352216 -372.64086)
		(end 39.447216 -372.64086)
		(stroke
			(width 0.2)
			(type default)
		)
		(layer "In1.Cu")
	)
	(gr_line
		(start 41.352216 -372.13286)
		(end 41.352216 -372.64086)
		(stroke
			(width 0.2)
			(type default)
		)
		(layer "In1.Cu")
	)
	(gr_line
		(start 41.352216 -371.04066)
		(end 39.447216 -371.04066)
		(stroke
			(width 0.2)
			(type default)
		)
		(layer "In1.Cu")
	)
	(gr_line
		(start 41.352216 -370.53266)
		(end 41.352216 -371.04066)
		(stroke
			(width 0.2)
			(type default)
		)
		(layer "In1.Cu")
	)
	(gr_line
		(start 41.352216 -370.240814)
		(end 39.447216 -370.240814)
		(stroke
			(width 0.2)
			(type default)
		)
		(layer "In1.Cu")
	)
	(gr_line
		(start 41.352216 -369.732814)
		(end 41.352216 -370.240814)
		(stroke
			(width 0.2)
			(type default)
		)
		(layer "In1.Cu")
	)
	(gr_line
		(start 41.352216 -270.440658)
		(end 39.447216 -270.440658)
		(stroke
			(width 0.2)
			(type default)
		)
		(layer "In1.Cu")
	)
	(gr_line
		(start 41.352216 -269.932658)
		(end 41.352216 -270.440658)
		(stroke
			(width 0.2)
			(type default)
		)
		(layer "In1.Cu")
	)
	(gr_line
		(start 41.352216 -269.640812)
		(end 39.447216 -269.640812)
		(stroke
			(width 0.2)
			(type default)
		)
		(layer "In1.Cu")
	)
	(gr_line
		(start 41.352216 -269.132812)
		(end 41.352216 -269.640812)
		(stroke
			(width 0.2)
			(type default)
		)
		(layer "In1.Cu")
	)
	(gr_line
		(start 41.352216 -268.040612)
		(end 39.447216 -268.040612)
		(stroke
			(width 0.2)
			(type default)
		)
		(layer "In1.Cu")
	)
	(gr_line
		(start 41.352216 -267.532612)
		(end 41.352216 -268.040612)
		(stroke
			(width 0.2)
			(type default)
		)
		(layer "In1.Cu")
	)
	(gr_line
		(start 41.352216 -267.240766)
		(end 39.447216 -267.240766)
		(stroke
			(width 0.2)
			(type default)
		)
		(layer "In1.Cu")
	)
	(gr_line
		(start 41.352216 -266.732766)
		(end 41.352216 -267.240766)
		(stroke
			(width 0.2)
			(type default)
		)
		(layer "In1.Cu")
	)
	(gr_line
		(start 41.352216 -167.44061)
		(end 39.447216 -167.44061)
		(stroke
			(width 0.2)
			(type default)
		)
		(layer "In1.Cu")
	)
	(gr_line
		(start 41.352216 -166.93261)
		(end 41.352216 -167.44061)
		(stroke
			(width 0.2)
			(type default)
		)
		(layer "In1.Cu")
	)
	(gr_line
		(start 41.352216 -166.640764)
		(end 39.447216 -166.640764)
		(stroke
			(width 0.2)
			(type default)
		)
		(layer "In1.Cu")
	)
	(gr_line
		(start 41.352216 -166.132764)
		(end 41.352216 -166.640764)
		(stroke
			(width 0.2)
			(type default)
		)
		(layer "In1.Cu")
	)
	(gr_line
		(start 41.352216 -165.040564)
		(end 39.447216 -165.040564)
		(stroke
			(width 0.2)
			(type default)
		)
		(layer "In1.Cu")
	)
	(gr_line
		(start 41.352216 -164.532564)
		(end 41.352216 -165.040564)
		(stroke
			(width 0.2)
			(type default)
		)
		(layer "In1.Cu")
	)
	(gr_line
		(start 41.352216 -164.240718)
		(end 39.447216 -164.240718)
		(stroke
			(width 0.2)
			(type default)
		)
		(layer "In1.Cu")
	)
	(gr_line
		(start 41.352216 -163.732718)
		(end 41.352216 -164.240718)
		(stroke
			(width 0.2)
			(type default)
		)
		(layer "In1.Cu")
	)
	(gr_line
		(start 41.352216 -64.440562)
		(end 39.447216 -64.440562)
		(stroke
			(width 0.2)
			(type default)
		)
		(layer "In1.Cu")
	)
	(gr_line
		(start 41.352216 -63.932562)
		(end 41.352216 -64.440562)
		(stroke
			(width 0.2)
			(type default)
		)
		(layer "In1.Cu")
	)
	(gr_line
		(start 41.352216 -63.640716)
		(end 39.447216 -63.640716)
		(stroke
			(width 0.2)
			(type default)
		)
		(layer "In1.Cu")
	)
	(gr_line
		(start 41.352216 -63.132716)
		(end 41.352216 -63.640716)
		(stroke
			(width 0.2)
			(type default)
		)
		(layer "In1.Cu")
	)
	(gr_line
		(start 41.352216 -62.040516)
		(end 39.447216 -62.040516)
		(stroke
			(width 0.2)
			(type default)
		)
		(layer "In1.Cu")
	)
	(gr_line
		(start 41.352216 -61.532516)
		(end 41.352216 -62.040516)
		(stroke
			(width 0.2)
			(type default)
		)
		(layer "In1.Cu")
	)
	(gr_line
		(start 41.352216 -61.24067)
		(end 39.447216 -61.24067)
		(stroke
			(width 0.2)
			(type default)
		)
		(layer "In1.Cu")
	)
	(gr_line
		(start 41.352216 -60.73267)
		(end 41.352216 -61.24067)
		(stroke
			(width 0.2)
			(type default)
		)
		(layer "In1.Cu")
	)
	(gr_arc
		(start 215.1888 -269.032228)
		(mid 214.610442 -269.62735)
		(end 215.205564 -270.205708)
		(stroke
			(width 0.2)
			(type default)
		)
		(layer "In1.Cu")
	)
	(gr_line
		(start 215.205564 -270.205708)
		(end 216.11971 -270.192754)
		(stroke
			(width 0.2)
			(type default)
		)
		(layer "In1.Cu")
	)
	(gr_line
		(start 215.32342 -167.05072)
		(end 216.186766 -167.066468)
		(stroke
			(width 0.2)
			(type default)
		)
		(layer "In1.Cu")
	)
	(gr_arc
		(start 215.344756 -165.87724)
		(mid 214.747348 -166.453312)
		(end 215.32342 -167.05072)
		(stroke
			(width 0.2)
			(type default)
		)
		(layer "In1.Cu")
	)
	(gr_arc
		(start 215.349836 -62.92342)
		(mid 214.774524 -63.521463)
		(end 215.372442 -64.0969)
		(stroke
			(width 0.2)
			(type default)
		)
		(layer "In1.Cu")
	)
	(gr_line
		(start 215.372442 -64.0969)
		(end 216.236042 -64.080136)
		(stroke
			(width 0.2)
			(type default)
		)
		(layer "In1.Cu")
	)
	(gr_arc
		(start 215.608154 -371.879368)
		(mid 215.031064 -372.475633)
		(end 215.627204 -373.052848)
		(stroke
			(width 0.2)
			(type default)
		)
		(layer "In1.Cu")
	)
	(gr_line
		(start 215.627204 -373.052848)
		(end 216.490804 -373.038624)
		(stroke
			(width 0.2)
			(type default)
		)
		(layer "In1.Cu")
	)
	(gr_arc
		(start 215.92159 -474.661484)
		(mid 215.338406 -475.25178)
		(end 215.928702 -475.834964)
		(stroke
			(width 0.2)
			(type default)
		)
		(layer "In1.Cu")
	)
	(gr_line
		(start 215.928702 -475.834964)
		(end 216.792048 -475.829884)
		(stroke
			(width 0.2)
			(type default)
		)
		(layer "In1.Cu")
	)
	(gr_line
		(start 216.027 -64.5922)
		(end 216.027 -63.9318)
		(stroke
			(width 0.2)
			(type default)
		)
		(layer "In1.Cu")
	)
	(gr_line
		(start 216.027 -63.9318)
		(end 216.14765 -63.81115)
		(stroke
			(width 0.2)
			(type default)
		)
		(layer "In1.Cu")
	)
	(gr_line
		(start 216.1032 -269.019274)
		(end 215.1888 -269.032228)
		(stroke
			(width 0.2)
			(type default)
		)
		(layer "In1.Cu")
	)
	(gr_line
		(start 216.1032 -64.6684)
		(end 216.027 -64.5922)
		(stroke
			(width 0.2)
			(type default)
		)
		(layer "In1.Cu")
	)
	(gr_line
		(start 216.11209 -64.67729)
		(end 216.1032 -64.6684)
		(stroke
			(width 0.2)
			(type default)
		)
		(layer "In1.Cu")
	)
	(gr_arc
		(start 216.11971 -270.192754)
		(mid 216.69832 -269.597759)
		(end 216.1032 -269.019274)
		(stroke
			(width 0.2)
			(type default)
		)
		(layer "In1.Cu")
	)
	(gr_line
		(start 216.14765 -63.81115)
		(end 216.851738 -63.81115)
		(stroke
			(width 0.2)
			(type default)
		)
		(layer "In1.Cu")
	)
	(gr_arc
		(start 216.186766 -167.066468)
		(mid 216.78443 -166.490523)
		(end 216.208356 -165.892988)
		(stroke
			(width 0.2)
			(type default)
		)
		(layer "In1.Cu")
	)
	(gr_line
		(start 216.208356 -165.892988)
		(end 215.344756 -165.87724)
		(stroke
			(width 0.2)
			(type default)
		)
		(layer "In1.Cu")
	)
	(gr_line
		(start 216.213182 -62.906656)
		(end 215.349836 -62.92342)
		(stroke
			(width 0.2)
			(type default)
		)
		(layer "In1.Cu")
	)
	(gr_arc
		(start 216.236042 -64.080136)
		(mid 216.811352 -63.481966)
		(end 216.213182 -62.906656)
		(stroke
			(width 0.2)
			(type default)
		)
		(layer "In1.Cu")
	)
	(gr_line
		(start 216.4715 -371.865144)
		(end 215.608154 -371.879368)
		(stroke
			(width 0.2)
			(type default)
		)
		(layer "In1.Cu")
	)
	(gr_arc
		(start 216.490804 -373.038624)
		(mid 217.067892 -372.442232)
		(end 216.4715 -371.865144)
		(stroke
			(width 0.2)
			(type default)
		)
		(layer "In1.Cu")
	)
	(gr_line
		(start 216.78519 -474.656404)
		(end 215.92159 -474.661484)
		(stroke
			(width 0.2)
			(type default)
		)
		(layer "In1.Cu")
	)
	(gr_arc
		(start 216.792048 -475.829884)
		(mid 217.375485 -475.239715)
		(end 216.78519 -474.656404)
		(stroke
			(width 0.2)
			(type default)
		)
		(layer "In1.Cu")
	)
	(gr_rect
		(start 216.80551 -269.921482)
		(end 218.712796 -270.787622)
		(stroke
			(width 0)
			(type default)
		)
		(fill no)
		(layer "In1.Cu")
	)
	(gr_rect
		(start 216.80551 -269.032482)
		(end 218.712796 -269.898622)
		(stroke
			(width 0)
			(type default)
		)
		(fill no)
		(layer "In1.Cu")
	)
	(gr_rect
		(start 216.80551 -263.571482)
		(end 218.712796 -264.437622)
		(stroke
			(width 0)
			(type default)
		)
		(fill no)
		(layer "In1.Cu")
	)
	(gr_rect
		(start 216.80551 -262.682482)
		(end 218.712796 -263.548622)
		(stroke
			(width 0)
			(type default)
		)
		(fill no)
		(layer "In1.Cu")
	)
	(gr_line
		(start 216.851738 -64.67729)
		(end 216.11209 -64.67729)
		(stroke
			(width 0.2)
			(type default)
		)
		(layer "In1.Cu")
	)
	(gr_line
		(start 216.851738 -63.81115)
		(end 218.759024 -63.81115)
		(stroke
			(width 0.2)
			(type default)
		)
		(layer "In1.Cu")
	)
	(gr_rect
		(start 216.851738 -62.92215)
		(end 218.759024 -63.78829)
		(stroke
			(width 0)
			(type default)
		)
		(fill no)
		(layer "In1.Cu")
	)
	(gr_rect
		(start 216.851738 -57.58815)
		(end 218.759024 -58.45429)
		(stroke
			(width 0)
			(type default)
		)
		(fill no)
		(layer "In1.Cu")
	)
	(gr_rect
		(start 216.851738 -56.69915)
		(end 218.759024 -57.56529)
		(stroke
			(width 0)
			(type default)
		)
		(fill no)
		(layer "In1.Cu")
	)
	(gr_rect
		(start 216.90711 -166.797482)
		(end 218.814396 -167.663622)
		(stroke
			(width 0)
			(type default)
		)
		(fill no)
		(layer "In1.Cu")
	)
	(gr_rect
		(start 216.90711 -165.908482)
		(end 218.814396 -166.774622)
		(stroke
			(width 0)
			(type default)
		)
		(fill no)
		(layer "In1.Cu")
	)
	(gr_rect
		(start 216.90711 -160.574482)
		(end 218.814396 -161.440622)
		(stroke
			(width 0)
			(type default)
		)
		(fill no)
		(layer "In1.Cu")
	)
	(gr_rect
		(start 216.90711 -159.685482)
		(end 218.814396 -160.551622)
		(stroke
			(width 0)
			(type default)
		)
		(fill no)
		(layer "In1.Cu")
	)
	(gr_rect
		(start 217.18651 -372.766082)
		(end 219.093796 -373.632222)
		(stroke
			(width 0)
			(type default)
		)
		(fill no)
		(layer "In1.Cu")
	)
	(gr_rect
		(start 217.18651 -371.877082)
		(end 219.093796 -372.743222)
		(stroke
			(width 0)
			(type default)
		)
		(fill no)
		(layer "In1.Cu")
	)
	(gr_rect
		(start 217.18651 -366.416082)
		(end 219.093796 -367.282222)
		(stroke
			(width 0)
			(type default)
		)
		(fill no)
		(layer "In1.Cu")
	)
	(gr_rect
		(start 217.18651 -365.527082)
		(end 219.093796 -366.393222)
		(stroke
			(width 0)
			(type default)
		)
		(fill no)
		(layer "In1.Cu")
	)
	(gr_rect
		(start 217.699082 -475.720156)
		(end 219.606368 -476.586296)
		(stroke
			(width 0)
			(type default)
		)
		(fill no)
		(layer "In1.Cu")
	)
	(gr_rect
		(start 217.699082 -474.831156)
		(end 219.606368 -475.697296)
		(stroke
			(width 0)
			(type default)
		)
		(fill no)
		(layer "In1.Cu")
	)
	(gr_rect
		(start 217.699082 -469.497156)
		(end 219.606368 -470.363296)
		(stroke
			(width 0)
			(type default)
		)
		(fill no)
		(layer "In1.Cu")
	)
	(gr_rect
		(start 217.699082 -468.608156)
		(end 219.606368 -469.474296)
		(stroke
			(width 0)
			(type default)
		)
		(fill no)
		(layer "In1.Cu")
	)
	(gr_line
		(start 218.759024 -64.67729)
		(end 216.851738 -64.67729)
		(stroke
			(width 0.2)
			(type default)
		)
		(layer "In1.Cu")
	)
	(gr_line
		(start 218.759024 -63.81115)
		(end 218.759024 -64.67729)
		(stroke
			(width 0.2)
			(type default)
		)
		(layer "In1.Cu")
	)
	(gr_arc
		(start 219.609416 -473.86621)
		(mid 220.196156 -474.45295)
		(end 220.782896 -473.86621)
		(stroke
			(width 0.2)
			(type default)
		)
		(layer "In1.Cu")
	)
	(gr_line
		(start 219.609416 -472.90736)
		(end 219.609416 -473.86621)
		(stroke
			(width 0.2)
			(type default)
		)
		(layer "In1.Cu")
	)
	(gr_line
		(start 220.782896 -473.86621)
		(end 220.782896 -472.907614)
		(stroke
			(width 0.2)
			(type default)
		)
		(layer "In1.Cu")
	)
	(gr_arc
		(start 220.782896 -472.907614)
		(mid 220.196283 -472.32062)
		(end 219.609416 -472.90736)
		(stroke
			(width 0.2)
			(type default)
		)
		(layer "In1.Cu")
	)
	(gr_line
		(start 222.055944 -470.477088)
		(end 222.055944 -469.816688)
		(stroke
			(width 0.2)
			(type default)
		)
		(layer "In1.Cu")
	)
	(gr_line
		(start 222.055944 -469.816688)
		(end 224.443544 -469.816688)
		(stroke
			(width 0.2)
			(type default)
		)
		(layer "In1.Cu")
	)
	(gr_line
		(start 222.055944 -469.207088)
		(end 222.055944 -468.546688)
		(stroke
			(width 0.2)
			(type default)
		)
		(layer "In1.Cu")
	)
	(gr_line
		(start 222.055944 -468.546688)
		(end 224.443544 -468.546688)
		(stroke
			(width 0.2)
			(type default)
		)
		(layer "In1.Cu")
	)
	(gr_line
		(start 222.055944 -466.667088)
		(end 222.055944 -466.006688)
		(stroke
			(width 0.2)
			(type default)
		)
		(layer "In1.Cu")
	)
	(gr_line
		(start 222.055944 -466.006688)
		(end 224.443544 -466.006688)
		(stroke
			(width 0.2)
			(type default)
		)
		(layer "In1.Cu")
	)
	(gr_line
		(start 222.055944 -465.397088)
		(end 222.055944 -464.736688)
		(stroke
			(width 0.2)
			(type default)
		)
		(layer "In1.Cu")
	)
	(gr_line
		(start 222.055944 -464.736688)
		(end 224.443544 -464.736688)
		(stroke
			(width 0.2)
			(type default)
		)
		(layer "In1.Cu")
	)
	(gr_line
		(start 222.055944 -367.47704)
		(end 222.055944 -366.81664)
		(stroke
			(width 0.2)
			(type default)
		)
		(layer "In1.Cu")
	)
	(gr_line
		(start 222.055944 -366.81664)
		(end 224.443544 -366.81664)
		(stroke
			(width 0.2)
			(type default)
		)
		(layer "In1.Cu")
	)
	(gr_line
		(start 222.055944 -366.20704)
		(end 222.055944 -365.54664)
		(stroke
			(width 0.2)
			(type default)
		)
		(layer "In1.Cu")
	)
	(gr_line
		(start 222.055944 -365.54664)
		(end 224.443544 -365.54664)
		(stroke
			(width 0.2)
			(type default)
		)
		(layer "In1.Cu")
	)
	(gr_line
		(start 222.055944 -363.66704)
		(end 222.055944 -363.00664)
		(stroke
			(width 0.2)
			(type default)
		)
		(layer "In1.Cu")
	)
	(gr_line
		(start 222.055944 -363.00664)
		(end 224.443544 -363.00664)
		(stroke
			(width 0.2)
			(type default)
		)
		(layer "In1.Cu")
	)
	(gr_line
		(start 222.055944 -362.39704)
		(end 222.055944 -361.73664)
		(stroke
			(width 0.2)
			(type default)
		)
		(layer "In1.Cu")
	)
	(gr_line
		(start 222.055944 -361.73664)
		(end 224.443544 -361.73664)
		(stroke
			(width 0.2)
			(type default)
		)
		(layer "In1.Cu")
	)
	(gr_line
		(start 222.055944 -264.476992)
		(end 222.055944 -263.816592)
		(stroke
			(width 0.2)
			(type default)
		)
		(layer "In1.Cu")
	)
	(gr_line
		(start 222.055944 -263.816592)
		(end 224.443544 -263.816592)
		(stroke
			(width 0.2)
			(type default)
		)
		(layer "In1.Cu")
	)
	(gr_line
		(start 222.055944 -263.206992)
		(end 222.055944 -262.546592)
		(stroke
			(width 0.2)
			(type default)
		)
		(layer "In1.Cu")
	)
	(gr_line
		(start 222.055944 -262.546592)
		(end 224.443544 -262.546592)
		(stroke
			(width 0.2)
			(type default)
		)
		(layer "In1.Cu")
	)
	(gr_line
		(start 222.055944 -260.666992)
		(end 222.055944 -260.006592)
		(stroke
			(width 0.2)
			(type default)
		)
		(layer "In1.Cu")
	)
	(gr_line
		(start 222.055944 -260.006592)
		(end 224.443544 -260.006592)
		(stroke
			(width 0.2)
			(type default)
		)
		(layer "In1.Cu")
	)
	(gr_line
		(start 222.055944 -259.396992)
		(end 222.055944 -258.736592)
		(stroke
			(width 0.2)
			(type default)
		)
		(layer "In1.Cu")
	)
	(gr_line
		(start 222.055944 -258.736592)
		(end 224.443544 -258.736592)
		(stroke
			(width 0.2)
			(type default)
		)
		(layer "In1.Cu")
	)
	(gr_line
		(start 222.055944 -161.476944)
		(end 222.055944 -160.816544)
		(stroke
			(width 0.2)
			(type default)
		)
		(layer "In1.Cu")
	)
	(gr_line
		(start 222.055944 -160.816544)
		(end 224.443544 -160.816544)
		(stroke
			(width 0.2)
			(type default)
		)
		(layer "In1.Cu")
	)
	(gr_line
		(start 222.055944 -160.206944)
		(end 222.055944 -159.546544)
		(stroke
			(width 0.2)
			(type default)
		)
		(layer "In1.Cu")
	)
	(gr_line
		(start 222.055944 -159.546544)
		(end 224.443544 -159.546544)
		(stroke
			(width 0.2)
			(type default)
		)
		(layer "In1.Cu")
	)
	(gr_line
		(start 222.055944 -157.666944)
		(end 222.055944 -157.006544)
		(stroke
			(width 0.2)
			(type default)
		)
		(layer "In1.Cu")
	)
	(gr_line
		(start 222.055944 -157.006544)
		(end 224.443544 -157.006544)
		(stroke
			(width 0.2)
			(type default)
		)
		(layer "In1.Cu")
	)
	(gr_line
		(start 222.055944 -156.396944)
		(end 222.055944 -155.736544)
		(stroke
			(width 0.2)
			(type default)
		)
		(layer "In1.Cu")
	)
	(gr_line
		(start 222.055944 -155.736544)
		(end 224.443544 -155.736544)
		(stroke
			(width 0.2)
			(type default)
		)
		(layer "In1.Cu")
	)
	(gr_line
		(start 222.055944 -58.476896)
		(end 222.055944 -57.816496)
		(stroke
			(width 0.2)
			(type default)
		)
		(layer "In1.Cu")
	)
	(gr_line
		(start 222.055944 -57.816496)
		(end 224.443544 -57.816496)
		(stroke
			(width 0.2)
			(type default)
		)
		(layer "In1.Cu")
	)
	(gr_line
		(start 222.055944 -57.206896)
		(end 222.055944 -56.546496)
		(stroke
			(width 0.2)
			(type default)
		)
		(layer "In1.Cu")
	)
	(gr_line
		(start 222.055944 -56.546496)
		(end 224.443544 -56.546496)
		(stroke
			(width 0.2)
			(type default)
		)
		(layer "In1.Cu")
	)
	(gr_line
		(start 222.055944 -54.666896)
		(end 222.055944 -54.006496)
		(stroke
			(width 0.2)
			(type default)
		)
		(layer "In1.Cu")
	)
	(gr_line
		(start 222.055944 -54.006496)
		(end 224.443544 -54.006496)
		(stroke
			(width 0.2)
			(type default)
		)
		(layer "In1.Cu")
	)
	(gr_line
		(start 222.055944 -53.396896)
		(end 222.055944 -52.736496)
		(stroke
			(width 0.2)
			(type default)
		)
		(layer "In1.Cu")
	)
	(gr_line
		(start 222.055944 -52.736496)
		(end 224.443544 -52.736496)
		(stroke
			(width 0.2)
			(type default)
		)
		(layer "In1.Cu")
	)
	(gr_line
		(start 222.386398 -370.80444)
		(end 222.388938 -370.804694)
		(stroke
			(width 0.2)
			(type default)
		)
		(layer "In1.Cu")
	)
	(gr_arc
		(start 222.388938 -370.804694)
		(mid 222.941642 -371.423438)
		(end 223.560386 -370.870734)
		(stroke
			(width 0.2)
			(type default)
		)
		(layer "In1.Cu")
	)
	(gr_arc
		(start 222.417894 -267.792708)
		(mid 222.956374 -268.424152)
		(end 223.587818 -267.885672)
		(stroke
			(width 0.2)
			(type default)
		)
		(layer "In1.Cu")
	)
	(gr_line
		(start 222.437452 -369.905026)
		(end 222.386398 -370.80444)
		(stroke
			(width 0.2)
			(type default)
		)
		(layer "In1.Cu")
	)
	(gr_line
		(start 222.439992 -369.90528)
		(end 222.437452 -369.905026)
		(stroke
			(width 0.2)
			(type default)
		)
		(layer "In1.Cu")
	)
	(gr_arc
		(start 222.445072 -61.945012)
		(mid 223.031812 -62.531752)
		(end 223.618552 -61.945012)
		(stroke
			(width 0.2)
			(type default)
		)
		(layer "In1.Cu")
	)
	(gr_line
		(start 222.445072 -60.986162)
		(end 222.445072 -61.945012)
		(stroke
			(width 0.2)
			(type default)
		)
		(layer "In1.Cu")
	)
	(gr_line
		(start 222.48622 -266.931648)
		(end 222.417894 -267.792708)
		(stroke
			(width 0.2)
			(type default)
		)
		(layer "In1.Cu")
	)
	(gr_arc
		(start 222.576644 -164.934392)
		(mid 223.163384 -165.521132)
		(end 223.750124 -164.934392)
		(stroke
			(width 0.2)
			(type default)
		)
		(layer "In1.Cu")
	)
	(gr_line
		(start 222.576644 -163.975542)
		(end 222.576644 -164.934392)
		(stroke
			(width 0.2)
			(type default)
		)
		(layer "In1.Cu")
	)
	(gr_line
		(start 223.560386 -370.870734)
		(end 223.562926 -370.870988)
		(stroke
			(width 0.2)
			(type default)
		)
		(layer "In1.Cu")
	)
	(gr_line
		(start 223.562926 -370.870988)
		(end 223.61398 -369.971828)
		(stroke
			(width 0.2)
			(type default)
		)
		(layer "In1.Cu")
	)
	(gr_line
		(start 223.587818 -267.885672)
		(end 223.656144 -267.024866)
		(stroke
			(width 0.2)
			(type default)
		)
		(layer "In1.Cu")
	)
	(gr_arc
		(start 223.61144 -369.971574)
		(mid 223.058863 -369.352569)
		(end 222.439992 -369.90528)
		(stroke
			(width 0.2)
			(type default)
		)
		(layer "In1.Cu")
	)
	(gr_line
		(start 223.613726 -369.971574)
		(end 223.61144 -369.971574)
		(stroke
			(width 0.2)
			(type default)
		)
		(layer "In1.Cu")
	)
	(gr_line
		(start 223.61398 -369.971828)
		(end 223.613726 -369.971574)
		(stroke
			(width 0.2)
			(type default)
		)
		(layer "In1.Cu")
	)
	(gr_line
		(start 223.618552 -61.945012)
		(end 223.618552 -60.986416)
		(stroke
			(width 0.2)
			(type default)
		)
		(layer "In1.Cu")
	)
	(gr_arc
		(start 223.618552 -60.986416)
		(mid 223.031939 -60.399422)
		(end 222.445072 -60.986162)
		(stroke
			(width 0.2)
			(type default)
		)
		(layer "In1.Cu")
	)
	(gr_arc
		(start 223.656144 -267.024866)
		(mid 223.11779 -266.393432)
		(end 222.48622 -266.931648)
		(stroke
			(width 0.2)
			(type default)
		)
		(layer "In1.Cu")
	)
	(gr_line
		(start 223.750124 -164.934392)
		(end 223.750124 -163.975796)
		(stroke
			(width 0.2)
			(type default)
		)
		(layer "In1.Cu")
	)
	(gr_arc
		(start 223.750124 -163.975796)
		(mid 223.163511 -163.388802)
		(end 222.576644 -163.975542)
		(stroke
			(width 0.2)
			(type default)
		)
		(layer "In1.Cu")
	)
	(gr_line
		(start 224.443544 -470.477088)
		(end 222.055944 -470.477088)
		(stroke
			(width 0.2)
			(type default)
		)
		(layer "In1.Cu")
	)
	(gr_line
		(start 224.443544 -469.816688)
		(end 224.443544 -470.477088)
		(stroke
			(width 0.2)
			(type default)
		)
		(layer "In1.Cu")
	)
	(gr_line
		(start 224.443544 -469.207088)
		(end 222.055944 -469.207088)
		(stroke
			(width 0.2)
			(type default)
		)
		(layer "In1.Cu")
	)
	(gr_line
		(start 224.443544 -468.546688)
		(end 224.443544 -469.207088)
		(stroke
			(width 0.2)
			(type default)
		)
		(layer "In1.Cu")
	)
	(gr_line
		(start 224.443544 -466.667088)
		(end 222.055944 -466.667088)
		(stroke
			(width 0.2)
			(type default)
		)
		(layer "In1.Cu")
	)
	(gr_line
		(start 224.443544 -466.006688)
		(end 224.443544 -466.667088)
		(stroke
			(width 0.2)
			(type default)
		)
		(layer "In1.Cu")
	)
	(gr_line
		(start 224.443544 -465.397088)
		(end 222.055944 -465.397088)
		(stroke
			(width 0.2)
			(type default)
		)
		(layer "In1.Cu")
	)
	(gr_line
		(start 224.443544 -464.736688)
		(end 224.443544 -465.397088)
		(stroke
			(width 0.2)
			(type default)
		)
		(layer "In1.Cu")
	)
	(gr_line
		(start 224.443544 -367.47704)
		(end 222.055944 -367.47704)
		(stroke
			(width 0.2)
			(type default)
		)
		(layer "In1.Cu")
	)
	(gr_line
		(start 224.443544 -366.81664)
		(end 224.443544 -367.47704)
		(stroke
			(width 0.2)
			(type default)
		)
		(layer "In1.Cu")
	)
	(gr_line
		(start 224.443544 -366.20704)
		(end 222.055944 -366.20704)
		(stroke
			(width 0.2)
			(type default)
		)
		(layer "In1.Cu")
	)
	(gr_line
		(start 224.443544 -365.54664)
		(end 224.443544 -366.20704)
		(stroke
			(width 0.2)
			(type default)
		)
		(layer "In1.Cu")
	)
	(gr_line
		(start 224.443544 -363.66704)
		(end 222.055944 -363.66704)
		(stroke
			(width 0.2)
			(type default)
		)
		(layer "In1.Cu")
	)
	(gr_line
		(start 224.443544 -363.00664)
		(end 224.443544 -363.66704)
		(stroke
			(width 0.2)
			(type default)
		)
		(layer "In1.Cu")
	)
	(gr_line
		(start 224.443544 -362.39704)
		(end 222.055944 -362.39704)
		(stroke
			(width 0.2)
			(type default)
		)
		(layer "In1.Cu")
	)
	(gr_line
		(start 224.443544 -361.73664)
		(end 224.443544 -362.39704)
		(stroke
			(width 0.2)
			(type default)
		)
		(layer "In1.Cu")
	)
	(gr_line
		(start 224.443544 -264.476992)
		(end 222.055944 -264.476992)
		(stroke
			(width 0.2)
			(type default)
		)
		(layer "In1.Cu")
	)
	(gr_line
		(start 224.443544 -263.816592)
		(end 224.443544 -264.476992)
		(stroke
			(width 0.2)
			(type default)
		)
		(layer "In1.Cu")
	)
	(gr_line
		(start 224.443544 -263.206992)
		(end 222.055944 -263.206992)
		(stroke
			(width 0.2)
			(type default)
		)
		(layer "In1.Cu")
	)
	(gr_line
		(start 224.443544 -262.546592)
		(end 224.443544 -263.206992)
		(stroke
			(width 0.2)
			(type default)
		)
		(layer "In1.Cu")
	)
	(gr_line
		(start 224.443544 -260.666992)
		(end 222.055944 -260.666992)
		(stroke
			(width 0.2)
			(type default)
		)
		(layer "In1.Cu")
	)
	(gr_line
		(start 224.443544 -260.006592)
		(end 224.443544 -260.666992)
		(stroke
			(width 0.2)
			(type default)
		)
		(layer "In1.Cu")
	)
	(gr_line
		(start 224.443544 -259.396992)
		(end 222.055944 -259.396992)
		(stroke
			(width 0.2)
			(type default)
		)
		(layer "In1.Cu")
	)
	(gr_line
		(start 224.443544 -258.736592)
		(end 224.443544 -259.396992)
		(stroke
			(width 0.2)
			(type default)
		)
		(layer "In1.Cu")
	)
	(gr_line
		(start 224.443544 -161.476944)
		(end 222.055944 -161.476944)
		(stroke
			(width 0.2)
			(type default)
		)
		(layer "In1.Cu")
	)
	(gr_line
		(start 224.443544 -160.816544)
		(end 224.443544 -161.476944)
		(stroke
			(width 0.2)
			(type default)
		)
		(layer "In1.Cu")
	)
	(gr_line
		(start 224.443544 -160.206944)
		(end 222.055944 -160.206944)
		(stroke
			(width 0.2)
			(type default)
		)
		(layer "In1.Cu")
	)
	(gr_line
		(start 224.443544 -159.546544)
		(end 224.443544 -160.206944)
		(stroke
			(width 0.2)
			(type default)
		)
		(layer "In1.Cu")
	)
	(gr_line
		(start 224.443544 -157.666944)
		(end 222.055944 -157.666944)
		(stroke
			(width 0.2)
			(type default)
		)
		(layer "In1.Cu")
	)
	(gr_line
		(start 224.443544 -157.006544)
		(end 224.443544 -157.666944)
		(stroke
			(width 0.2)
			(type default)
		)
		(layer "In1.Cu")
	)
	(gr_line
		(start 224.443544 -156.396944)
		(end 222.055944 -156.396944)
		(stroke
			(width 0.2)
			(type default)
		)
		(layer "In1.Cu")
	)
	(gr_line
		(start 224.443544 -155.736544)
		(end 224.443544 -156.396944)
		(stroke
			(width 0.2)
			(type default)
		)
		(layer "In1.Cu")
	)
	(gr_line
		(start 224.443544 -58.476896)
		(end 222.055944 -58.476896)
		(stroke
			(width 0.2)
			(type default)
		)
		(layer "In1.Cu")
	)
	(gr_line
		(start 224.443544 -57.816496)
		(end 224.443544 -58.476896)
		(stroke
			(width 0.2)
			(type default)
		)
		(layer "In1.Cu")
	)
	(gr_line
		(start 224.443544 -57.206896)
		(end 222.055944 -57.206896)
		(stroke
			(width 0.2)
			(type default)
		)
		(layer "In1.Cu")
	)
	(gr_line
		(start 224.443544 -56.546496)
		(end 224.443544 -57.206896)
		(stroke
			(width 0.2)
			(type default)
		)
		(layer "In1.Cu")
	)
	(gr_line
		(start 224.443544 -54.666896)
		(end 222.055944 -54.666896)
		(stroke
			(width 0.2)
			(type default)
		)
		(layer "In1.Cu")
	)
	(gr_line
		(start 224.443544 -54.006496)
		(end 224.443544 -54.666896)
		(stroke
			(width 0.2)
			(type default)
		)
		(layer "In1.Cu")
	)
	(gr_line
		(start 224.443544 -53.396896)
		(end 222.055944 -53.396896)
		(stroke
			(width 0.2)
			(type default)
		)
		(layer "In1.Cu")
	)
	(gr_line
		(start 224.443544 -52.736496)
		(end 224.443544 -53.396896)
		(stroke
			(width 0.2)
			(type default)
		)
		(layer "In1.Cu")
	)
	(gr_line
		(start 224.4471 -476.440754)
		(end 224.4471 -475.932754)
		(stroke
			(width 0.2)
			(type default)
		)
		(layer "In1.Cu")
	)
	(gr_line
		(start 224.4471 -475.932754)
		(end 226.3521 -475.932754)
		(stroke
			(width 0.2)
			(type default)
		)
		(layer "In1.Cu")
	)
	(gr_line
		(start 224.4471 -475.640908)
		(end 224.4471 -475.132908)
		(stroke
			(width 0.2)
			(type default)
		)
		(layer "In1.Cu")
	)
	(gr_line
		(start 224.4471 -475.132908)
		(end 226.3521 -475.132908)
		(stroke
			(width 0.2)
			(type default)
		)
		(layer "In1.Cu")
	)
	(gr_line
		(start 224.4471 -474.040708)
		(end 224.4471 -473.532708)
		(stroke
			(width 0.2)
			(type default)
		)
		(layer "In1.Cu")
	)
	(gr_line
		(start 224.4471 -473.532708)
		(end 226.3521 -473.532708)
		(stroke
			(width 0.2)
			(type default)
		)
		(layer "In1.Cu")
	)
	(gr_line
		(start 224.4471 -473.240862)
		(end 224.4471 -472.732862)
		(stroke
			(width 0.2)
			(type default)
		)
		(layer "In1.Cu")
	)
	(gr_line
		(start 224.4471 -472.732862)
		(end 226.3521 -472.732862)
		(stroke
			(width 0.2)
			(type default)
		)
		(layer "In1.Cu")
	)
	(gr_line
		(start 224.4471 -373.440706)
		(end 224.4471 -372.932706)
		(stroke
			(width 0.2)
			(type default)
		)
		(layer "In1.Cu")
	)
	(gr_line
		(start 224.4471 -372.932706)
		(end 226.3521 -372.932706)
		(stroke
			(width 0.2)
			(type default)
		)
		(layer "In1.Cu")
	)
	(gr_line
		(start 224.4471 -372.64086)
		(end 224.4471 -372.13286)
		(stroke
			(width 0.2)
			(type default)
		)
		(layer "In1.Cu")
	)
	(gr_line
		(start 224.4471 -372.13286)
		(end 226.3521 -372.13286)
		(stroke
			(width 0.2)
			(type default)
		)
		(layer "In1.Cu")
	)
	(gr_line
		(start 224.4471 -371.04066)
		(end 224.4471 -370.53266)
		(stroke
			(width 0.2)
			(type default)
		)
		(layer "In1.Cu")
	)
	(gr_line
		(start 224.4471 -370.53266)
		(end 226.3521 -370.53266)
		(stroke
			(width 0.2)
			(type default)
		)
		(layer "In1.Cu")
	)
	(gr_line
		(start 224.4471 -370.240814)
		(end 224.4471 -369.732814)
		(stroke
			(width 0.2)
			(type default)
		)
		(layer "In1.Cu")
	)
	(gr_line
		(start 224.4471 -369.732814)
		(end 226.3521 -369.732814)
		(stroke
			(width 0.2)
			(type default)
		)
		(layer "In1.Cu")
	)
	(gr_line
		(start 224.4471 -270.440658)
		(end 224.4471 -269.932658)
		(stroke
			(width 0.2)
			(type default)
		)
		(layer "In1.Cu")
	)
	(gr_line
		(start 224.4471 -269.932658)
		(end 226.3521 -269.932658)
		(stroke
			(width 0.2)
			(type default)
		)
		(layer "In1.Cu")
	)
	(gr_line
		(start 224.4471 -269.640812)
		(end 224.4471 -269.132812)
		(stroke
			(width 0.2)
			(type default)
		)
		(layer "In1.Cu")
	)
	(gr_line
		(start 224.4471 -269.132812)
		(end 226.3521 -269.132812)
		(stroke
			(width 0.2)
			(type default)
		)
		(layer "In1.Cu")
	)
	(gr_line
		(start 224.4471 -268.040612)
		(end 224.4471 -267.532612)
		(stroke
			(width 0.2)
			(type default)
		)
		(layer "In1.Cu")
	)
	(gr_line
		(start 224.4471 -267.532612)
		(end 226.3521 -267.532612)
		(stroke
			(width 0.2)
			(type default)
		)
		(layer "In1.Cu")
	)
	(gr_line
		(start 224.4471 -267.240766)
		(end 224.4471 -266.732766)
		(stroke
			(width 0.2)
			(type default)
		)
		(layer "In1.Cu")
	)
	(gr_line
		(start 224.4471 -266.732766)
		(end 226.3521 -266.732766)
		(stroke
			(width 0.2)
			(type default)
		)
		(layer "In1.Cu")
	)
	(gr_line
		(start 224.4471 -167.44061)
		(end 224.4471 -166.93261)
		(stroke
			(width 0.2)
			(type default)
		)
		(layer "In1.Cu")
	)
	(gr_line
		(start 224.4471 -166.93261)
		(end 226.3521 -166.93261)
		(stroke
			(width 0.2)
			(type default)
		)
		(layer "In1.Cu")
	)
	(gr_line
		(start 224.4471 -166.640764)
		(end 224.4471 -166.132764)
		(stroke
			(width 0.2)
			(type default)
		)
		(layer "In1.Cu")
	)
	(gr_line
		(start 224.4471 -166.132764)
		(end 226.3521 -166.132764)
		(stroke
			(width 0.2)
			(type default)
		)
		(layer "In1.Cu")
	)
	(gr_line
		(start 224.4471 -165.040564)
		(end 224.4471 -164.532564)
		(stroke
			(width 0.2)
			(type default)
		)
		(layer "In1.Cu")
	)
	(gr_line
		(start 224.4471 -164.532564)
		(end 226.3521 -164.532564)
		(stroke
			(width 0.2)
			(type default)
		)
		(layer "In1.Cu")
	)
	(gr_line
		(start 224.4471 -164.240718)
		(end 224.4471 -163.732718)
		(stroke
			(width 0.2)
			(type default)
		)
		(layer "In1.Cu")
	)
	(gr_line
		(start 224.4471 -163.732718)
		(end 226.3521 -163.732718)
		(stroke
			(width 0.2)
			(type default)
		)
		(layer "In1.Cu")
	)
	(gr_line
		(start 224.4471 -64.440562)
		(end 224.4471 -63.932562)
		(stroke
			(width 0.2)
			(type default)
		)
		(layer "In1.Cu")
	)
	(gr_line
		(start 224.4471 -63.932562)
		(end 226.3521 -63.932562)
		(stroke
			(width 0.2)
			(type default)
		)
		(layer "In1.Cu")
	)
	(gr_line
		(start 224.4471 -63.640716)
		(end 224.4471 -63.132716)
		(stroke
			(width 0.2)
			(type default)
		)
		(layer "In1.Cu")
	)
	(gr_line
		(start 224.4471 -63.132716)
		(end 226.3521 -63.132716)
		(stroke
			(width 0.2)
			(type default)
		)
		(layer "In1.Cu")
	)
	(gr_line
		(start 224.4471 -62.040516)
		(end 224.4471 -61.532516)
		(stroke
			(width 0.2)
			(type default)
		)
		(layer "In1.Cu")
	)
	(gr_line
		(start 224.4471 -61.532516)
		(end 226.3521 -61.532516)
		(stroke
			(width 0.2)
			(type default)
		)
		(layer "In1.Cu")
	)
	(gr_line
		(start 224.4471 -61.24067)
		(end 224.4471 -60.73267)
		(stroke
			(width 0.2)
			(type default)
		)
		(layer "In1.Cu")
	)
	(gr_line
		(start 224.4471 -60.73267)
		(end 226.3521 -60.73267)
		(stroke
			(width 0.2)
			(type default)
		)
		(layer "In1.Cu")
	)
	(gr_line
		(start 226.3521 -476.440754)
		(end 224.4471 -476.440754)
		(stroke
			(width 0.2)
			(type default)
		)
		(layer "In1.Cu")
	)
	(gr_line
		(start 226.3521 -475.932754)
		(end 226.3521 -476.440754)
		(stroke
			(width 0.2)
			(type default)
		)
		(layer "In1.Cu")
	)
	(gr_line
		(start 226.3521 -475.640908)
		(end 224.4471 -475.640908)
		(stroke
			(width 0.2)
			(type default)
		)
		(layer "In1.Cu")
	)
	(gr_line
		(start 226.3521 -475.132908)
		(end 226.3521 -475.640908)
		(stroke
			(width 0.2)
			(type default)
		)
		(layer "In1.Cu")
	)
	(gr_line
		(start 226.3521 -474.040708)
		(end 224.4471 -474.040708)
		(stroke
			(width 0.2)
			(type default)
		)
		(layer "In1.Cu")
	)
	(gr_line
		(start 226.3521 -473.532708)
		(end 226.3521 -474.040708)
		(stroke
			(width 0.2)
			(type default)
		)
		(layer "In1.Cu")
	)
	(gr_line
		(start 226.3521 -473.240862)
		(end 224.4471 -473.240862)
		(stroke
			(width 0.2)
			(type default)
		)
		(layer "In1.Cu")
	)
	(gr_line
		(start 226.3521 -472.732862)
		(end 226.3521 -473.240862)
		(stroke
			(width 0.2)
			(type default)
		)
		(layer "In1.Cu")
	)
	(gr_line
		(start 226.3521 -373.440706)
		(end 224.4471 -373.440706)
		(stroke
			(width 0.2)
			(type default)
		)
		(layer "In1.Cu")
	)
	(gr_line
		(start 226.3521 -372.932706)
		(end 226.3521 -373.440706)
		(stroke
			(width 0.2)
			(type default)
		)
		(layer "In1.Cu")
	)
	(gr_line
		(start 226.3521 -372.64086)
		(end 224.4471 -372.64086)
		(stroke
			(width 0.2)
			(type default)
		)
		(layer "In1.Cu")
	)
	(gr_line
		(start 226.3521 -372.13286)
		(end 226.3521 -372.64086)
		(stroke
			(width 0.2)
			(type default)
		)
		(layer "In1.Cu")
	)
	(gr_line
		(start 226.3521 -371.04066)
		(end 224.4471 -371.04066)
		(stroke
			(width 0.2)
			(type default)
		)
		(layer "In1.Cu")
	)
	(gr_line
		(start 226.3521 -370.53266)
		(end 226.3521 -371.04066)
		(stroke
			(width 0.2)
			(type default)
		)
		(layer "In1.Cu")
	)
	(gr_line
		(start 226.3521 -370.240814)
		(end 224.4471 -370.240814)
		(stroke
			(width 0.2)
			(type default)
		)
		(layer "In1.Cu")
	)
	(gr_line
		(start 226.3521 -369.732814)
		(end 226.3521 -370.240814)
		(stroke
			(width 0.2)
			(type default)
		)
		(layer "In1.Cu")
	)
	(gr_line
		(start 226.3521 -270.440658)
		(end 224.4471 -270.440658)
		(stroke
			(width 0.2)
			(type default)
		)
		(layer "In1.Cu")
	)
	(gr_line
		(start 226.3521 -269.932658)
		(end 226.3521 -270.440658)
		(stroke
			(width 0.2)
			(type default)
		)
		(layer "In1.Cu")
	)
	(gr_line
		(start 226.3521 -269.640812)
		(end 224.4471 -269.640812)
		(stroke
			(width 0.2)
			(type default)
		)
		(layer "In1.Cu")
	)
	(gr_line
		(start 226.3521 -269.132812)
		(end 226.3521 -269.640812)
		(stroke
			(width 0.2)
			(type default)
		)
		(layer "In1.Cu")
	)
	(gr_line
		(start 226.3521 -268.040612)
		(end 224.4471 -268.040612)
		(stroke
			(width 0.2)
			(type default)
		)
		(layer "In1.Cu")
	)
	(gr_line
		(start 226.3521 -267.532612)
		(end 226.3521 -268.040612)
		(stroke
			(width 0.2)
			(type default)
		)
		(layer "In1.Cu")
	)
	(gr_line
		(start 226.3521 -267.240766)
		(end 224.4471 -267.240766)
		(stroke
			(width 0.2)
			(type default)
		)
		(layer "In1.Cu")
	)
	(gr_line
		(start 226.3521 -266.732766)
		(end 226.3521 -267.240766)
		(stroke
			(width 0.2)
			(type default)
		)
		(layer "In1.Cu")
	)
	(gr_line
		(start 226.3521 -167.44061)
		(end 224.4471 -167.44061)
		(stroke
			(width 0.2)
			(type default)
		)
		(layer "In1.Cu")
	)
	(gr_line
		(start 226.3521 -166.93261)
		(end 226.3521 -167.44061)
		(stroke
			(width 0.2)
			(type default)
		)
		(layer "In1.Cu")
	)
	(gr_line
		(start 226.3521 -166.640764)
		(end 224.4471 -166.640764)
		(stroke
			(width 0.2)
			(type default)
		)
		(layer "In1.Cu")
	)
	(gr_line
		(start 226.3521 -166.132764)
		(end 226.3521 -166.640764)
		(stroke
			(width 0.2)
			(type default)
		)
		(layer "In1.Cu")
	)
	(gr_line
		(start 226.3521 -165.040564)
		(end 224.4471 -165.040564)
		(stroke
			(width 0.2)
			(type default)
		)
		(layer "In1.Cu")
	)
	(gr_line
		(start 226.3521 -164.532564)
		(end 226.3521 -165.040564)
		(stroke
			(width 0.2)
			(type default)
		)
		(layer "In1.Cu")
	)
	(gr_line
		(start 226.3521 -164.240718)
		(end 224.4471 -164.240718)
		(stroke
			(width 0.2)
			(type default)
		)
		(layer "In1.Cu")
	)
	(gr_line
		(start 226.3521 -163.732718)
		(end 226.3521 -164.240718)
		(stroke
			(width 0.2)
			(type default)
		)
		(layer "In1.Cu")
	)
	(gr_line
		(start 226.3521 -64.440562)
		(end 224.4471 -64.440562)
		(stroke
			(width 0.2)
			(type default)
		)
		(layer "In1.Cu")
	)
	(gr_line
		(start 226.3521 -63.932562)
		(end 226.3521 -64.440562)
		(stroke
			(width 0.2)
			(type default)
		)
		(layer "In1.Cu")
	)
	(gr_line
		(start 226.3521 -63.640716)
		(end 224.4471 -63.640716)
		(stroke
			(width 0.2)
			(type default)
		)
		(layer "In1.Cu")
	)
	(gr_line
		(start 226.3521 -63.132716)
		(end 226.3521 -63.640716)
		(stroke
			(width 0.2)
			(type default)
		)
		(layer "In1.Cu")
	)
	(gr_line
		(start 226.3521 -62.040516)
		(end 224.4471 -62.040516)
		(stroke
			(width 0.2)
			(type default)
		)
		(layer "In1.Cu")
	)
	(gr_line
		(start 226.3521 -61.532516)
		(end 226.3521 -62.040516)
		(stroke
			(width 0.2)
			(type default)
		)
		(layer "In1.Cu")
	)
	(gr_line
		(start 226.3521 -61.24067)
		(end 224.4471 -61.24067)
		(stroke
			(width 0.2)
			(type default)
		)
		(layer "In1.Cu")
	)
	(gr_line
		(start 226.3521 -60.73267)
		(end 226.3521 -61.24067)
		(stroke
			(width 0.2)
			(type default)
		)
		(layer "In1.Cu")
	)
	(gr_line
		(start 6.679946 -121.514616)
		(end 7.095744 -121.514616)
		(stroke
			(width 0.05715)
			(type default)
		)
		(layer "In2.Cu")
	)
	(gr_arc
		(start 6.727444 -117.512592)
		(mid 6.818252 -117.572559)
		(end 6.92531 -117.592094)
		(stroke
			(width 0.05715)
			(type default)
		)
		(layer "In2.Cu")
	)
	(gr_line
		(start 6.730746 -118.251986)
		(end 6.730746 -118.4275)
		(stroke
			(width 0.05715)
			(type default)
		)
		(layer "In2.Cu")
	)
	(gr_line
		(start 6.73481 -122.376692)
		(end 6.778244 -122.272044)
		(stroke
			(width 0.05715)
			(type default)
		)
		(layer "In2.Cu")
	)
	(gr_arc
		(start 6.756146 -133.570218)
		(mid 6.879274 -133.819642)
		(end 7.152132 -133.873494)
		(stroke
			(width 0.05715)
			(type default)
		)
		(layer "In2.Cu")
	)
	(gr_line
		(start 6.756146 -133.514592)
		(end 6.756146 -133.570218)
		(stroke
			(width 0.05715)
			(type default)
		)
		(layer "In2.Cu")
	)
	(gr_arc
		(start 6.778244 -122.272044)
		(mid 6.784719 -122.250498)
		(end 6.78688 -122.228102)
		(stroke
			(width 0.05715)
			(type default)
		)
		(layer "In2.Cu")
	)
	(gr_line
		(start 6.78688 -122.228102)
		(end 6.828536 -122.127518)
		(stroke
			(width 0.05715)
			(type default)
		)
		(layer "In2.Cu")
	)
	(gr_arc
		(start 6.828536 -122.127518)
		(mid 6.835579 -122.104491)
		(end 6.837934 -122.080528)
		(stroke
			(width 0.05715)
			(type default)
		)
		(layer "In2.Cu")
	)
	(gr_line
		(start 6.837934 -122.054112)
		(end 6.837934 -122.080528)
		(stroke
			(width 0.05715)
			(type default)
		)
		(layer "In2.Cu")
	)
	(gr_arc
		(start 6.873748 -121.967498)
		(mid 6.847249 -122.007251)
		(end 6.837934 -122.054112)
		(stroke
			(width 0.05715)
			(type default)
		)
		(layer "In2.Cu")
	)
	(gr_line
		(start 6.873748 -121.967498)
		(end 6.903974 -121.937272)
		(stroke
			(width 0.05715)
			(type default)
		)
		(layer "In2.Cu")
	)
	(gr_line
		(start 6.92531 -117.592094)
		(end 7.071614 -117.588792)
		(stroke
			(width 0.05715)
			(type default)
		)
		(layer "In2.Cu")
	)
	(gr_arc
		(start 7.062978 -121.871486)
		(mid 6.97694 -121.888582)
		(end 6.903974 -121.937272)
		(stroke
			(width 0.05715)
			(type default)
		)
		(layer "In2.Cu")
	)
	(gr_line
		(start 7.062978 -121.871486)
		(end 7.257542 -121.871486)
		(stroke
			(width 0.05715)
			(type default)
		)
		(layer "In2.Cu")
	)
	(gr_arc
		(start 7.508494 -121.646696)
		(mid 7.312436 -121.548404)
		(end 7.095744 -121.514616)
		(stroke
			(width 0.05715)
			(type default)
		)
		(layer "In2.Cu")
	)
	(gr_arc
		(start 9.529826 -133.82625)
		(mid 9.634736 -133.801095)
		(end 9.717786 -133.73227)
		(stroke
			(width 0.05715)
			(type default)
		)
		(layer "In2.Cu")
	)
	(gr_line
		(start 9.837166 -134.13105)
		(end 10.317226 -134.13105)
		(stroke
			(width 0.05715)
			(type default)
		)
		(layer "In2.Cu")
	)
	(gr_arc
		(start 9.905746 -133.63829)
		(mid 9.800881 -133.663516)
		(end 9.717786 -133.73227)
		(stroke
			(width 0.05715)
			(type default)
		)
		(layer "In2.Cu")
	)
	(gr_line
		(start 9.905746 -133.63829)
		(end 10.248646 -133.63829)
		(stroke
			(width 0.05715)
			(type default)
		)
		(layer "In2.Cu")
	)
	(gr_arc
		(start 10.436606 -133.73227)
		(mid 10.353542 -133.663456)
		(end 10.248646 -133.63829)
		(stroke
			(width 0.05715)
			(type default)
		)
		(layer "In2.Cu")
	)
	(gr_arc
		(start 10.436606 -133.73227)
		(mid 10.5197 -133.801006)
		(end 10.624566 -133.82625)
		(stroke
			(width 0.05715)
			(type default)
		)
		(layer "In2.Cu")
	)
	(gr_arc
		(start 10.967466 -133.82625)
		(mid 11.072376 -133.801095)
		(end 11.155426 -133.73227)
		(stroke
			(width 0.05715)
			(type default)
		)
		(layer "In2.Cu")
	)
	(gr_line
		(start 11.274806 -134.13105)
		(end 11.754866 -134.13105)
		(stroke
			(width 0.05715)
			(type default)
		)
		(layer "In2.Cu")
	)
	(gr_arc
		(start 11.343386 -133.63829)
		(mid 11.238538 -133.663537)
		(end 11.155426 -133.73227)
		(stroke
			(width 0.05715)
			(type default)
		)
		(layer "In2.Cu")
	)
	(gr_line
		(start 11.343386 -133.63829)
		(end 11.686286 -133.63829)
		(stroke
			(width 0.05715)
			(type default)
		)
		(layer "In2.Cu")
	)
	(gr_arc
		(start 11.874246 -133.73227)
		(mid 11.791185 -133.663442)
		(end 11.686286 -133.63829)
		(stroke
			(width 0.05715)
			(type default)
		)
		(layer "In2.Cu")
	)
	(gr_arc
		(start 11.874246 -133.73227)
		(mid 11.95734 -133.801006)
		(end 12.062206 -133.82625)
		(stroke
			(width 0.05715)
			(type default)
		)
		(layer "In2.Cu")
	)
	(gr_arc
		(start 12.405106 -133.82625)
		(mid 12.510016 -133.801095)
		(end 12.593066 -133.73227)
		(stroke
			(width 0.05715)
			(type default)
		)
		(layer "In2.Cu")
	)
	(gr_line
		(start 12.712446 -134.13105)
		(end 13.192506 -134.13105)
		(stroke
			(width 0.05715)
			(type default)
		)
		(layer "In2.Cu")
	)
	(gr_arc
		(start 12.781026 -133.63829)
		(mid 12.676167 -133.663523)
		(end 12.593066 -133.73227)
		(stroke
			(width 0.05715)
			(type default)
		)
		(layer "In2.Cu")
	)
	(gr_line
		(start 12.781026 -133.63829)
		(end 13.123926 -133.63829)
		(stroke
			(width 0.05715)
			(type default)
		)
		(layer "In2.Cu")
	)
	(gr_arc
		(start 13.311886 -133.73227)
		(mid 13.22882 -133.663463)
		(end 13.123926 -133.63829)
		(stroke
			(width 0.05715)
			(type default)
		)
		(layer "In2.Cu")
	)
	(gr_arc
		(start 13.311886 -133.73227)
		(mid 13.39498 -133.801006)
		(end 13.499846 -133.82625)
		(stroke
			(width 0.05715)
			(type default)
		)
		(layer "In2.Cu")
	)
	(gr_line
		(start 13.537946 -133.82625)
		(end 13.842746 -133.82625)
		(stroke
			(width 0.05715)
			(type default)
		)
		(layer "In2.Cu")
	)
	(gr_line
		(start 13.842746 -134.130796)
		(end 13.842746 -134.13105)
		(stroke
			(width 0.05715)
			(type default)
		)
		(layer "In2.Cu")
	)
	(gr_arc
		(start 19.445478 -131.6609)
		(mid 19.550318 -131.635656)
		(end 19.633438 -131.56692)
		(stroke
			(width 0.05715)
			(type default)
		)
		(layer "In2.Cu")
	)
	(gr_line
		(start 19.752818 -131.9657)
		(end 20.232878 -131.9657)
		(stroke
			(width 0.05715)
			(type default)
		)
		(layer "In2.Cu")
	)
	(gr_arc
		(start 19.821398 -131.47294)
		(mid 19.716542 -131.498179)
		(end 19.633438 -131.56692)
		(stroke
			(width 0.05715)
			(type default)
		)
		(layer "In2.Cu")
	)
	(gr_line
		(start 19.821398 -131.47294)
		(end 20.164298 -131.47294)
		(stroke
			(width 0.05715)
			(type default)
		)
		(layer "In2.Cu")
	)
	(gr_arc
		(start 20.352258 -131.56692)
		(mid 20.269143 -131.498211)
		(end 20.164298 -131.47294)
		(stroke
			(width 0.05715)
			(type default)
		)
		(layer "In2.Cu")
	)
	(gr_arc
		(start 20.352258 -131.56692)
		(mid 20.435352 -131.635656)
		(end 20.540218 -131.6609)
		(stroke
			(width 0.05715)
			(type default)
		)
		(layer "In2.Cu")
	)
	(gr_arc
		(start 20.883118 -131.6609)
		(mid 20.987958 -131.635656)
		(end 21.071078 -131.56692)
		(stroke
			(width 0.05715)
			(type default)
		)
		(layer "In2.Cu")
	)
	(gr_line
		(start 21.190458 -131.9657)
		(end 21.670518 -131.9657)
		(stroke
			(width 0.05715)
			(type default)
		)
		(layer "In2.Cu")
	)
	(gr_arc
		(start 21.259038 -131.47294)
		(mid 21.154171 -131.498165)
		(end 21.071078 -131.56692)
		(stroke
			(width 0.05715)
			(type default)
		)
		(layer "In2.Cu")
	)
	(gr_line
		(start 21.259038 -131.47294)
		(end 21.601938 -131.47294)
		(stroke
			(width 0.05715)
			(type default)
		)
		(layer "In2.Cu")
	)
	(gr_arc
		(start 21.789898 -131.56692)
		(mid 21.706786 -131.498197)
		(end 21.601938 -131.47294)
		(stroke
			(width 0.05715)
			(type default)
		)
		(layer "In2.Cu")
	)
	(gr_arc
		(start 21.789898 -131.56692)
		(mid 21.872992 -131.635656)
		(end 21.977858 -131.6609)
		(stroke
			(width 0.05715)
			(type default)
		)
		(layer "In2.Cu")
	)
	(gr_arc
		(start 22.320758 -131.6609)
		(mid 22.425668 -131.635745)
		(end 22.508718 -131.56692)
		(stroke
			(width 0.05715)
			(type default)
		)
		(layer "In2.Cu")
	)
	(gr_line
		(start 22.628098 -131.9657)
		(end 23.108158 -131.9657)
		(stroke
			(width 0.05715)
			(type default)
		)
		(layer "In2.Cu")
	)
	(gr_arc
		(start 22.696678 -131.47294)
		(mid 22.591828 -131.498186)
		(end 22.508718 -131.56692)
		(stroke
			(width 0.05715)
			(type default)
		)
		(layer "In2.Cu")
	)
	(gr_line
		(start 22.696678 -131.47294)
		(end 23.039578 -131.47294)
		(stroke
			(width 0.05715)
			(type default)
		)
		(layer "In2.Cu")
	)
	(gr_arc
		(start 23.227538 -131.56692)
		(mid 23.14448 -131.498081)
		(end 23.039578 -131.47294)
		(stroke
			(width 0.05715)
			(type default)
		)
		(layer "In2.Cu")
	)
	(gr_arc
		(start 23.227538 -131.56692)
		(mid 23.310632 -131.635656)
		(end 23.415498 -131.6609)
		(stroke
			(width 0.05715)
			(type default)
		)
		(layer "In2.Cu")
	)
	(gr_line
		(start 24.257 -130.4036)
		(end 24.371554 -130.518408)
		(stroke
			(width 0.05715)
			(type default)
		)
		(layer "In2.Cu")
	)
	(gr_arc
		(start 24.5872 -131.0386)
		(mid 24.531105 -130.757061)
		(end 24.371554 -130.518408)
		(stroke
			(width 0.05715)
			(type default)
		)
		(layer "In2.Cu")
	)
	(gr_line
		(start 24.650446 -131.762246)
		(end 24.650446 -131.7625)
		(stroke
			(width 0.05715)
			(type default)
		)
		(layer "In2.Cu")
	)
	(gr_arc
		(start 25.1206 -130.4036)
		(mid 24.951395 -130.656833)
		(end 24.892 -130.955542)
		(stroke
			(width 0.05715)
			(type default)
		)
		(layer "In2.Cu")
	)
	(gr_line
		(start 30.162754 -205.600554)
		(end 30.3784 -205.8162)
		(stroke
			(width 0.05715)
			(type default)
		)
		(layer "In2.Cu")
	)
	(gr_line
		(start 30.163008 -206.031592)
		(end 30.162754 -206.031846)
		(stroke
			(width 0.05715)
			(type default)
		)
		(layer "In2.Cu")
	)
	(gr_line
		(start 31.495746 -266.8651)
		(end 31.701994 -267.071602)
		(stroke
			(width 0.05715)
			(type default)
		)
		(layer "In2.Cu")
	)
	(gr_arc
		(start 31.701994 -267.071602)
		(mid 31.810839 -267.14433)
		(end 31.93923 -267.1699)
		(stroke
			(width 0.05715)
			(type default)
		)
		(layer "In2.Cu")
	)
	(gr_arc
		(start 32.004254 -267.48105)
		(mid 31.729253 -267.562268)
		(end 31.495746 -267.7287)
		(stroke
			(width 0.05715)
			(type default)
		)
		(layer "In2.Cu")
	)
	(gr_line
		(start 32.004254 -267.48105)
		(end 32.004508 -267.48105)
		(stroke
			(width 0.05715)
			(type default)
		)
		(layer "In2.Cu")
	)
	(gr_arc
		(start 32.108902 -267.4747)
		(mid 32.05661 -267.476308)
		(end 32.004508 -267.48105)
		(stroke
			(width 0.05715)
			(type default)
		)
		(layer "In2.Cu")
	)
	(gr_line
		(start 32.3215 -265.328654)
		(end 32.537146 -265.5443)
		(stroke
			(width 0.05715)
			(type default)
		)
		(layer "In2.Cu")
	)
	(gr_line
		(start 32.398208 -167.906192)
		(end 32.397954 -167.906446)
		(stroke
			(width 0.05715)
			(type default)
		)
		(layer "In2.Cu")
	)
	(gr_line
		(start 32.498792 -167.575992)
		(end 32.6136 -167.6908)
		(stroke
			(width 0.05715)
			(type default)
		)
		(layer "In2.Cu")
	)
	(gr_line
		(start 32.752792 -265.328654)
		(end 32.752538 -265.328908)
		(stroke
			(width 0.05715)
			(type default)
		)
		(layer "In2.Cu")
	)
	(gr_arc
		(start 32.766 -164.583618)
		(mid 32.699937 -164.251373)
		(end 32.511746 -163.9697)
		(stroke
			(width 0.05715)
			(type default)
		)
		(layer "In2.Cu")
	)
	(gr_line
		(start 32.776668 -267.259562)
		(end 32.776668 -267.259816)
		(stroke
			(width 0.05715)
			(type default)
		)
		(layer "In2.Cu")
	)
	(gr_arc
		(start 33.3756 -163.7284)
		(mid 33.150019 -164.066005)
		(end 33.0708 -164.464238)
		(stroke
			(width 0.05715)
			(type default)
		)
		(layer "In2.Cu")
	)
	(gr_line
		(start 35.2552 -167.6146)
		(end 35.470846 -167.398954)
		(stroke
			(width 0.05715)
			(type default)
		)
		(layer "In2.Cu")
	)
	(gr_line
		(start 35.470592 -167.829992)
		(end 35.470846 -167.830246)
		(stroke
			(width 0.05715)
			(type default)
		)
		(layer "In2.Cu")
	)
	(gr_arc
		(start 37.058346 -149.429216)
		(mid 37.083509 -149.534108)
		(end 37.152326 -149.617176)
		(stroke
			(width 0.05715)
			(type default)
		)
		(layer "In2.Cu")
	)
	(gr_line
		(start 37.058346 -149.086316)
		(end 37.058346 -149.429216)
		(stroke
			(width 0.05715)
			(type default)
		)
		(layer "In2.Cu")
	)
	(gr_arc
		(start 37.058346 -147.991576)
		(mid 37.083495 -148.096479)
		(end 37.152326 -148.179536)
		(stroke
			(width 0.05715)
			(type default)
		)
		(layer "In2.Cu")
	)
	(gr_line
		(start 37.058346 -147.648676)
		(end 37.058346 -147.991576)
		(stroke
			(width 0.05715)
			(type default)
		)
		(layer "In2.Cu")
	)
	(gr_arc
		(start 37.058346 -145.404078)
		(mid 37.083577 -145.50894)
		(end 37.152326 -145.592038)
		(stroke
			(width 0.05715)
			(type default)
		)
		(layer "In2.Cu")
	)
	(gr_line
		(start 37.058346 -145.061178)
		(end 37.058346 -145.404078)
		(stroke
			(width 0.05715)
			(type default)
		)
		(layer "In2.Cu")
	)
	(gr_arc
		(start 37.058346 -143.966438)
		(mid 37.083517 -144.071324)
		(end 37.152326 -144.154398)
		(stroke
			(width 0.05715)
			(type default)
		)
		(layer "In2.Cu")
	)
	(gr_line
		(start 37.058346 -143.623538)
		(end 37.058346 -143.966438)
		(stroke
			(width 0.05715)
			(type default)
		)
		(layer "In2.Cu")
	)
	(gr_arc
		(start 37.058346 -142.528798)
		(mid 37.083503 -142.633695)
		(end 37.152326 -142.716758)
		(stroke
			(width 0.05715)
			(type default)
		)
		(layer "In2.Cu")
	)
	(gr_line
		(start 37.058346 -142.185898)
		(end 37.058346 -142.528798)
		(stroke
			(width 0.05715)
			(type default)
		)
		(layer "In2.Cu")
	)
	(gr_arc
		(start 37.058346 -141.091158)
		(mid 37.08357 -141.196025)
		(end 37.152326 -141.279118)
		(stroke
			(width 0.05715)
			(type default)
		)
		(layer "In2.Cu")
	)
	(gr_line
		(start 37.058346 -140.748258)
		(end 37.058346 -141.091158)
		(stroke
			(width 0.05715)
			(type default)
		)
		(layer "In2.Cu")
	)
	(gr_line
		(start 37.109654 -165.760146)
		(end 37.3253 -165.5445)
		(stroke
			(width 0.05715)
			(type default)
		)
		(layer "In2.Cu")
	)
	(gr_arc
		(start 37.152326 -148.898356)
		(mid 37.083483 -148.981413)
		(end 37.058346 -149.086316)
		(stroke
			(width 0.05715)
			(type default)
		)
		(layer "In2.Cu")
	)
	(gr_arc
		(start 37.152326 -148.898356)
		(mid 37.221151 -148.815281)
		(end 37.246306 -148.710396)
		(stroke
			(width 0.05715)
			(type default)
		)
		(layer "In2.Cu")
	)
	(gr_arc
		(start 37.152326 -147.460716)
		(mid 37.083504 -147.543777)
		(end 37.058346 -147.648676)
		(stroke
			(width 0.05715)
			(type default)
		)
		(layer "In2.Cu")
	)
	(gr_arc
		(start 37.152326 -147.460716)
		(mid 37.221151 -147.377641)
		(end 37.246306 -147.272756)
		(stroke
			(width 0.05715)
			(type default)
		)
		(layer "In2.Cu")
	)
	(gr_arc
		(start 37.152326 -144.873218)
		(mid 37.083505 -144.956279)
		(end 37.058346 -145.061178)
		(stroke
			(width 0.05715)
			(type default)
		)
		(layer "In2.Cu")
	)
	(gr_arc
		(start 37.152326 -144.873218)
		(mid 37.221062 -144.790124)
		(end 37.246306 -144.685258)
		(stroke
			(width 0.05715)
			(type default)
		)
		(layer "In2.Cu")
	)
	(gr_arc
		(start 37.152326 -143.435578)
		(mid 37.08349 -143.518636)
		(end 37.058346 -143.623538)
		(stroke
			(width 0.05715)
			(type default)
		)
		(layer "In2.Cu")
	)
	(gr_arc
		(start 37.152326 -143.435578)
		(mid 37.221151 -143.352503)
		(end 37.246306 -143.247618)
		(stroke
			(width 0.05715)
			(type default)
		)
		(layer "In2.Cu")
	)
	(gr_arc
		(start 37.152326 -141.997938)
		(mid 37.083476 -142.080993)
		(end 37.058346 -142.185898)
		(stroke
			(width 0.05715)
			(type default)
		)
		(layer "In2.Cu")
	)
	(gr_arc
		(start 37.152326 -141.997938)
		(mid 37.221151 -141.914863)
		(end 37.246306 -141.809978)
		(stroke
			(width 0.05715)
			(type default)
		)
		(layer "In2.Cu")
	)
	(gr_arc
		(start 37.152326 -140.560298)
		(mid 37.083498 -140.643358)
		(end 37.058346 -140.748258)
		(stroke
			(width 0.05715)
			(type default)
		)
		(layer "In2.Cu")
	)
	(gr_arc
		(start 37.152326 -140.560298)
		(mid 37.221062 -140.477204)
		(end 37.246306 -140.372338)
		(stroke
			(width 0.05715)
			(type default)
		)
		(layer "In2.Cu")
	)
	(gr_line
		(start 37.246306 -151.7777)
		(end 37.24656 -151.7777)
		(stroke
			(width 0.05715)
			(type default)
		)
		(layer "In2.Cu")
	)
	(gr_arc
		(start 37.246306 -149.805136)
		(mid 37.221151 -149.700226)
		(end 37.152326 -149.617176)
		(stroke
			(width 0.05715)
			(type default)
		)
		(layer "In2.Cu")
	)
	(gr_arc
		(start 37.246306 -148.367496)
		(mid 37.221151 -148.262586)
		(end 37.152326 -148.179536)
		(stroke
			(width 0.05715)
			(type default)
		)
		(layer "In2.Cu")
	)
	(gr_arc
		(start 37.246306 -145.779998)
		(mid 37.221151 -145.675088)
		(end 37.152326 -145.592038)
		(stroke
			(width 0.05715)
			(type default)
		)
		(layer "In2.Cu")
	)
	(gr_arc
		(start 37.246306 -144.342358)
		(mid 37.221151 -144.237448)
		(end 37.152326 -144.154398)
		(stroke
			(width 0.05715)
			(type default)
		)
		(layer "In2.Cu")
	)
	(gr_arc
		(start 37.246306 -142.904718)
		(mid 37.221151 -142.799808)
		(end 37.152326 -142.716758)
		(stroke
			(width 0.05715)
			(type default)
		)
		(layer "In2.Cu")
	)
	(gr_arc
		(start 37.246306 -141.467078)
		(mid 37.221151 -141.362168)
		(end 37.152326 -141.279118)
		(stroke
			(width 0.05715)
			(type default)
		)
		(layer "In2.Cu")
	)
	(gr_line
		(start 37.540692 -165.759892)
		(end 37.540946 -165.760146)
		(stroke
			(width 0.05715)
			(type default)
		)
		(layer "In2.Cu")
	)
	(gr_line
		(start 37.551106 -151.4729)
		(end 37.551106 -151.7777)
		(stroke
			(width 0.05715)
			(type default)
		)
		(layer "In2.Cu")
	)
	(gr_line
		(start 37.551106 -149.017736)
		(end 37.551106 -149.497796)
		(stroke
			(width 0.05715)
			(type default)
		)
		(layer "In2.Cu")
	)
	(gr_line
		(start 37.551106 -147.580096)
		(end 37.551106 -148.060156)
		(stroke
			(width 0.05715)
			(type default)
		)
		(layer "In2.Cu")
	)
	(gr_line
		(start 37.551106 -144.992598)
		(end 37.551106 -145.472658)
		(stroke
			(width 0.05715)
			(type default)
		)
		(layer "In2.Cu")
	)
	(gr_line
		(start 37.551106 -143.554958)
		(end 37.551106 -144.035018)
		(stroke
			(width 0.05715)
			(type default)
		)
		(layer "In2.Cu")
	)
	(gr_line
		(start 37.551106 -142.117318)
		(end 37.551106 -142.597378)
		(stroke
			(width 0.05715)
			(type default)
		)
		(layer "In2.Cu")
	)
	(gr_line
		(start 37.551106 -140.679678)
		(end 37.551106 -141.159738)
		(stroke
			(width 0.05715)
			(type default)
		)
		(layer "In2.Cu")
	)
	(gr_line
		(start 39.789354 -154.787092)
		(end 39.7891 -154.787346)
		(stroke
			(width 0.05715)
			(type default)
		)
		(layer "In2.Cu")
	)
	(gr_line
		(start 39.997126 -154.56408)
		(end 40.004746 -154.5717)
		(stroke
			(width 0.05715)
			(type default)
		)
		(layer "In2.Cu")
	)
	(gr_arc
		(start 5.894578 -348.491048)
		(mid 6.470396 -349.08363)
		(end 7.062978 -348.507812)
		(stroke
			(width 0.2)
			(type default)
		)
		(layer "In3.Cu")
	)
	(gr_line
		(start 5.907532 -347.577156)
		(end 5.894578 -348.491048)
		(stroke
			(width 0.2)
			(type default)
		)
		(layer "In3.Cu")
	)
	(gr_line
		(start 6.091936 -121.551954)
		(end 6.1468 -122.41403)
		(stroke
			(width 0.2)
			(type default)
		)
		(layer "In3.Cu")
	)
	(gr_arc
		(start 6.093206 -102.457504)
		(mid 6.679946 -103.044244)
		(end 7.266686 -102.457504)
		(stroke
			(width 0.2)
			(type default)
		)
		(layer "In3.Cu")
	)
	(gr_line
		(start 6.093206 -101.498654)
		(end 6.093206 -102.457504)
		(stroke
			(width 0.2)
			(type default)
		)
		(layer "In3.Cu")
	)
	(gr_arc
		(start 6.093206 -98.457766)
		(mid 6.679946 -99.044506)
		(end 7.266686 -98.457766)
		(stroke
			(width 0.2)
			(type default)
		)
		(layer "In3.Cu")
	)
	(gr_line
		(start 6.093206 -97.498916)
		(end 6.093206 -98.457766)
		(stroke
			(width 0.2)
			(type default)
		)
		(layer "In3.Cu")
	)
	(gr_line
		(start 6.094476 -121.5517)
		(end 6.091936 -121.551954)
		(stroke
			(width 0.2)
			(type default)
		)
		(layer "In3.Cu")
	)
	(gr_line
		(start 6.116574 -107.545378)
		(end 6.148324 -108.408216)
		(stroke
			(width 0.2)
			(type default)
		)
		(layer "In3.Cu")
	)
	(gr_arc
		(start 6.118606 -128.458214)
		(mid 6.705346 -129.044954)
		(end 7.292086 -128.458214)
		(stroke
			(width 0.2)
			(type default)
		)
		(layer "In3.Cu")
	)
	(gr_line
		(start 6.118606 -127.499364)
		(end 6.118606 -128.458214)
		(stroke
			(width 0.2)
			(type default)
		)
		(layer "In3.Cu")
	)
	(gr_line
		(start 6.119114 -107.545378)
		(end 6.116574 -107.545378)
		(stroke
			(width 0.2)
			(type default)
		)
		(layer "In3.Cu")
	)
	(gr_line
		(start 6.140704 -117.514624)
		(end 6.144006 -118.429532)
		(stroke
			(width 0.2)
			(type default)
		)
		(layer "In3.Cu")
	)
	(gr_line
		(start 6.142482 -111.613442)
		(end 6.16966 -112.476788)
		(stroke
			(width 0.2)
			(type default)
		)
		(layer "In3.Cu")
	)
	(gr_arc
		(start 6.144006 -118.429532)
		(mid 6.732778 -119.01424)
		(end 7.317486 -118.425468)
		(stroke
			(width 0.2)
			(type default)
		)
		(layer "In3.Cu")
	)
	(gr_line
		(start 6.1468 -122.41403)
		(end 6.14934 -122.413776)
		(stroke
			(width 0.2)
			(type default)
		)
		(layer "In3.Cu")
	)
	(gr_line
		(start 6.148324 -108.408216)
		(end 6.148578 -108.40847)
		(stroke
			(width 0.2)
			(type default)
		)
		(layer "In3.Cu")
	)
	(gr_line
		(start 6.148578 -108.40847)
		(end 6.150864 -108.40847)
		(stroke
			(width 0.2)
			(type default)
		)
		(layer "In3.Cu")
	)
	(gr_arc
		(start 6.14934 -122.413776)
		(mid 6.771894 -122.962162)
		(end 7.32028 -122.339608)
		(stroke
			(width 0.2)
			(type default)
		)
		(layer "In3.Cu")
	)
	(gr_arc
		(start 6.150864 -108.40847)
		(mid 6.758686 -108.973112)
		(end 7.323328 -108.36529)
		(stroke
			(width 0.2)
			(type default)
		)
		(layer "In3.Cu")
	)
	(gr_arc
		(start 6.164072 -162.459416)
		(mid 6.748272 -163.043616)
		(end 7.332472 -162.459416)
		(stroke
			(width 0.2)
			(type default)
		)
		(layer "In3.Cu")
	)
	(gr_line
		(start 6.164072 -161.5313)
		(end 6.164072 -162.459416)
		(stroke
			(width 0.2)
			(type default)
		)
		(layer "In3.Cu")
	)
	(gr_arc
		(start 6.169406 -134.442708)
		(mid 6.756146 -135.029448)
		(end 7.342886 -134.442708)
		(stroke
			(width 0.2)
			(type default)
		)
		(layer "In3.Cu")
	)
	(gr_line
		(start 6.169406 -133.514592)
		(end 6.169406 -134.442708)
		(stroke
			(width 0.2)
			(type default)
		)
		(layer "In3.Cu")
	)
	(gr_arc
		(start 6.16966 -112.476788)
		(mid 6.774688 -113.044732)
		(end 7.342632 -112.439704)
		(stroke
			(width 0.2)
			(type default)
		)
		(layer "In3.Cu")
	)
	(gr_line
		(start 6.205474 -165.630606)
		(end 6.272022 -166.797228)
		(stroke
			(width 0.2)
			(type default)
		)
		(layer "In3.Cu")
	)
	(gr_line
		(start 6.208014 -165.630352)
		(end 6.205474 -165.630606)
		(stroke
			(width 0.2)
			(type default)
		)
		(layer "In3.Cu")
	)
	(gr_line
		(start 6.21792 -116.441982)
		(end 6.22046 -116.441982)
		(stroke
			(width 0.2)
			(type default)
		)
		(layer "In3.Cu")
	)
	(gr_arc
		(start 6.22046 -116.441982)
		(mid 6.79069 -117.044724)
		(end 7.393432 -116.474494)
		(stroke
			(width 0.2)
			(type default)
		)
		(layer "In3.Cu")
	)
	(gr_line
		(start 6.24332 -115.515644)
		(end 6.21792 -116.441982)
		(stroke
			(width 0.2)
			(type default)
		)
		(layer "In3.Cu")
	)
	(gr_line
		(start 6.24586 -115.515644)
		(end 6.24332 -115.515644)
		(stroke
			(width 0.2)
			(type default)
		)
		(layer "In3.Cu")
	)
	(gr_line
		(start 6.272022 -166.797228)
		(end 6.274562 -166.796974)
		(stroke
			(width 0.2)
			(type default)
		)
		(layer "In3.Cu")
	)
	(gr_arc
		(start 6.274562 -166.796974)
		(mid 6.89102 -167.346884)
		(end 7.44093 -166.730426)
		(stroke
			(width 0.2)
			(type default)
		)
		(layer "In3.Cu")
	)
	(gr_arc
		(start 6.400546 -158.459678)
		(mid 6.984746 -159.043878)
		(end 7.568946 -158.459678)
		(stroke
			(width 0.2)
			(type default)
		)
		(layer "In3.Cu")
	)
	(gr_line
		(start 6.400546 -157.531562)
		(end 6.400546 -158.459678)
		(stroke
			(width 0.2)
			(type default)
		)
		(layer "In3.Cu")
	)
	(gr_arc
		(start 6.445758 -170.459654)
		(mid 7.032498 -171.046394)
		(end 7.619238 -170.459654)
		(stroke
			(width 0.2)
			(type default)
		)
		(layer "In3.Cu")
	)
	(gr_line
		(start 6.445758 -169.531538)
		(end 6.445758 -170.459654)
		(stroke
			(width 0.2)
			(type default)
		)
		(layer "In3.Cu")
	)
	(gr_arc
		(start 6.862318 -398.756378)
		(mid 6.30555 -399.366994)
		(end 6.916166 -399.923762)
		(stroke
			(width 0.2)
			(type default)
		)
		(layer "In3.Cu")
	)
	(gr_line
		(start 6.916166 -399.923762)
		(end 7.77875 -399.884138)
		(stroke
			(width 0.2)
			(type default)
		)
		(layer "In3.Cu")
	)
	(gr_line
		(start 7.003796 -352.786442)
		(end 7.004812 -352.788728)
		(stroke
			(width 0.2)
			(type default)
		)
		(layer "In3.Cu")
	)
	(gr_line
		(start 7.00405 -352.786188)
		(end 7.003796 -352.786442)
		(stroke
			(width 0.2)
			(type default)
		)
		(layer "In3.Cu")
	)
	(gr_arc
		(start 7.004812 -352.788728)
		(mid 6.70054 -353.560934)
		(end 7.47268 -353.864926)
		(stroke
			(width 0.2)
			(type default)
		)
		(layer "In3.Cu")
	)
	(gr_line
		(start 7.062978 -348.507812)
		(end 7.075932 -347.594174)
		(stroke
			(width 0.2)
			(type default)
		)
		(layer "In3.Cu")
	)
	(gr_arc
		(start 7.075932 -347.594174)
		(mid 6.500241 -347.001594)
		(end 5.907532 -347.577156)
		(stroke
			(width 0.2)
			(type default)
		)
		(layer "In3.Cu")
	)
	(gr_arc
		(start 7.215886 -413.544512)
		(mid 7.007016 -414.313851)
		(end 7.778242 -414.516062)
		(stroke
			(width 0.2)
			(type default)
		)
		(layer "In3.Cu")
	)
	(gr_line
		(start 7.249922 -422.467532)
		(end 8.113014 -422.489884)
		(stroke
			(width 0.2)
			(type default)
		)
		(layer "In3.Cu")
	)
	(gr_line
		(start 7.249922 -422.464992)
		(end 7.249922 -422.467532)
		(stroke
			(width 0.2)
			(type default)
		)
		(layer "In3.Cu")
	)
	(gr_line
		(start 7.265162 -368.402616)
		(end 8.127746 -368.441224)
		(stroke
			(width 0.2)
			(type default)
		)
		(layer "In3.Cu")
	)
	(gr_arc
		(start 7.265416 -121.477532)
		(mid 6.642862 -120.929146)
		(end 6.094476 -121.5517)
		(stroke
			(width 0.2)
			(type default)
		)
		(layer "In3.Cu")
	)
	(gr_line
		(start 7.266686 -102.457504)
		(end 7.266686 -101.498908)
		(stroke
			(width 0.2)
			(type default)
		)
		(layer "In3.Cu")
	)
	(gr_arc
		(start 7.266686 -101.498908)
		(mid 6.680073 -100.911914)
		(end 6.093206 -101.498654)
		(stroke
			(width 0.2)
			(type default)
		)
		(layer "In3.Cu")
	)
	(gr_line
		(start 7.266686 -98.457766)
		(end 7.266686 -97.49917)
		(stroke
			(width 0.2)
			(type default)
		)
		(layer "In3.Cu")
	)
	(gr_arc
		(start 7.266686 -97.49917)
		(mid 6.680073 -96.912176)
		(end 6.093206 -97.498916)
		(stroke
			(width 0.2)
			(type default)
		)
		(layer "In3.Cu")
	)
	(gr_line
		(start 7.267702 -121.477278)
		(end 7.265416 -121.477532)
		(stroke
			(width 0.2)
			(type default)
		)
		(layer "In3.Cu")
	)
	(gr_line
		(start 7.267956 -121.477532)
		(end 7.267702 -121.477278)
		(stroke
			(width 0.2)
			(type default)
		)
		(layer "In3.Cu")
	)
	(gr_arc
		(start 7.278878 -421.34282)
		(mid 6.703314 -421.889428)
		(end 7.249922 -422.464992)
		(stroke
			(width 0.2)
			(type default)
		)
		(layer "In3.Cu")
	)
	(gr_line
		(start 7.278878 -421.34028)
		(end 7.278878 -421.34282)
		(stroke
			(width 0.2)
			(type default)
		)
		(layer "In3.Cu")
	)
	(gr_arc
		(start 7.291578 -107.502198)
		(mid 6.683756 -106.937556)
		(end 6.119114 -107.545378)
		(stroke
			(width 0.2)
			(type default)
		)
		(layer "In3.Cu")
	)
	(gr_line
		(start 7.292086 -128.458214)
		(end 7.292086 -127.499618)
		(stroke
			(width 0.2)
			(type default)
		)
		(layer "In3.Cu")
	)
	(gr_arc
		(start 7.292086 -127.499618)
		(mid 6.705473 -126.912624)
		(end 6.118606 -127.499364)
		(stroke
			(width 0.2)
			(type default)
		)
		(layer "In3.Cu")
	)
	(gr_line
		(start 7.294118 -107.502198)
		(end 7.291578 -107.502198)
		(stroke
			(width 0.2)
			(type default)
		)
		(layer "In3.Cu")
	)
	(gr_arc
		(start 7.312914 -367.331752)
		(mid 6.753606 -367.843308)
		(end 7.265162 -368.402616)
		(stroke
			(width 0.2)
			(type default)
		)
		(layer "In3.Cu")
	)
	(gr_arc
		(start 7.314184 -117.510814)
		(mid 6.725539 -116.926106)
		(end 6.140704 -117.514624)
		(stroke
			(width 0.2)
			(type default)
		)
		(layer "In3.Cu")
	)
	(gr_arc
		(start 7.315454 -111.576612)
		(mid 6.710553 -111.008664)
		(end 6.142482 -111.613442)
		(stroke
			(width 0.2)
			(type default)
		)
		(layer "In3.Cu")
	)
	(gr_line
		(start 7.317486 -118.425468)
		(end 7.314184 -117.510814)
		(stroke
			(width 0.2)
			(type default)
		)
		(layer "In3.Cu")
	)
	(gr_line
		(start 7.32028 -122.339608)
		(end 7.32282 -122.339354)
		(stroke
			(width 0.2)
			(type default)
		)
		(layer "In3.Cu")
	)
	(gr_line
		(start 7.32282 -122.339354)
		(end 7.267956 -121.477532)
		(stroke
			(width 0.2)
			(type default)
		)
		(layer "In3.Cu")
	)
	(gr_line
		(start 7.323328 -108.36529)
		(end 7.325868 -108.36529)
		(stroke
			(width 0.2)
			(type default)
		)
		(layer "In3.Cu")
	)
	(gr_line
		(start 7.325868 -108.36529)
		(end 7.294118 -107.502198)
		(stroke
			(width 0.2)
			(type default)
		)
		(layer "In3.Cu")
	)
	(gr_line
		(start 7.332472 -162.459416)
		(end 7.332472 -161.531554)
		(stroke
			(width 0.2)
			(type default)
		)
		(layer "In3.Cu")
	)
	(gr_arc
		(start 7.332472 -161.531554)
		(mid 6.748399 -160.9471)
		(end 6.164072 -161.5313)
		(stroke
			(width 0.2)
			(type default)
		)
		(layer "In3.Cu")
	)
	(gr_line
		(start 7.340346 -410.396436)
		(end 8.203946 -410.396436)
		(stroke
			(width 0.2)
			(type default)
		)
		(layer "In3.Cu")
	)
	(gr_arc
		(start 7.340346 -409.273756)
		(mid 6.779006 -409.835096)
		(end 7.340346 -410.396436)
		(stroke
			(width 0.2)
			(type default)
		)
		(layer "In3.Cu")
	)
	(gr_line
		(start 7.3406 -409.273756)
		(end 7.340346 -409.273756)
		(stroke
			(width 0.2)
			(type default)
		)
		(layer "In3.Cu")
	)
	(gr_line
		(start 7.342632 -112.439704)
		(end 7.315454 -111.576612)
		(stroke
			(width 0.2)
			(type default)
		)
		(layer "In3.Cu")
	)
	(gr_line
		(start 7.342886 -134.442708)
		(end 7.342886 -133.514846)
		(stroke
			(width 0.2)
			(type default)
		)
		(layer "In3.Cu")
	)
	(gr_arc
		(start 7.342886 -133.514846)
		(mid 6.756273 -132.927852)
		(end 6.169406 -133.514592)
		(stroke
			(width 0.2)
			(type default)
		)
		(layer "In3.Cu")
	)
	(gr_arc
		(start 7.351776 -357.949754)
		(mid 6.7818 -358.54767)
		(end 7.379716 -359.117646)
		(stroke
			(width 0.2)
			(type default)
		)
		(layer "In3.Cu")
	)
	(gr_line
		(start 7.351776 -357.947214)
		(end 7.351776 -357.949754)
		(stroke
			(width 0.2)
			(type default)
		)
		(layer "In3.Cu")
	)
	(gr_line
		(start 7.358888 -424.590464)
		(end 8.22071 -424.642788)
		(stroke
			(width 0.2)
			(type default)
		)
		(layer "In3.Cu")
	)
	(gr_line
		(start 7.359142 -424.587924)
		(end 7.358888 -424.590464)
		(stroke
			(width 0.2)
			(type default)
		)
		(layer "In3.Cu")
	)
	(gr_arc
		(start 7.374382 -165.563804)
		(mid 6.757924 -165.013894)
		(end 6.208014 -165.630352)
		(stroke
			(width 0.2)
			(type default)
		)
		(layer "In3.Cu")
	)
	(gr_line
		(start 7.375398 -363.918246)
		(end 7.376922 -363.920278)
		(stroke
			(width 0.2)
			(type default)
		)
		(layer "In3.Cu")
	)
	(gr_line
		(start 7.376668 -165.563804)
		(end 7.374382 -165.563804)
		(stroke
			(width 0.2)
			(type default)
		)
		(layer "In3.Cu")
	)
	(gr_arc
		(start 7.376922 -363.920278)
		(mid 7.291324 -364.745524)
		(end 8.11657 -364.831122)
		(stroke
			(width 0.2)
			(type default)
		)
		(layer "In3.Cu")
	)
	(gr_line
		(start 7.376922 -165.563804)
		(end 7.376668 -165.563804)
		(stroke
			(width 0.2)
			(type default)
		)
		(layer "In3.Cu")
	)
	(gr_line
		(start 7.379716 -359.120186)
		(end 8.25627 -359.099358)
		(stroke
			(width 0.2)
			(type default)
		)
		(layer "In3.Cu")
	)
	(gr_line
		(start 7.379716 -359.117646)
		(end 7.379716 -359.120186)
		(stroke
			(width 0.2)
			(type default)
		)
		(layer "In3.Cu")
	)
	(gr_line
		(start 7.393432 -116.474494)
		(end 7.395972 -116.474494)
		(stroke
			(width 0.2)
			(type default)
		)
		(layer "In3.Cu")
	)
	(gr_line
		(start 7.395972 -116.474494)
		(end 7.421372 -115.54841)
		(stroke
			(width 0.2)
			(type default)
		)
		(layer "In3.Cu")
	)
	(gr_arc
		(start 7.418832 -115.548156)
		(mid 6.848602 -114.945414)
		(end 6.24586 -115.515644)
		(stroke
			(width 0.2)
			(type default)
		)
		(layer "In3.Cu")
	)
	(gr_line
		(start 7.421118 -115.548156)
		(end 7.418832 -115.548156)
		(stroke
			(width 0.2)
			(type default)
		)
		(layer "In3.Cu")
	)
	(gr_line
		(start 7.421372 -115.54841)
		(end 7.421118 -115.548156)
		(stroke
			(width 0.2)
			(type default)
		)
		(layer "In3.Cu")
	)
	(gr_arc
		(start 7.423658 -423.518076)
		(mid 6.856476 -424.020742)
		(end 7.359142 -424.587924)
		(stroke
			(width 0.2)
			(type default)
		)
		(layer "In3.Cu")
	)
	(gr_line
		(start 7.423912 -423.515536)
		(end 7.423658 -423.518076)
		(stroke
			(width 0.2)
			(type default)
		)
		(layer "In3.Cu")
	)
	(gr_line
		(start 7.44093 -166.730426)
		(end 7.44347 -166.730172)
		(stroke
			(width 0.2)
			(type default)
		)
		(layer "In3.Cu")
	)
	(gr_line
		(start 7.44347 -166.730172)
		(end 7.376922 -165.563804)
		(stroke
			(width 0.2)
			(type default)
		)
		(layer "In3.Cu")
	)
	(gr_line
		(start 7.47268 -353.864926)
		(end 7.473696 -353.867212)
		(stroke
			(width 0.2)
			(type default)
		)
		(layer "In3.Cu")
	)
	(gr_line
		(start 7.473696 -353.867212)
		(end 8.447532 -353.443794)
		(stroke
			(width 0.2)
			(type default)
		)
		(layer "In3.Cu")
	)
	(gr_line
		(start 7.516622 -418.417248)
		(end 8.380222 -418.429694)
		(stroke
			(width 0.2)
			(type default)
		)
		(layer "In3.Cu")
	)
	(gr_arc
		(start 7.53364 -417.243768)
		(mid 6.93852 -417.821999)
		(end 7.516622 -418.417248)
		(stroke
			(width 0.2)
			(type default)
		)
		(layer "In3.Cu")
	)
	(gr_arc
		(start 7.566406 -386.461)
		(mid 8.127746 -387.02234)
		(end 8.689086 -386.461)
		(stroke
			(width 0.2)
			(type default)
		)
		(layer "In3.Cu")
	)
	(gr_line
		(start 7.566406 -385.532884)
		(end 7.566406 -386.461)
		(stroke
			(width 0.2)
			(type default)
		)
		(layer "In3.Cu")
	)
	(gr_line
		(start 7.568946 -158.459678)
		(end 7.568946 -157.531816)
		(stroke
			(width 0.2)
			(type default)
		)
		(layer "In3.Cu")
	)
	(gr_arc
		(start 7.568946 -157.531816)
		(mid 6.984873 -156.947362)
		(end 6.400546 -157.531562)
		(stroke
			(width 0.2)
			(type default)
		)
		(layer "In3.Cu")
	)
	(gr_line
		(start 7.619238 -170.459654)
		(end 7.619238 -169.531792)
		(stroke
			(width 0.2)
			(type default)
		)
		(layer "In3.Cu")
	)
	(gr_arc
		(start 7.619238 -169.531792)
		(mid 7.032625 -168.944798)
		(end 6.445758 -169.531538)
		(stroke
			(width 0.2)
			(type default)
		)
		(layer "In3.Cu")
	)
	(gr_line
		(start 7.623048 -384.608832)
		(end 8.485886 -384.647186)
		(stroke
			(width 0.2)
			(type default)
		)
		(layer "In3.Cu")
	)
	(gr_arc
		(start 7.675626 -383.436368)
		(mid 7.063238 -383.996311)
		(end 7.623048 -384.608832)
		(stroke
			(width 0.2)
			(type default)
		)
		(layer "In3.Cu")
	)
	(gr_line
		(start 7.689088 -372.065804)
		(end 8.587486 -372.107206)
		(stroke
			(width 0.2)
			(type default)
		)
		(layer "In3.Cu")
	)
	(gr_line
		(start 7.725156 -398.716754)
		(end 6.862318 -398.756378)
		(stroke
			(width 0.2)
			(type default)
		)
		(layer "In3.Cu")
	)
	(gr_arc
		(start 7.74319 -370.89334)
		(mid 7.13004 -371.452521)
		(end 7.689088 -372.065804)
		(stroke
			(width 0.2)
			(type default)
		)
		(layer "In3.Cu")
	)
	(gr_line
		(start 7.746746 -380.96444)
		(end 8.660892 -380.96444)
		(stroke
			(width 0.2)
			(type default)
		)
		(layer "In3.Cu")
	)
	(gr_arc
		(start 7.746746 -379.79096)
		(mid 7.160006 -380.3777)
		(end 7.746746 -380.96444)
		(stroke
			(width 0.2)
			(type default)
		)
		(layer "In3.Cu")
	)
	(gr_line
		(start 7.778242 -414.516062)
		(end 8.581898 -414.041336)
		(stroke
			(width 0.2)
			(type default)
		)
		(layer "In3.Cu")
	)
	(gr_arc
		(start 7.77875 -399.884138)
		(mid 8.335766 -399.273649)
		(end 7.725156 -398.716754)
		(stroke
			(width 0.2)
			(type default)
		)
		(layer "In3.Cu")
	)
	(gr_line
		(start 7.817104 -375.905268)
		(end 7.817358 -375.907808)
		(stroke
			(width 0.2)
			(type default)
		)
		(layer "In3.Cu")
	)
	(gr_arc
		(start 7.817358 -375.907808)
		(mid 7.340854 -376.497088)
		(end 7.930134 -376.973592)
		(stroke
			(width 0.2)
			(type default)
		)
		(layer "In3.Cu")
	)
	(gr_line
		(start 7.930134 -376.973592)
		(end 7.930388 -376.976132)
		(stroke
			(width 0.2)
			(type default)
		)
		(layer "In3.Cu")
	)
	(gr_line
		(start 7.930388 -376.976132)
		(end 8.810498 -376.882914)
		(stroke
			(width 0.2)
			(type default)
		)
		(layer "In3.Cu")
	)
	(gr_line
		(start 7.977632 -352.36277)
		(end 7.00405 -352.786188)
		(stroke
			(width 0.2)
			(type default)
		)
		(layer "In3.Cu")
	)
	(gr_line
		(start 7.978648 -352.365056)
		(end 7.977632 -352.36277)
		(stroke
			(width 0.2)
			(type default)
		)
		(layer "In3.Cu")
	)
	(gr_line
		(start 8.010906 -413.074612)
		(end 7.215886 -413.544512)
		(stroke
			(width 0.2)
			(type default)
		)
		(layer "In3.Cu")
	)
	(gr_line
		(start 8.062976 -363.359954)
		(end 7.375398 -363.918246)
		(stroke
			(width 0.2)
			(type default)
		)
		(layer "In3.Cu")
	)
	(gr_line
		(start 8.0645 -363.361986)
		(end 8.062976 -363.359954)
		(stroke
			(width 0.2)
			(type default)
		)
		(layer "In3.Cu")
	)
	(gr_line
		(start 8.113014 -422.489884)
		(end 8.113268 -422.48963)
		(stroke
			(width 0.2)
			(type default)
		)
		(layer "In3.Cu")
	)
	(gr_line
		(start 8.113268 -422.48963)
		(end 8.113268 -422.487344)
		(stroke
			(width 0.2)
			(type default)
		)
		(layer "In3.Cu")
	)
	(gr_arc
		(start 8.113268 -422.487344)
		(mid 8.688832 -421.940736)
		(end 8.142224 -421.365172)
		(stroke
			(width 0.2)
			(type default)
		)
		(layer "In3.Cu")
	)
	(gr_line
		(start 8.11657 -364.831122)
		(end 8.118094 -364.833154)
		(stroke
			(width 0.2)
			(type default)
		)
		(layer "In3.Cu")
	)
	(gr_line
		(start 8.118094 -364.833154)
		(end 8.805672 -364.275116)
		(stroke
			(width 0.2)
			(type default)
		)
		(layer "In3.Cu")
	)
	(gr_arc
		(start 8.127746 -368.441224)
		(mid 8.687314 -367.929795)
		(end 8.175752 -367.37036)
		(stroke
			(width 0.2)
			(type default)
		)
		(layer "In3.Cu")
	)
	(gr_line
		(start 8.142224 -421.365172)
		(end 8.142224 -421.362632)
		(stroke
			(width 0.2)
			(type default)
		)
		(layer "In3.Cu")
	)
	(gr_line
		(start 8.142224 -421.362632)
		(end 7.278878 -421.34028)
		(stroke
			(width 0.2)
			(type default)
		)
		(layer "In3.Cu")
	)
	(gr_line
		(start 8.175752 -367.37036)
		(end 7.312914 -367.331752)
		(stroke
			(width 0.2)
			(type default)
		)
		(layer "In3.Cu")
	)
	(gr_arc
		(start 8.203946 -410.396436)
		(mid 8.765286 -409.835096)
		(end 8.203946 -409.273756)
		(stroke
			(width 0.2)
			(type default)
		)
		(layer "In3.Cu")
	)
	(gr_line
		(start 8.203946 -409.273756)
		(end 7.3406 -409.273756)
		(stroke
			(width 0.2)
			(type default)
		)
		(layer "In3.Cu")
	)
	(gr_line
		(start 8.22071 -424.642788)
		(end 8.220964 -424.642534)
		(stroke
			(width 0.2)
			(type default)
		)
		(layer "In3.Cu")
	)
	(gr_line
		(start 8.220964 -424.642534)
		(end 8.221218 -424.640248)
		(stroke
			(width 0.2)
			(type default)
		)
		(layer "In3.Cu")
	)
	(gr_arc
		(start 8.221218 -424.640248)
		(mid 8.7884 -424.137582)
		(end 8.285734 -423.5704)
		(stroke
			(width 0.2)
			(type default)
		)
		(layer "In3.Cu")
	)
	(gr_line
		(start 8.228584 -357.928926)
		(end 8.228584 -357.926386)
		(stroke
			(width 0.2)
			(type default)
		)
		(layer "In3.Cu")
	)
	(gr_line
		(start 8.228584 -357.926386)
		(end 7.351776 -357.947214)
		(stroke
			(width 0.2)
			(type default)
		)
		(layer "In3.Cu")
	)
	(gr_line
		(start 8.25627 -359.099358)
		(end 8.256524 -359.099104)
		(stroke
			(width 0.2)
			(type default)
		)
		(layer "In3.Cu")
	)
	(gr_line
		(start 8.256524 -359.099104)
		(end 8.256524 -359.096818)
		(stroke
			(width 0.2)
			(type default)
		)
		(layer "In3.Cu")
	)
	(gr_arc
		(start 8.256524 -359.096818)
		(mid 8.8265 -358.498902)
		(end 8.228584 -357.928926)
		(stroke
			(width 0.2)
			(type default)
		)
		(layer "In3.Cu")
	)
	(gr_line
		(start 8.285734 -423.5704)
		(end 8.285988 -423.56786)
		(stroke
			(width 0.2)
			(type default)
		)
		(layer "In3.Cu")
	)
	(gr_line
		(start 8.285988 -423.56786)
		(end 7.423912 -423.515536)
		(stroke
			(width 0.2)
			(type default)
		)
		(layer "In3.Cu")
	)
	(gr_arc
		(start 8.380222 -418.429694)
		(mid 8.975344 -417.851336)
		(end 8.396986 -417.256214)
		(stroke
			(width 0.2)
			(type default)
		)
		(layer "In3.Cu")
	)
	(gr_line
		(start 8.396986 -417.256214)
		(end 7.53364 -417.243768)
		(stroke
			(width 0.2)
			(type default)
		)
		(layer "In3.Cu")
	)
	(gr_arc
		(start 8.446516 -353.441508)
		(mid 8.750808 -352.669348)
		(end 7.978648 -352.365056)
		(stroke
			(width 0.2)
			(type default)
		)
		(layer "In3.Cu")
	)
	(gr_line
		(start 8.447532 -353.443794)
		(end 8.446516 -353.441508)
		(stroke
			(width 0.2)
			(type default)
		)
		(layer "In3.Cu")
	)
	(gr_arc
		(start 8.485886 -384.647186)
		(mid 9.09828 -384.087116)
		(end 8.53821 -383.474722)
		(stroke
			(width 0.2)
			(type default)
		)
		(layer "In3.Cu")
	)
	(gr_line
		(start 8.53821 -383.474722)
		(end 7.675626 -383.436368)
		(stroke
			(width 0.2)
			(type default)
		)
		(layer "In3.Cu")
	)
	(gr_arc
		(start 8.581898 -414.041336)
		(mid 8.779764 -413.272478)
		(end 8.010906 -413.074612)
		(stroke
			(width 0.2)
			(type default)
		)
		(layer "In3.Cu")
	)
	(gr_arc
		(start 8.587486 -372.107206)
		(mid 9.200642 -371.547898)
		(end 8.641334 -370.934742)
		(stroke
			(width 0.2)
			(type default)
		)
		(layer "In3.Cu")
	)
	(gr_line
		(start 8.641334 -370.934742)
		(end 7.74319 -370.89334)
		(stroke
			(width 0.2)
			(type default)
		)
		(layer "In3.Cu")
	)
	(gr_line
		(start 8.660892 -380.96444)
		(end 8.661146 -380.96444)
		(stroke
			(width 0.2)
			(type default)
		)
		(layer "In3.Cu")
	)
	(gr_arc
		(start 8.661146 -380.96444)
		(mid 9.247886 -380.3777)
		(end 8.661146 -379.79096)
		(stroke
			(width 0.2)
			(type default)
		)
		(layer "In3.Cu")
	)
	(gr_line
		(start 8.661146 -379.79096)
		(end 7.746746 -379.79096)
		(stroke
			(width 0.2)
			(type default)
		)
		(layer "In3.Cu")
	)
	(gr_arc
		(start 8.684006 -132.4737)
		(mid 9.270746 -133.06044)
		(end 9.857486 -132.4737)
		(stroke
			(width 0.2)
			(type default)
		)
		(layer "In3.Cu")
	)
	(gr_line
		(start 8.684006 -131.51485)
		(end 8.684006 -132.4737)
		(stroke
			(width 0.2)
			(type default)
		)
		(layer "In3.Cu")
	)
	(gr_line
		(start 8.689086 -386.461)
		(end 8.689086 -385.533138)
		(stroke
			(width 0.2)
			(type default)
		)
		(layer "In3.Cu")
	)
	(gr_arc
		(start 8.689086 -385.533138)
		(mid 8.127873 -384.971544)
		(end 7.566406 -385.532884)
		(stroke
			(width 0.2)
			(type default)
		)
		(layer "In3.Cu")
	)
	(gr_line
		(start 8.697468 -375.81205)
		(end 7.817104 -375.905268)
		(stroke
			(width 0.2)
			(type default)
		)
		(layer "In3.Cu")
	)
	(gr_line
		(start 8.697722 -375.81459)
		(end 8.697468 -375.81205)
		(stroke
			(width 0.2)
			(type default)
		)
		(layer "In3.Cu")
	)
	(gr_arc
		(start 8.804148 -364.27283)
		(mid 8.889746 -363.447584)
		(end 8.0645 -363.361986)
		(stroke
			(width 0.2)
			(type default)
		)
		(layer "In3.Cu")
	)
	(gr_line
		(start 8.805672 -364.275116)
		(end 8.805672 -364.274608)
		(stroke
			(width 0.2)
			(type default)
		)
		(layer "In3.Cu")
	)
	(gr_line
		(start 8.805672 -364.274608)
		(end 8.804148 -364.27283)
		(stroke
			(width 0.2)
			(type default)
		)
		(layer "In3.Cu")
	)
	(gr_line
		(start 8.810498 -376.882914)
		(end 8.810752 -376.88266)
		(stroke
			(width 0.2)
			(type default)
		)
		(layer "In3.Cu")
	)
	(gr_arc
		(start 8.810498 -376.880374)
		(mid 9.287002 -376.291094)
		(end 8.697722 -375.81459)
		(stroke
			(width 0.2)
			(type default)
		)
		(layer "In3.Cu")
	)
	(gr_line
		(start 8.810752 -376.88266)
		(end 8.810498 -376.880374)
		(stroke
			(width 0.2)
			(type default)
		)
		(layer "In3.Cu")
	)
	(gr_line
		(start 9.857486 -132.4737)
		(end 9.857486 -131.515104)
		(stroke
			(width 0.2)
			(type default)
		)
		(layer "In3.Cu")
	)
	(gr_arc
		(start 9.857486 -131.515104)
		(mid 9.270873 -130.92811)
		(end 8.684006 -131.51485)
		(stroke
			(width 0.2)
			(type default)
		)
		(layer "In3.Cu")
	)
	(gr_arc
		(start 11.066018 -439.032904)
		(mid 11.652631 -439.619898)
		(end 12.239498 -439.033158)
		(stroke
			(width 0.2)
			(type default)
		)
		(layer "In3.Cu")
	)
	(gr_line
		(start 11.066018 -438.105042)
		(end 11.066018 -439.032904)
		(stroke
			(width 0.2)
			(type default)
		)
		(layer "In3.Cu")
	)
	(gr_line
		(start 11.0744 -441.81014)
		(end 11.937746 -441.81014)
		(stroke
			(width 0.2)
			(type default)
		)
		(layer "In3.Cu")
	)
	(gr_arc
		(start 11.0744 -440.63666)
		(mid 10.48766 -441.2234)
		(end 11.0744 -441.81014)
		(stroke
			(width 0.2)
			(type default)
		)
		(layer "In3.Cu")
	)
	(gr_line
		(start 11.937746 -441.81014)
		(end 11.938 -441.81014)
		(stroke
			(width 0.2)
			(type default)
		)
		(layer "In3.Cu")
	)
	(gr_arc
		(start 11.938 -441.81014)
		(mid 12.52474 -441.2234)
		(end 11.938 -440.63666)
		(stroke
			(width 0.2)
			(type default)
		)
		(layer "In3.Cu")
	)
	(gr_line
		(start 11.938 -440.63666)
		(end 11.0744 -440.63666)
		(stroke
			(width 0.2)
			(type default)
		)
		(layer "In3.Cu")
	)
	(gr_arc
		(start 12.192254 -177.578004)
		(mid 12.757404 -178.180746)
		(end 13.360146 -177.615596)
		(stroke
			(width 0.2)
			(type default)
		)
		(layer "In3.Cu")
	)
	(gr_line
		(start 12.220194 -176.714658)
		(end 12.192254 -177.578004)
		(stroke
			(width 0.2)
			(type default)
		)
		(layer "In3.Cu")
	)
	(gr_line
		(start 12.239498 -439.033158)
		(end 12.239498 -438.105042)
		(stroke
			(width 0.2)
			(type default)
		)
		(layer "In3.Cu")
	)
	(gr_arc
		(start 12.239498 -438.105042)
		(mid 11.652758 -437.518302)
		(end 11.066018 -438.105042)
		(stroke
			(width 0.2)
			(type default)
		)
		(layer "In3.Cu")
	)
	(gr_line
		(start 13.360146 -177.615596)
		(end 13.388086 -176.752504)
		(stroke
			(width 0.2)
			(type default)
		)
		(layer "In3.Cu")
	)
	(gr_arc
		(start 13.388086 -176.752504)
		(mid 12.823063 -176.149766)
		(end 12.220194 -176.714658)
		(stroke
			(width 0.2)
			(type default)
		)
		(layer "In3.Cu")
	)
	(gr_arc
		(start 14.653006 -136.536938)
		(mid 15.238984 -137.12444)
		(end 15.826486 -136.538462)
		(stroke
			(width 0.2)
			(type default)
		)
		(layer "In3.Cu")
	)
	(gr_line
		(start 14.654022 -135.673338)
		(end 14.653006 -136.536938)
		(stroke
			(width 0.2)
			(type default)
		)
		(layer "In3.Cu")
	)
	(gr_arc
		(start 15.770098 -120.508268)
		(mid 16.355822 -121.096024)
		(end 16.943578 -120.5103)
		(stroke
			(width 0.2)
			(type default)
		)
		(layer "In3.Cu")
	)
	(gr_line
		(start 15.771622 -119.644668)
		(end 15.770098 -120.508268)
		(stroke
			(width 0.2)
			(type default)
		)
		(layer "In3.Cu")
	)
	(gr_line
		(start 15.826486 -136.538462)
		(end 15.827502 -135.675116)
		(stroke
			(width 0.2)
			(type default)
		)
		(layer "In3.Cu")
	)
	(gr_arc
		(start 15.827502 -135.675116)
		(mid 15.241651 -135.087614)
		(end 14.654022 -135.673338)
		(stroke
			(width 0.2)
			(type default)
		)
		(layer "In3.Cu")
	)
	(gr_line
		(start 16.943578 -120.5103)
		(end 16.945102 -119.646954)
		(stroke
			(width 0.2)
			(type default)
		)
		(layer "In3.Cu")
	)
	(gr_arc
		(start 16.945102 -119.646954)
		(mid 16.359505 -119.059198)
		(end 15.771622 -119.644668)
		(stroke
			(width 0.2)
			(type default)
		)
		(layer "In3.Cu")
	)
	(gr_line
		(start 18.922746 -493.1537)
		(end 20.954746 -495.1857)
		(stroke
			(width 0.381)
			(type default)
		)
		(layer "In3.Cu")
	)
	(gr_line
		(start 18.922746 -465.8487)
		(end 18.922746 -493.1537)
		(stroke
			(width 0.381)
			(type default)
		)
		(layer "In3.Cu")
	)
	(gr_line
		(start 20.954746 -495.1857)
		(end 48.894746 -495.1857)
		(stroke
			(width 0.381)
			(type default)
		)
		(layer "In3.Cu")
	)
	(gr_line
		(start 21.053044 -444.232792)
		(end 21.090382 -445.095376)
		(stroke
			(width 0.2)
			(type default)
		)
		(layer "In3.Cu")
	)
	(gr_arc
		(start 21.090382 -445.095376)
		(mid 21.701887 -445.656457)
		(end 22.262846 -445.04483)
		(stroke
			(width 0.2)
			(type default)
		)
		(layer "In3.Cu")
	)
	(gr_arc
		(start 21.26107 -238.799624)
		(mid 21.774529 -239.451657)
		(end 22.426422 -238.938054)
		(stroke
			(width 0.2)
			(type default)
		)
		(layer "In3.Cu")
	)
	(gr_arc
		(start 21.307806 -136.15035)
		(mid 21.894546 -136.73709)
		(end 22.481286 -136.15035)
		(stroke
			(width 0.2)
			(type default)
		)
		(layer "In3.Cu")
	)
	(gr_line
		(start 21.307806 -135.1915)
		(end 21.307806 -136.15035)
		(stroke
			(width 0.2)
			(type default)
		)
		(layer "In3.Cu")
	)
	(gr_line
		(start 21.335746 -463.4357)
		(end 18.922746 -465.8487)
		(stroke
			(width 0.381)
			(type default)
		)
		(layer "In3.Cu")
	)
	(gr_line
		(start 21.36267 -237.941612)
		(end 21.26107 -238.799624)
		(stroke
			(width 0.2)
			(type default)
		)
		(layer "In3.Cu")
	)
	(gr_line
		(start 21.411184 -32.240474)
		(end 21.487384 -33.209738)
		(stroke
			(width 0.2)
			(type default)
		)
		(layer "In3.Cu")
	)
	(gr_arc
		(start 21.48586 -342.045036)
		(mid 22.069933 -342.62949)
		(end 22.65426 -342.04529)
		(stroke
			(width 0.2)
			(type default)
		)
		(layer "In3.Cu")
	)
	(gr_line
		(start 21.48586 -341.08644)
		(end 21.48586 -342.045036)
		(stroke
			(width 0.2)
			(type default)
		)
		(layer "In3.Cu")
	)
	(gr_arc
		(start 21.487384 -33.209738)
		(mid 22.118192 -33.74897)
		(end 22.657308 -33.118044)
		(stroke
			(width 0.2)
			(type default)
		)
		(layer "In3.Cu")
	)
	(gr_arc
		(start 22.225508 -444.181992)
		(mid 21.613876 -443.62116)
		(end 21.053044 -444.232792)
		(stroke
			(width 0.2)
			(type default)
		)
		(layer "In3.Cu")
	)
	(gr_line
		(start 22.262846 -445.04483)
		(end 22.225508 -444.181992)
		(stroke
			(width 0.2)
			(type default)
		)
		(layer "In3.Cu")
	)
	(gr_line
		(start 22.426422 -238.938054)
		(end 22.528022 -238.079788)
		(stroke
			(width 0.2)
			(type default)
		)
		(layer "In3.Cu")
	)
	(gr_line
		(start 22.481286 -136.15035)
		(end 22.481286 -135.191754)
		(stroke
			(width 0.2)
			(type default)
		)
		(layer "In3.Cu")
	)
	(gr_arc
		(start 22.481286 -135.191754)
		(mid 21.894673 -134.60476)
		(end 21.307806 -135.1915)
		(stroke
			(width 0.2)
			(type default)
		)
		(layer "In3.Cu")
	)
	(gr_arc
		(start 22.528022 -238.079788)
		(mid 22.014434 -237.428024)
		(end 21.36267 -237.941612)
		(stroke
			(width 0.2)
			(type default)
		)
		(layer "In3.Cu")
	)
	(gr_arc
		(start 22.581108 -32.148526)
		(mid 21.950172 -31.609538)
		(end 21.411184 -32.240474)
		(stroke
			(width 0.2)
			(type default)
		)
		(layer "In3.Cu")
	)
	(gr_line
		(start 22.65426 -342.04529)
		(end 22.65426 -341.08644)
		(stroke
			(width 0.2)
			(type default)
		)
		(layer "In3.Cu")
	)
	(gr_arc
		(start 22.65426 -341.08644)
		(mid 22.07006 -340.50224)
		(end 21.48586 -341.08644)
		(stroke
			(width 0.2)
			(type default)
		)
		(layer "In3.Cu")
	)
	(gr_line
		(start 22.657308 -33.118044)
		(end 22.581108 -32.148526)
		(stroke
			(width 0.2)
			(type default)
		)
		(layer "In3.Cu")
	)
	(gr_arc
		(start 24.052022 -349.878904)
		(mid 24.606504 -350.496378)
		(end 25.223978 -349.941896)
		(stroke
			(width 0.2)
			(type default)
		)
		(layer "In3.Cu")
	)
	(gr_line
		(start 24.110188 -348.796102)
		(end 24.052022 -349.878904)
		(stroke
			(width 0.2)
			(type default)
		)
		(layer "In3.Cu")
	)
	(gr_line
		(start 24.257 -130.99034)
		(end 25.1206 -130.99034)
		(stroke
			(width 0.2)
			(type default)
		)
		(layer "In3.Cu")
	)
	(gr_arc
		(start 24.257 -129.81686)
		(mid 23.67026 -130.4036)
		(end 24.257 -130.99034)
		(stroke
			(width 0.2)
			(type default)
		)
		(layer "In3.Cu")
	)
	(gr_arc
		(start 25.1206 -130.99034)
		(mid 25.70734 -130.4036)
		(end 25.1206 -129.81686)
		(stroke
			(width 0.2)
			(type default)
		)
		(layer "In3.Cu")
	)
	(gr_line
		(start 25.1206 -129.81686)
		(end 24.257 -129.81686)
		(stroke
			(width 0.2)
			(type default)
		)
		(layer "In3.Cu")
	)
	(gr_line
		(start 25.223978 -349.941896)
		(end 25.282144 -348.859348)
		(stroke
			(width 0.2)
			(type default)
		)
		(layer "In3.Cu")
	)
	(gr_arc
		(start 25.282144 -348.859348)
		(mid 24.727789 -348.241881)
		(end 24.110188 -348.796102)
		(stroke
			(width 0.2)
			(type default)
		)
		(layer "In3.Cu")
	)
	(gr_arc
		(start 25.41016 -342.431116)
		(mid 25.9969 -343.017856)
		(end 26.58364 -342.431116)
		(stroke
			(width 0.2)
			(type default)
		)
		(layer "In3.Cu")
	)
	(gr_line
		(start 25.41016 -341.503)
		(end 25.41016 -342.431116)
		(stroke
			(width 0.2)
			(type default)
		)
		(layer "In3.Cu")
	)
	(gr_line
		(start 25.526746 -403.1107)
		(end 39.369746 -416.9537)
		(stroke
			(width 0.381)
			(type default)
		)
		(layer "In3.Cu")
	)
	(gr_line
		(start 25.526746 -375.6787)
		(end 25.526746 -403.1107)
		(stroke
			(width 0.381)
			(type default)
		)
		(layer "In3.Cu")
	)
	(gr_line
		(start 26.06675 -365.929672)
		(end 26.083006 -367.02365)
		(stroke
			(width 0.2)
			(type default)
		)
		(layer "In3.Cu")
	)
	(gr_arc
		(start 26.083006 -367.02365)
		(mid 26.678382 -367.601754)
		(end 27.256486 -367.006378)
		(stroke
			(width 0.2)
			(type default)
		)
		(layer "In3.Cu")
	)
	(gr_line
		(start 26.58364 -342.431116)
		(end 26.58364 -341.503254)
		(stroke
			(width 0.2)
			(type default)
		)
		(layer "In3.Cu")
	)
	(gr_arc
		(start 26.58364 -341.503254)
		(mid 25.997027 -340.91626)
		(end 25.41016 -341.503)
		(stroke
			(width 0.2)
			(type default)
		)
		(layer "In3.Cu")
	)
	(gr_arc
		(start 27.061414 -236.59719)
		(mid 27.602942 -237.226094)
		(end 28.231846 -236.684566)
		(stroke
			(width 0.2)
			(type default)
		)
		(layer "In3.Cu")
	)
	(gr_line
		(start 27.12593 -235.731812)
		(end 27.061414 -236.59719)
		(stroke
			(width 0.2)
			(type default)
		)
		(layer "In3.Cu")
	)
	(gr_arc
		(start 27.157172 -339.620606)
		(mid 27.743785 -340.2076)
		(end 28.330652 -339.62086)
		(stroke
			(width 0.2)
			(type default)
		)
		(layer "In3.Cu")
	)
	(gr_line
		(start 27.157172 -338.66201)
		(end 27.157172 -339.620606)
		(stroke
			(width 0.2)
			(type default)
		)
		(layer "In3.Cu")
	)
	(gr_line
		(start 27.19832 -441.860432)
		(end 27.22372 -442.876178)
		(stroke
			(width 0.2)
			(type default)
		)
		(layer "In3.Cu")
	)
	(gr_line
		(start 27.20086 -441.860432)
		(end 27.19832 -441.860432)
		(stroke
			(width 0.2)
			(type default)
		)
		(layer "In3.Cu")
	)
	(gr_line
		(start 27.22372 -442.876178)
		(end 27.223974 -442.876432)
		(stroke
			(width 0.2)
			(type default)
		)
		(layer "In3.Cu")
	)
	(gr_line
		(start 27.223974 -442.876432)
		(end 27.22626 -442.876432)
		(stroke
			(width 0.2)
			(type default)
		)
		(layer "In3.Cu")
	)
	(gr_arc
		(start 27.22626 -442.876432)
		(mid 27.827478 -443.448186)
		(end 28.399232 -442.846968)
		(stroke
			(width 0.2)
			(type default)
		)
		(layer "In3.Cu")
	)
	(gr_arc
		(start 27.24023 -365.912654)
		(mid 26.644981 -365.334548)
		(end 26.06675 -365.929672)
		(stroke
			(width 0.2)
			(type default)
		)
		(layer "In3.Cu")
	)
	(gr_line
		(start 27.256486 -367.006378)
		(end 27.24023 -365.912654)
		(stroke
			(width 0.2)
			(type default)
		)
		(layer "In3.Cu")
	)
	(gr_line
		(start 27.558746 -312.0517)
		(end 39.369746 -323.8627)
		(stroke
			(width 0.381)
			(type default)
		)
		(layer "In3.Cu")
	)
	(gr_line
		(start 27.558746 -284.8737)
		(end 27.558746 -312.0517)
		(stroke
			(width 0.381)
			(type default)
		)
		(layer "In3.Cu")
	)
	(gr_line
		(start 27.980894 -345.078304)
		(end 28.12288 -345.93022)
		(stroke
			(width 0.2)
			(type default)
		)
		(layer "In3.Cu")
	)
	(gr_arc
		(start 28.12288 -345.93022)
		(mid 28.798266 -346.412566)
		(end 29.280612 -345.73718)
		(stroke
			(width 0.2)
			(type default)
		)
		(layer "In3.Cu")
	)
	(gr_line
		(start 28.231846 -236.684566)
		(end 28.296362 -235.819442)
		(stroke
			(width 0.2)
			(type default)
		)
		(layer "In3.Cu")
	)
	(gr_arc
		(start 28.24226 -342.431116)
		(mid 28.829 -343.017856)
		(end 29.41574 -342.431116)
		(stroke
			(width 0.2)
			(type default)
		)
		(layer "In3.Cu")
	)
	(gr_line
		(start 28.24226 -341.503)
		(end 28.24226 -342.431116)
		(stroke
			(width 0.2)
			(type default)
		)
		(layer "In3.Cu")
	)
	(gr_arc
		(start 28.296362 -235.819442)
		(mid 27.75496 -235.190547)
		(end 27.12593 -235.731812)
		(stroke
			(width 0.2)
			(type default)
		)
		(layer "In3.Cu")
	)
	(gr_line
		(start 28.330652 -339.62086)
		(end 28.330652 -338.66201)
		(stroke
			(width 0.2)
			(type default)
		)
		(layer "In3.Cu")
	)
	(gr_arc
		(start 28.330652 -338.66201)
		(mid 27.743912 -338.07527)
		(end 27.157172 -338.66201)
		(stroke
			(width 0.2)
			(type default)
		)
		(layer "In3.Cu")
	)
	(gr_arc
		(start 28.373832 -441.830968)
		(mid 27.772614 -441.259214)
		(end 27.20086 -441.860432)
		(stroke
			(width 0.2)
			(type default)
		)
		(layer "In3.Cu")
	)
	(gr_line
		(start 28.376372 -441.830968)
		(end 28.373832 -441.830968)
		(stroke
			(width 0.2)
			(type default)
		)
		(layer "In3.Cu")
	)
	(gr_line
		(start 28.399232 -442.846968)
		(end 28.401772 -442.846968)
		(stroke
			(width 0.2)
			(type default)
		)
		(layer "In3.Cu")
	)
	(gr_line
		(start 28.401772 -442.846968)
		(end 28.376372 -441.830968)
		(stroke
			(width 0.2)
			(type default)
		)
		(layer "In3.Cu")
	)
	(gr_arc
		(start 28.896564 -33.0327)
		(mid 29.432504 -33.56864)
		(end 29.968444 -33.0327)
		(stroke
			(width 0.2)
			(type default)
		)
		(layer "In3.Cu")
	)
	(gr_line
		(start 28.896564 -31.997142)
		(end 28.896564 -33.0327)
		(stroke
			(width 0.2)
			(type default)
		)
		(layer "In3.Cu")
	)
	(gr_line
		(start 29.082746 -463.4357)
		(end 21.335746 -463.4357)
		(stroke
			(width 0.381)
			(type default)
		)
		(layer "In3.Cu")
	)
	(gr_arc
		(start 29.138626 -344.885518)
		(mid 28.463364 -344.403151)
		(end 27.980894 -345.078304)
		(stroke
			(width 0.2)
			(type default)
		)
		(layer "In3.Cu")
	)
	(gr_arc
		(start 29.23032 -363.213904)
		(mid 29.81706 -363.800644)
		(end 30.4038 -363.213904)
		(stroke
			(width 0.2)
			(type default)
		)
		(layer "In3.Cu")
	)
	(gr_line
		(start 29.23032 -362.255054)
		(end 29.23032 -363.213904)
		(stroke
			(width 0.2)
			(type default)
		)
		(layer "In3.Cu")
	)
	(gr_line
		(start 29.280612 -345.73718)
		(end 29.138626 -344.885518)
		(stroke
			(width 0.2)
			(type default)
		)
		(layer "In3.Cu")
	)
	(gr_line
		(start 29.41574 -342.431116)
		(end 29.41574 -341.503254)
		(stroke
			(width 0.2)
			(type default)
		)
		(layer "In3.Cu")
	)
	(gr_arc
		(start 29.41574 -341.503254)
		(mid 28.829127 -340.91626)
		(end 28.24226 -341.503)
		(stroke
			(width 0.2)
			(type default)
		)
		(layer "In3.Cu")
	)
	(gr_line
		(start 29.968444 -33.0327)
		(end 29.968444 -31.997396)
		(stroke
			(width 0.2)
			(type default)
		)
		(layer "In3.Cu")
	)
	(gr_arc
		(start 29.968444 -31.997396)
		(mid 29.432631 -31.461202)
		(end 28.896564 -31.997142)
		(stroke
			(width 0.2)
			(type default)
		)
		(layer "In3.Cu")
	)
	(gr_line
		(start 30.098746 -98.9457)
		(end 39.242746 -108.0897)
		(stroke
			(width 0.381)
			(type default)
		)
		(layer "In3.Cu")
	)
	(gr_line
		(start 30.098746 -50.0507)
		(end 30.098746 -98.9457)
		(stroke
			(width 0.381)
			(type default)
		)
		(layer "In3.Cu")
	)
	(gr_line
		(start 30.4038 -363.213904)
		(end 30.4038 -362.255308)
		(stroke
			(width 0.2)
			(type default)
		)
		(layer "In3.Cu")
	)
	(gr_arc
		(start 30.4038 -362.255308)
		(mid 29.817187 -361.668314)
		(end 29.23032 -362.255054)
		(stroke
			(width 0.2)
			(type default)
		)
		(layer "In3.Cu")
	)
	(gr_line
		(start 30.503368 -64.11595)
		(end 30.503622 -64.116204)
		(stroke
			(width 0.2)
			(type default)
		)
		(layer "In3.Cu")
	)
	(gr_line
		(start 30.503622 -64.116204)
		(end 30.505908 -64.116458)
		(stroke
			(width 0.2)
			(type default)
		)
		(layer "In3.Cu")
	)
	(gr_arc
		(start 30.505908 -64.116458)
		(mid 31.022544 -64.765682)
		(end 31.671768 -64.249046)
		(stroke
			(width 0.2)
			(type default)
		)
		(layer "In3.Cu")
	)
	(gr_line
		(start 30.605476 -63.217552)
		(end 30.503368 -64.11595)
		(stroke
			(width 0.2)
			(type default)
		)
		(layer "In3.Cu")
	)
	(gr_line
		(start 30.608016 -63.217806)
		(end 30.605476 -63.217552)
		(stroke
			(width 0.2)
			(type default)
		)
		(layer "In3.Cu")
	)
	(gr_line
		(start 30.753558 -475.23273)
		(end 30.804104 -476.09506)
		(stroke
			(width 0.2)
			(type default)
		)
		(layer "In3.Cu")
	)
	(gr_line
		(start 30.756098 -475.232476)
		(end 30.753558 -475.23273)
		(stroke
			(width 0.2)
			(type default)
		)
		(layer "In3.Cu")
	)
	(gr_line
		(start 30.804104 -476.09506)
		(end 30.806644 -476.094806)
		(stroke
			(width 0.2)
			(type default)
		)
		(layer "In3.Cu")
	)
	(gr_arc
		(start 30.806644 -476.094806)
		(mid 31.426658 -476.64624)
		(end 31.978092 -476.026226)
		(stroke
			(width 0.2)
			(type default)
		)
		(layer "In3.Cu")
	)
	(gr_arc
		(start 30.909006 -267.728446)
		(mid 31.495619 -268.31544)
		(end 32.082486 -267.7287)
		(stroke
			(width 0.2)
			(type default)
		)
		(layer "In3.Cu")
	)
	(gr_line
		(start 30.909006 -266.8651)
		(end 30.909006 -267.728446)
		(stroke
			(width 0.2)
			(type default)
		)
		(layer "In3.Cu")
	)
	(gr_line
		(start 30.912308 -372.184168)
		(end 31.034736 -373.248428)
		(stroke
			(width 0.2)
			(type default)
		)
		(layer "In3.Cu")
	)
	(gr_line
		(start 30.914848 -372.183914)
		(end 30.912308 -372.184168)
		(stroke
			(width 0.2)
			(type default)
		)
		(layer "In3.Cu")
	)
	(gr_arc
		(start 31.016702 -274.618958)
		(mid 31.603442 -275.205698)
		(end 32.190182 -274.618958)
		(stroke
			(width 0.2)
			(type default)
		)
		(layer "In3.Cu")
	)
	(gr_line
		(start 31.016702 -273.690842)
		(end 31.016702 -274.618958)
		(stroke
			(width 0.2)
			(type default)
		)
		(layer "In3.Cu")
	)
	(gr_line
		(start 31.034736 -373.248428)
		(end 31.03499 -373.248682)
		(stroke
			(width 0.2)
			(type default)
		)
		(layer "In3.Cu")
	)
	(gr_line
		(start 31.03499 -373.248682)
		(end 31.037276 -373.248428)
		(stroke
			(width 0.2)
			(type default)
		)
		(layer "In3.Cu")
	)
	(gr_arc
		(start 31.037276 -373.248428)
		(mid 31.630874 -373.719598)
		(end 32.102044 -373.126)
		(stroke
			(width 0.2)
			(type default)
		)
		(layer "In3.Cu")
	)
	(gr_line
		(start 31.114746 -197.1167)
		(end 39.496746 -205.4987)
		(stroke
			(width 0.381)
			(type default)
		)
		(layer "In3.Cu")
	)
	(gr_line
		(start 31.114746 -174.0027)
		(end 31.114746 -197.1167)
		(stroke
			(width 0.381)
			(type default)
		)
		(layer "In3.Cu")
	)
	(gr_arc
		(start 31.290006 -162.2933)
		(mid 31.876746 -162.88004)
		(end 32.463486 -162.2933)
		(stroke
			(width 0.2)
			(type default)
		)
		(layer "In3.Cu")
	)
	(gr_line
		(start 31.290006 -161.4297)
		(end 31.290006 -162.2933)
		(stroke
			(width 0.2)
			(type default)
		)
		(layer "In3.Cu")
	)
	(gr_line
		(start 31.671768 -64.249046)
		(end 31.674308 -64.2493)
		(stroke
			(width 0.2)
			(type default)
		)
		(layer "In3.Cu")
	)
	(gr_line
		(start 31.674308 -64.2493)
		(end 31.776416 -63.350648)
		(stroke
			(width 0.2)
			(type default)
		)
		(layer "In3.Cu")
	)
	(gr_line
		(start 31.749746 -37.9857)
		(end 31.749746 -13.0937)
		(stroke
			(width 0.381)
			(type default)
		)
		(layer "In3.Cu")
	)
	(gr_line
		(start 31.749746 -13.0937)
		(end 35.559746 -9.2837)
		(stroke
			(width 0.381)
			(type default)
		)
		(layer "In3.Cu")
	)
	(gr_arc
		(start 31.773876 -63.350394)
		(mid 31.25724 -62.70117)
		(end 30.608016 -63.217806)
		(stroke
			(width 0.2)
			(type default)
		)
		(layer "In3.Cu")
	)
	(gr_line
		(start 31.776416 -63.350648)
		(end 31.773876 -63.350394)
		(stroke
			(width 0.2)
			(type default)
		)
		(layer "In3.Cu")
	)
	(gr_arc
		(start 31.927546 -475.163896)
		(mid 31.307532 -474.612462)
		(end 30.756098 -475.232476)
		(stroke
			(width 0.2)
			(type default)
		)
		(layer "In3.Cu")
	)
	(gr_line
		(start 31.929832 -475.163642)
		(end 31.927546 -475.163896)
		(stroke
			(width 0.2)
			(type default)
		)
		(layer "In3.Cu")
	)
	(gr_line
		(start 31.930086 -475.163896)
		(end 31.929832 -475.163642)
		(stroke
			(width 0.2)
			(type default)
		)
		(layer "In3.Cu")
	)
	(gr_line
		(start 31.978092 -476.026226)
		(end 31.980632 -476.025972)
		(stroke
			(width 0.2)
			(type default)
		)
		(layer "In3.Cu")
	)
	(gr_arc
		(start 31.979616 -372.061486)
		(mid 31.386018 -371.590316)
		(end 30.914848 -372.183914)
		(stroke
			(width 0.2)
			(type default)
		)
		(layer "In3.Cu")
	)
	(gr_line
		(start 31.980632 -476.025972)
		(end 31.930086 -475.163896)
		(stroke
			(width 0.2)
			(type default)
		)
		(layer "In3.Cu")
	)
	(gr_line
		(start 31.982156 -372.061232)
		(end 31.979616 -372.061486)
		(stroke
			(width 0.2)
			(type default)
		)
		(layer "In3.Cu")
	)
	(gr_line
		(start 32.082486 -267.7287)
		(end 32.082486 -266.8651)
		(stroke
			(width 0.2)
			(type default)
		)
		(layer "In3.Cu")
	)
	(gr_arc
		(start 32.082486 -266.8651)
		(mid 31.495746 -266.27836)
		(end 30.909006 -266.8651)
		(stroke
			(width 0.2)
			(type default)
		)
		(layer "In3.Cu")
	)
	(gr_line
		(start 32.102044 -373.126)
		(end 32.104584 -373.125746)
		(stroke
			(width 0.2)
			(type default)
		)
		(layer "In3.Cu")
	)
	(gr_line
		(start 32.104584 -373.125746)
		(end 31.982156 -372.061232)
		(stroke
			(width 0.2)
			(type default)
		)
		(layer "In3.Cu")
	)
	(gr_line
		(start 32.190182 -274.618958)
		(end 32.190182 -273.691096)
		(stroke
			(width 0.2)
			(type default)
		)
		(layer "In3.Cu")
	)
	(gr_arc
		(start 32.190182 -273.691096)
		(mid 31.603569 -273.104102)
		(end 31.016702 -273.690842)
		(stroke
			(width 0.2)
			(type default)
		)
		(layer "In3.Cu")
	)
	(gr_arc
		(start 32.361886 -163.402518)
		(mid 31.945616 -164.123487)
		(end 32.66948 -164.53485)
		(stroke
			(width 0.2)
			(type default)
		)
		(layer "In3.Cu")
	)
	(gr_line
		(start 32.463486 -162.2933)
		(end 32.463486 -161.429954)
		(stroke
			(width 0.2)
			(type default)
		)
		(layer "In3.Cu")
	)
	(gr_arc
		(start 32.463486 -161.429954)
		(mid 31.876873 -160.84296)
		(end 31.290006 -161.4297)
		(stroke
			(width 0.2)
			(type default)
		)
		(layer "In3.Cu")
	)
	(gr_line
		(start 32.66948 -164.53485)
		(end 33.533334 -164.29355)
		(stroke
			(width 0.2)
			(type default)
		)
		(layer "In3.Cu")
	)
	(gr_line
		(start 33.217866 -163.16325)
		(end 32.361886 -163.402518)
		(stroke
			(width 0.2)
			(type default)
		)
		(layer "In3.Cu")
	)
	(gr_arc
		(start 33.533334 -164.29355)
		(mid 33.94075 -163.570666)
		(end 33.217866 -163.16325)
		(stroke
			(width 0.2)
			(type default)
		)
		(layer "In3.Cu")
	)
	(gr_arc
		(start 34.332418 -274.618196)
		(mid 34.918396 -275.205698)
		(end 35.505898 -274.61972)
		(stroke
			(width 0.2)
			(type default)
		)
		(layer "In3.Cu")
	)
	(gr_line
		(start 34.333434 -273.698716)
		(end 34.332418 -274.618196)
		(stroke
			(width 0.2)
			(type default)
		)
		(layer "In3.Cu")
	)
	(gr_arc
		(start 34.465006 -473.748354)
		(mid 35.051746 -474.335094)
		(end 35.638486 -473.748354)
		(stroke
			(width 0.2)
			(type default)
		)
		(layer "In3.Cu")
	)
	(gr_line
		(start 34.465006 -472.820238)
		(end 34.465006 -473.748354)
		(stroke
			(width 0.2)
			(type default)
		)
		(layer "In3.Cu")
	)
	(gr_line
		(start 35.505898 -274.61972)
		(end 35.506914 -273.700494)
		(stroke
			(width 0.2)
			(type default)
		)
		(layer "In3.Cu")
	)
	(gr_arc
		(start 35.506914 -273.700494)
		(mid 34.921063 -273.112992)
		(end 34.333434 -273.698716)
		(stroke
			(width 0.2)
			(type default)
		)
		(layer "In3.Cu")
	)
	(gr_line
		(start 35.559746 -9.2837)
		(end 85.851746 -9.2837)
		(stroke
			(width 0.381)
			(type default)
		)
		(layer "In3.Cu")
	)
	(gr_line
		(start 35.638486 -473.748354)
		(end 35.638486 -472.820492)
		(stroke
			(width 0.2)
			(type default)
		)
		(layer "In3.Cu")
	)
	(gr_arc
		(start 35.638486 -472.820492)
		(mid 35.051873 -472.233498)
		(end 34.465006 -472.820238)
		(stroke
			(width 0.2)
			(type default)
		)
		(layer "In3.Cu")
	)
	(gr_line
		(start 35.707574 -370.823998)
		(end 35.710114 -370.823998)
		(stroke
			(width 0.2)
			(type default)
		)
		(layer "In3.Cu")
	)
	(gr_arc
		(start 35.710114 -370.823998)
		(mid 36.280598 -371.426486)
		(end 36.883086 -370.856002)
		(stroke
			(width 0.2)
			(type default)
		)
		(layer "In3.Cu")
	)
	(gr_line
		(start 35.73272 -369.90274)
		(end 35.707574 -370.823998)
		(stroke
			(width 0.2)
			(type default)
		)
		(layer "In3.Cu")
	)
	(gr_line
		(start 35.73526 -369.90274)
		(end 35.73272 -369.90274)
		(stroke
			(width 0.2)
			(type default)
		)
		(layer "In3.Cu")
	)
	(gr_arc
		(start 36.049712 -164.879274)
		(mid 36.636452 -165.466014)
		(end 37.223192 -164.879274)
		(stroke
			(width 0.2)
			(type default)
		)
		(layer "In3.Cu")
	)
	(gr_line
		(start 36.049712 -163.920424)
		(end 36.049712 -164.879274)
		(stroke
			(width 0.2)
			(type default)
		)
		(layer "In3.Cu")
	)
	(gr_line
		(start 36.883086 -370.856002)
		(end 36.885626 -370.856002)
		(stroke
			(width 0.2)
			(type default)
		)
		(layer "In3.Cu")
	)
	(gr_line
		(start 36.885626 -370.856002)
		(end 36.910772 -369.934998)
		(stroke
			(width 0.2)
			(type default)
		)
		(layer "In3.Cu")
	)
	(gr_arc
		(start 36.908232 -369.934744)
		(mid 36.337748 -369.332256)
		(end 35.73526 -369.90274)
		(stroke
			(width 0.2)
			(type default)
		)
		(layer "In3.Cu")
	)
	(gr_line
		(start 36.910518 -369.934744)
		(end 36.908232 -369.934744)
		(stroke
			(width 0.2)
			(type default)
		)
		(layer "In3.Cu")
	)
	(gr_line
		(start 36.910772 -369.934998)
		(end 36.910518 -369.934744)
		(stroke
			(width 0.2)
			(type default)
		)
		(layer "In3.Cu")
	)
	(gr_line
		(start 36.956746 -43.1927)
		(end 30.098746 -50.0507)
		(stroke
			(width 0.381)
			(type default)
		)
		(layer "In3.Cu")
	)
	(gr_line
		(start 36.956746 -43.1927)
		(end 31.749746 -37.9857)
		(stroke
			(width 0.381)
			(type default)
		)
		(layer "In3.Cu")
	)
	(gr_line
		(start 37.223192 -164.879274)
		(end 37.223192 -163.920678)
		(stroke
			(width 0.2)
			(type default)
		)
		(layer "In3.Cu")
	)
	(gr_arc
		(start 37.223192 -163.920678)
		(mid 36.636579 -163.333684)
		(end 36.049712 -163.920424)
		(stroke
			(width 0.2)
			(type default)
		)
		(layer "In3.Cu")
	)
	(gr_arc
		(start 37.513006 -61.850016)
		(mid 38.099746 -62.436756)
		(end 38.686486 -61.850016)
		(stroke
			(width 0.2)
			(type default)
		)
		(layer "In3.Cu")
	)
	(gr_line
		(start 37.513006 -60.891166)
		(end 37.513006 -61.850016)
		(stroke
			(width 0.2)
			(type default)
		)
		(layer "In3.Cu")
	)
	(gr_line
		(start 38.480746 -234.4547)
		(end 39.496746 -235.4707)
		(stroke
			(width 0.381)
			(type default)
		)
		(layer "In3.Cu")
	)
	(gr_line
		(start 38.480746 -213.7537)
		(end 38.480746 -234.4547)
		(stroke
			(width 0.381)
			(type default)
		)
		(layer "In3.Cu")
	)
	(gr_line
		(start 38.686486 -61.850016)
		(end 38.686486 -60.89142)
		(stroke
			(width 0.2)
			(type default)
		)
		(layer "In3.Cu")
	)
	(gr_arc
		(start 38.686486 -60.89142)
		(mid 38.099873 -60.304426)
		(end 37.513006 -60.891166)
		(stroke
			(width 0.2)
			(type default)
		)
		(layer "In3.Cu")
	)
	(gr_line
		(start 39.242746 -153.0477)
		(end 41.020746 -154.8257)
		(stroke
			(width 0.381)
			(type default)
		)
		(layer "In3.Cu")
	)
	(gr_line
		(start 39.242746 -108.0897)
		(end 39.242746 -153.0477)
		(stroke
			(width 0.381)
			(type default)
		)
		(layer "In3.Cu")
	)
	(gr_line
		(start 39.369746 -453.1487)
		(end 29.082746 -463.4357)
		(stroke
			(width 0.381)
			(type default)
		)
		(layer "In3.Cu")
	)
	(gr_line
		(start 39.369746 -416.9537)
		(end 39.369746 -453.1487)
		(stroke
			(width 0.381)
			(type default)
		)
		(layer "In3.Cu")
	)
	(gr_line
		(start 39.369746 -361.8357)
		(end 25.526746 -375.6787)
		(stroke
			(width 0.381)
			(type default)
		)
		(layer "In3.Cu")
	)
	(gr_line
		(start 39.369746 -323.8627)
		(end 39.369746 -361.8357)
		(stroke
			(width 0.381)
			(type default)
		)
		(layer "In3.Cu")
	)
	(gr_line
		(start 39.496746 -272.9357)
		(end 27.558746 -284.8737)
		(stroke
			(width 0.381)
			(type default)
		)
		(layer "In3.Cu")
	)
	(gr_line
		(start 39.496746 -235.4707)
		(end 39.496746 -272.9357)
		(stroke
			(width 0.381)
			(type default)
		)
		(layer "In3.Cu")
	)
	(gr_line
		(start 39.496746 -212.7377)
		(end 38.480746 -213.7537)
		(stroke
			(width 0.381)
			(type default)
		)
		(layer "In3.Cu")
	)
	(gr_line
		(start 39.496746 -205.4987)
		(end 39.496746 -212.7377)
		(stroke
			(width 0.381)
			(type default)
		)
		(layer "In3.Cu")
	)
	(gr_line
		(start 39.750746 -43.1927)
		(end 36.956746 -43.1927)
		(stroke
			(width 0.381)
			(type default)
		)
		(layer "In3.Cu")
	)
	(gr_line
		(start 41.020746 -164.0967)
		(end 31.114746 -174.0027)
		(stroke
			(width 0.381)
			(type default)
		)
		(layer "In3.Cu")
	)
	(gr_line
		(start 41.020746 -154.8257)
		(end 41.020746 -164.0967)
		(stroke
			(width 0.381)
			(type default)
		)
		(layer "In3.Cu")
	)
	(gr_line
		(start 48.894746 -495.1857)
		(end 60.451746 -483.6287)
		(stroke
			(width 0.381)
			(type default)
		)
		(layer "In3.Cu")
	)
	(gr_line
		(start 60.451746 -492.1377)
		(end 60.451746 -483.6287)
		(stroke
			(width 0.381)
			(type default)
		)
		(layer "In3.Cu")
	)
	(gr_line
		(start 60.451746 -483.6287)
		(end 67.817746 -476.2627)
		(stroke
			(width 0.381)
			(type default)
		)
		(layer "In3.Cu")
	)
	(gr_line
		(start 61.848746 -493.5347)
		(end 60.451746 -492.1377)
		(stroke
			(width 0.381)
			(type default)
		)
		(layer "In3.Cu")
	)
	(gr_line
		(start 65.150746 -88.1507)
		(end 65.150746 -74.4347)
		(stroke
			(width 0.381)
			(type default)
		)
		(layer "In3.Cu")
	)
	(gr_line
		(start 65.150746 -74.4347)
		(end 67.309746 -72.2757)
		(stroke
			(width 0.381)
			(type default)
		)
		(layer "In3.Cu")
	)
	(gr_line
		(start 65.277746 -301.0027)
		(end 65.277746 -288.8107)
		(stroke
			(width 0.381)
			(type default)
		)
		(layer "In3.Cu")
	)
	(gr_line
		(start 65.277746 -288.8107)
		(end 66.801746 -287.2867)
		(stroke
			(width 0.381)
			(type default)
		)
		(layer "In3.Cu")
	)
	(gr_line
		(start 65.404746 -397.5227)
		(end 65.404746 -381.7747)
		(stroke
			(width 0.381)
			(type default)
		)
		(layer "In3.Cu")
	)
	(gr_line
		(start 65.404746 -381.7747)
		(end 67.817746 -379.3617)
		(stroke
			(width 0.381)
			(type default)
		)
		(layer "In3.Cu")
	)
	(gr_line
		(start 66.420746 -89.4207)
		(end 65.150746 -88.1507)
		(stroke
			(width 0.381)
			(type default)
		)
		(layer "In3.Cu")
	)
	(gr_line
		(start 66.674746 -493.5347)
		(end 61.848746 -493.5347)
		(stroke
			(width 0.381)
			(type default)
		)
		(layer "In3.Cu")
	)
	(gr_line
		(start 66.801746 -287.2867)
		(end 81.025746 -287.2867)
		(stroke
			(width 0.381)
			(type default)
		)
		(layer "In3.Cu")
	)
	(gr_line
		(start 67.309746 -193.1797)
		(end 67.309746 -178.3207)
		(stroke
			(width 0.381)
			(type default)
		)
		(layer "In3.Cu")
	)
	(gr_line
		(start 67.309746 -178.3207)
		(end 68.579746 -177.0507)
		(stroke
			(width 0.381)
			(type default)
		)
		(layer "In3.Cu")
	)
	(gr_line
		(start 67.309746 -72.2757)
		(end 77.215746 -72.2757)
		(stroke
			(width 0.381)
			(type default)
		)
		(layer "In3.Cu")
	)
	(gr_line
		(start 67.817746 -476.2627)
		(end 82.168746 -476.2627)
		(stroke
			(width 0.381)
			(type default)
		)
		(layer "In3.Cu")
	)
	(gr_line
		(start 67.817746 -379.3617)
		(end 81.533746 -379.3617)
		(stroke
			(width 0.381)
			(type default)
		)
		(layer "In3.Cu")
	)
	(gr_line
		(start 68.452746 -304.1777)
		(end 65.277746 -301.0027)
		(stroke
			(width 0.381)
			(type default)
		)
		(layer "In3.Cu")
	)
	(gr_line
		(start 68.579746 -177.0507)
		(end 80.009746 -177.0507)
		(stroke
			(width 0.381)
			(type default)
		)
		(layer "In3.Cu")
	)
	(gr_line
		(start 70.230746 -89.4207)
		(end 66.420746 -89.4207)
		(stroke
			(width 0.381)
			(type default)
		)
		(layer "In3.Cu")
	)
	(gr_line
		(start 70.484746 -493.5347)
		(end 66.674746 -493.5347)
		(stroke
			(width 0.381)
			(type default)
		)
		(layer "In3.Cu")
	)
	(gr_line
		(start 70.484746 -402.6027)
		(end 65.404746 -397.5227)
		(stroke
			(width 0.381)
			(type default)
		)
		(layer "In3.Cu")
	)
	(gr_line
		(start 72.262746 -198.1327)
		(end 67.309746 -193.1797)
		(stroke
			(width 0.381)
			(type default)
		)
		(layer "In3.Cu")
	)
	(gr_line
		(start 73.659746 -490.3597)
		(end 70.484746 -493.5347)
		(stroke
			(width 0.381)
			(type default)
		)
		(layer "In3.Cu")
	)
	(gr_line
		(start 73.786746 -92.9767)
		(end 70.230746 -89.4207)
		(stroke
			(width 0.381)
			(type default)
		)
		(layer "In3.Cu")
	)
	(gr_line
		(start 74.294746 -43.1927)
		(end 36.956746 -43.1927)
		(stroke
			(width 0.381)
			(type default)
		)
		(layer "In3.Cu")
	)
	(gr_line
		(start 77.215746 -72.2757)
		(end 81.025746 -68.4657)
		(stroke
			(width 0.381)
			(type default)
		)
		(layer "In3.Cu")
	)
	(gr_line
		(start 80.009746 -304.1777)
		(end 68.452746 -304.1777)
		(stroke
			(width 0.381)
			(type default)
		)
		(layer "In3.Cu")
	)
	(gr_line
		(start 80.009746 -177.0507)
		(end 84.835746 -172.2247)
		(stroke
			(width 0.381)
			(type default)
		)
		(layer "In3.Cu")
	)
	(gr_line
		(start 80.009746 -92.9767)
		(end 73.786746 -92.9767)
		(stroke
			(width 0.381)
			(type default)
		)
		(layer "In3.Cu")
	)
	(gr_line
		(start 81.025746 -287.2867)
		(end 84.835746 -283.4767)
		(stroke
			(width 0.381)
			(type default)
		)
		(layer "In3.Cu")
	)
	(gr_line
		(start 81.025746 -68.4657)
		(end 81.025746 -49.9237)
		(stroke
			(width 0.381)
			(type default)
		)
		(layer "In3.Cu")
	)
	(gr_line
		(start 81.025746 -49.9237)
		(end 74.294746 -43.1927)
		(stroke
			(width 0.381)
			(type default)
		)
		(layer "In3.Cu")
	)
	(gr_line
		(start 81.533746 -379.3617)
		(end 83.819746 -377.0757)
		(stroke
			(width 0.381)
			(type default)
		)
		(layer "In3.Cu")
	)
	(gr_line
		(start 82.168746 -476.2627)
		(end 84.454746 -473.9767)
		(stroke
			(width 0.381)
			(type default)
		)
		(layer "In3.Cu")
	)
	(gr_line
		(start 82.168746 -402.6027)
		(end 70.484746 -402.6027)
		(stroke
			(width 0.381)
			(type default)
		)
		(layer "In3.Cu")
	)
	(gr_line
		(start 82.422746 -198.1327)
		(end 72.262746 -198.1327)
		(stroke
			(width 0.381)
			(type default)
		)
		(layer "In3.Cu")
	)
	(gr_line
		(start 83.819746 -377.0757)
		(end 83.819746 -307.9877)
		(stroke
			(width 0.381)
			(type default)
		)
		(layer "In3.Cu")
	)
	(gr_line
		(start 83.819746 -307.9877)
		(end 80.009746 -304.1777)
		(stroke
			(width 0.381)
			(type default)
		)
		(layer "In3.Cu")
	)
	(gr_line
		(start 84.454746 -473.9767)
		(end 84.454746 -404.8887)
		(stroke
			(width 0.381)
			(type default)
		)
		(layer "In3.Cu")
	)
	(gr_line
		(start 84.454746 -404.8887)
		(end 82.168746 -402.6027)
		(stroke
			(width 0.381)
			(type default)
		)
		(layer "In3.Cu")
	)
	(gr_line
		(start 84.835746 -283.4767)
		(end 84.835746 -200.5457)
		(stroke
			(width 0.381)
			(type default)
		)
		(layer "In3.Cu")
	)
	(gr_line
		(start 84.835746 -200.5457)
		(end 82.422746 -198.1327)
		(stroke
			(width 0.381)
			(type default)
		)
		(layer "In3.Cu")
	)
	(gr_line
		(start 84.835746 -172.2247)
		(end 84.835746 -97.8027)
		(stroke
			(width 0.381)
			(type default)
		)
		(layer "In3.Cu")
	)
	(gr_line
		(start 84.835746 -97.8027)
		(end 80.009746 -92.9767)
		(stroke
			(width 0.381)
			(type default)
		)
		(layer "In3.Cu")
	)
	(gr_line
		(start 85.851746 -9.2837)
		(end 98.551746 -21.9837)
		(stroke
			(width 0.381)
			(type default)
		)
		(layer "In3.Cu")
	)
	(gr_line
		(start 98.551746 -21.9837)
		(end 137.159746 -21.9837)
		(stroke
			(width 0.381)
			(type default)
		)
		(layer "In3.Cu")
	)
	(gr_line
		(start 132.333746 -490.3597)
		(end 73.659746 -490.3597)
		(stroke
			(width 0.381)
			(type default)
		)
		(layer "In3.Cu")
	)
	(gr_line
		(start 137.159746 -21.9837)
		(end 139.826746 -24.6507)
		(stroke
			(width 0.381)
			(type default)
		)
		(layer "In3.Cu")
	)
	(gr_line
		(start 139.826746 -482.8667)
		(end 132.333746 -490.3597)
		(stroke
			(width 0.381)
			(type default)
		)
		(layer "In3.Cu")
	)
	(gr_line
		(start 139.826746 -24.6507)
		(end 139.826746 -482.8667)
		(stroke
			(width 0.381)
			(type default)
		)
		(layer "In3.Cu")
	)
	(gr_line
		(start 193.420746 -484.7717)
		(end 193.420746 -24.7777)
		(stroke
			(width 0.381)
			(type default)
		)
		(layer "In3.Cu")
	)
	(gr_line
		(start 193.420746 -24.7777)
		(end 198.373746 -19.8247)
		(stroke
			(width 0.381)
			(type default)
		)
		(layer "In3.Cu")
	)
	(gr_line
		(start 197.738746 -489.0897)
		(end 193.420746 -484.7717)
		(stroke
			(width 0.381)
			(type default)
		)
		(layer "In3.Cu")
	)
	(gr_line
		(start 198.373746 -19.8247)
		(end 230.377746 -19.8247)
		(stroke
			(width 0.381)
			(type default)
		)
		(layer "In3.Cu")
	)
	(gr_arc
		(start 215.1888 -269.032228)
		(mid 214.610442 -269.62735)
		(end 215.205564 -270.205708)
		(stroke
			(width 0.2)
			(type default)
		)
		(layer "In3.Cu")
	)
	(gr_line
		(start 215.205564 -270.205708)
		(end 216.11971 -270.192754)
		(stroke
			(width 0.2)
			(type default)
		)
		(layer "In3.Cu")
	)
	(gr_line
		(start 215.32342 -167.05072)
		(end 216.186766 -167.066468)
		(stroke
			(width 0.2)
			(type default)
		)
		(layer "In3.Cu")
	)
	(gr_arc
		(start 215.344756 -165.87724)
		(mid 214.747348 -166.453312)
		(end 215.32342 -167.05072)
		(stroke
			(width 0.2)
			(type default)
		)
		(layer "In3.Cu")
	)
	(gr_arc
		(start 215.349836 -62.92342)
		(mid 214.774524 -63.521463)
		(end 215.372442 -64.0969)
		(stroke
			(width 0.2)
			(type default)
		)
		(layer "In3.Cu")
	)
	(gr_line
		(start 215.372442 -64.0969)
		(end 216.236042 -64.080136)
		(stroke
			(width 0.2)
			(type default)
		)
		(layer "In3.Cu")
	)
	(gr_arc
		(start 215.608154 -371.879368)
		(mid 215.031064 -372.475633)
		(end 215.627204 -373.052848)
		(stroke
			(width 0.2)
			(type default)
		)
		(layer "In3.Cu")
	)
	(gr_line
		(start 215.627204 -373.052848)
		(end 216.490804 -373.038624)
		(stroke
			(width 0.2)
			(type default)
		)
		(layer "In3.Cu")
	)
	(gr_arc
		(start 215.92159 -474.661484)
		(mid 215.338406 -475.25178)
		(end 215.928702 -475.834964)
		(stroke
			(width 0.2)
			(type default)
		)
		(layer "In3.Cu")
	)
	(gr_line
		(start 215.928702 -475.834964)
		(end 216.792048 -475.829884)
		(stroke
			(width 0.2)
			(type default)
		)
		(layer "In3.Cu")
	)
	(gr_line
		(start 216.1032 -269.019274)
		(end 215.1888 -269.032228)
		(stroke
			(width 0.2)
			(type default)
		)
		(layer "In3.Cu")
	)
	(gr_arc
		(start 216.11971 -270.192754)
		(mid 216.69832 -269.597759)
		(end 216.1032 -269.019274)
		(stroke
			(width 0.2)
			(type default)
		)
		(layer "In3.Cu")
	)
	(gr_arc
		(start 216.186766 -167.066468)
		(mid 216.78443 -166.490523)
		(end 216.208356 -165.892988)
		(stroke
			(width 0.2)
			(type default)
		)
		(layer "In3.Cu")
	)
	(gr_line
		(start 216.208356 -165.892988)
		(end 215.344756 -165.87724)
		(stroke
			(width 0.2)
			(type default)
		)
		(layer "In3.Cu")
	)
	(gr_line
		(start 216.213182 -62.906656)
		(end 215.349836 -62.92342)
		(stroke
			(width 0.2)
			(type default)
		)
		(layer "In3.Cu")
	)
	(gr_arc
		(start 216.236042 -64.080136)
		(mid 216.811352 -63.481966)
		(end 216.213182 -62.906656)
		(stroke
			(width 0.2)
			(type default)
		)
		(layer "In3.Cu")
	)
	(gr_line
		(start 216.4715 -371.865144)
		(end 215.608154 -371.879368)
		(stroke
			(width 0.2)
			(type default)
		)
		(layer "In3.Cu")
	)
	(gr_arc
		(start 216.490804 -373.038624)
		(mid 217.067892 -372.442232)
		(end 216.4715 -371.865144)
		(stroke
			(width 0.2)
			(type default)
		)
		(layer "In3.Cu")
	)
	(gr_line
		(start 216.78519 -474.656404)
		(end 215.92159 -474.661484)
		(stroke
			(width 0.2)
			(type default)
		)
		(layer "In3.Cu")
	)
	(gr_arc
		(start 216.792048 -475.829884)
		(mid 217.375485 -475.239715)
		(end 216.78519 -474.656404)
		(stroke
			(width 0.2)
			(type default)
		)
		(layer "In3.Cu")
	)
	(gr_arc
		(start 219.609416 -473.86621)
		(mid 220.196156 -474.45295)
		(end 220.782896 -473.86621)
		(stroke
			(width 0.2)
			(type default)
		)
		(layer "In3.Cu")
	)
	(gr_line
		(start 219.609416 -472.90736)
		(end 219.609416 -473.86621)
		(stroke
			(width 0.2)
			(type default)
		)
		(layer "In3.Cu")
	)
	(gr_line
		(start 220.782896 -473.86621)
		(end 220.782896 -472.907614)
		(stroke
			(width 0.2)
			(type default)
		)
		(layer "In3.Cu")
	)
	(gr_arc
		(start 220.782896 -472.907614)
		(mid 220.196283 -472.32062)
		(end 219.609416 -472.90736)
		(stroke
			(width 0.2)
			(type default)
		)
		(layer "In3.Cu")
	)
	(gr_line
		(start 222.386398 -370.80444)
		(end 222.388938 -370.804694)
		(stroke
			(width 0.2)
			(type default)
		)
		(layer "In3.Cu")
	)
	(gr_arc
		(start 222.388938 -370.804694)
		(mid 222.941642 -371.423438)
		(end 223.560386 -370.870734)
		(stroke
			(width 0.2)
			(type default)
		)
		(layer "In3.Cu")
	)
	(gr_arc
		(start 222.417894 -267.792708)
		(mid 222.956374 -268.424152)
		(end 223.587818 -267.885672)
		(stroke
			(width 0.2)
			(type default)
		)
		(layer "In3.Cu")
	)
	(gr_line
		(start 222.437452 -369.905026)
		(end 222.386398 -370.80444)
		(stroke
			(width 0.2)
			(type default)
		)
		(layer "In3.Cu")
	)
	(gr_line
		(start 222.439992 -369.90528)
		(end 222.437452 -369.905026)
		(stroke
			(width 0.2)
			(type default)
		)
		(layer "In3.Cu")
	)
	(gr_arc
		(start 222.445072 -61.945012)
		(mid 223.031812 -62.531752)
		(end 223.618552 -61.945012)
		(stroke
			(width 0.2)
			(type default)
		)
		(layer "In3.Cu")
	)
	(gr_line
		(start 222.445072 -60.986162)
		(end 222.445072 -61.945012)
		(stroke
			(width 0.2)
			(type default)
		)
		(layer "In3.Cu")
	)
	(gr_line
		(start 222.48622 -266.931648)
		(end 222.417894 -267.792708)
		(stroke
			(width 0.2)
			(type default)
		)
		(layer "In3.Cu")
	)
	(gr_arc
		(start 222.576644 -164.934392)
		(mid 223.163384 -165.521132)
		(end 223.750124 -164.934392)
		(stroke
			(width 0.2)
			(type default)
		)
		(layer "In3.Cu")
	)
	(gr_line
		(start 222.576644 -163.975542)
		(end 222.576644 -164.934392)
		(stroke
			(width 0.2)
			(type default)
		)
		(layer "In3.Cu")
	)
	(gr_line
		(start 223.560386 -370.870734)
		(end 223.562926 -370.870988)
		(stroke
			(width 0.2)
			(type default)
		)
		(layer "In3.Cu")
	)
	(gr_line
		(start 223.562926 -370.870988)
		(end 223.61398 -369.971828)
		(stroke
			(width 0.2)
			(type default)
		)
		(layer "In3.Cu")
	)
	(gr_line
		(start 223.587818 -267.885672)
		(end 223.656144 -267.024866)
		(stroke
			(width 0.2)
			(type default)
		)
		(layer "In3.Cu")
	)
	(gr_arc
		(start 223.61144 -369.971574)
		(mid 223.058863 -369.352569)
		(end 222.439992 -369.90528)
		(stroke
			(width 0.2)
			(type default)
		)
		(layer "In3.Cu")
	)
	(gr_line
		(start 223.613726 -369.971574)
		(end 223.61144 -369.971574)
		(stroke
			(width 0.2)
			(type default)
		)
		(layer "In3.Cu")
	)
	(gr_line
		(start 223.61398 -369.971828)
		(end 223.613726 -369.971574)
		(stroke
			(width 0.2)
			(type default)
		)
		(layer "In3.Cu")
	)
	(gr_line
		(start 223.618552 -61.945012)
		(end 223.618552 -60.986416)
		(stroke
			(width 0.2)
			(type default)
		)
		(layer "In3.Cu")
	)
	(gr_arc
		(start 223.618552 -60.986416)
		(mid 223.031939 -60.399422)
		(end 222.445072 -60.986162)
		(stroke
			(width 0.2)
			(type default)
		)
		(layer "In3.Cu")
	)
	(gr_arc
		(start 223.656144 -267.024866)
		(mid 223.11779 -266.393432)
		(end 222.48622 -266.931648)
		(stroke
			(width 0.2)
			(type default)
		)
		(layer "In3.Cu")
	)
	(gr_line
		(start 223.750124 -164.934392)
		(end 223.750124 -163.975796)
		(stroke
			(width 0.2)
			(type default)
		)
		(layer "In3.Cu")
	)
	(gr_arc
		(start 223.750124 -163.975796)
		(mid 223.163511 -163.388802)
		(end 222.576644 -163.975542)
		(stroke
			(width 0.2)
			(type default)
		)
		(layer "In3.Cu")
	)
	(gr_line
		(start 230.377746 -19.8247)
		(end 244.728746 -34.1757)
		(stroke
			(width 0.381)
			(type default)
		)
		(layer "In3.Cu")
	)
	(gr_line
		(start 240.537746 -489.0897)
		(end 197.738746 -489.0897)
		(stroke
			(width 0.381)
			(type default)
		)
		(layer "In3.Cu")
	)
	(gr_line
		(start 244.728746 -484.8987)
		(end 240.537746 -489.0897)
		(stroke
			(width 0.381)
			(type default)
		)
		(layer "In3.Cu")
	)
	(gr_line
		(start 244.728746 -34.1757)
		(end 244.728746 -484.8987)
		(stroke
			(width 0.381)
			(type default)
		)
		(layer "In3.Cu")
	)
	(gr_arc
		(start 5.894578 -348.491048)
		(mid 6.470396 -349.08363)
		(end 7.062978 -348.507812)
		(stroke
			(width 0.2)
			(type default)
		)
		(layer "In4.Cu")
	)
	(gr_line
		(start 5.907532 -347.577156)
		(end 5.894578 -348.491048)
		(stroke
			(width 0.2)
			(type default)
		)
		(layer "In4.Cu")
	)
	(gr_line
		(start 6.091936 -121.551954)
		(end 6.1468 -122.41403)
		(stroke
			(width 0.2)
			(type default)
		)
		(layer "In4.Cu")
	)
	(gr_arc
		(start 6.093206 -102.457504)
		(mid 6.679946 -103.044244)
		(end 7.266686 -102.457504)
		(stroke
			(width 0.2)
			(type default)
		)
		(layer "In4.Cu")
	)
	(gr_line
		(start 6.093206 -101.498654)
		(end 6.093206 -102.457504)
		(stroke
			(width 0.2)
			(type default)
		)
		(layer "In4.Cu")
	)
	(gr_arc
		(start 6.093206 -98.457766)
		(mid 6.679946 -99.044506)
		(end 7.266686 -98.457766)
		(stroke
			(width 0.2)
			(type default)
		)
		(layer "In4.Cu")
	)
	(gr_line
		(start 6.093206 -97.498916)
		(end 6.093206 -98.457766)
		(stroke
			(width 0.2)
			(type default)
		)
		(layer "In4.Cu")
	)
	(gr_line
		(start 6.094476 -121.5517)
		(end 6.091936 -121.551954)
		(stroke
			(width 0.2)
			(type default)
		)
		(layer "In4.Cu")
	)
	(gr_line
		(start 6.116574 -107.545378)
		(end 6.148324 -108.408216)
		(stroke
			(width 0.2)
			(type default)
		)
		(layer "In4.Cu")
	)
	(gr_arc
		(start 6.118606 -128.458214)
		(mid 6.705346 -129.044954)
		(end 7.292086 -128.458214)
		(stroke
			(width 0.2)
			(type default)
		)
		(layer "In4.Cu")
	)
	(gr_line
		(start 6.118606 -127.499364)
		(end 6.118606 -128.458214)
		(stroke
			(width 0.2)
			(type default)
		)
		(layer "In4.Cu")
	)
	(gr_line
		(start 6.119114 -107.545378)
		(end 6.116574 -107.545378)
		(stroke
			(width 0.2)
			(type default)
		)
		(layer "In4.Cu")
	)
	(gr_line
		(start 6.140704 -117.514624)
		(end 6.144006 -118.429532)
		(stroke
			(width 0.2)
			(type default)
		)
		(layer "In4.Cu")
	)
	(gr_line
		(start 6.142482 -111.613442)
		(end 6.16966 -112.476788)
		(stroke
			(width 0.2)
			(type default)
		)
		(layer "In4.Cu")
	)
	(gr_arc
		(start 6.144006 -118.429532)
		(mid 6.732778 -119.01424)
		(end 7.317486 -118.425468)
		(stroke
			(width 0.2)
			(type default)
		)
		(layer "In4.Cu")
	)
	(gr_line
		(start 6.1468 -122.41403)
		(end 6.14934 -122.413776)
		(stroke
			(width 0.2)
			(type default)
		)
		(layer "In4.Cu")
	)
	(gr_line
		(start 6.148324 -108.408216)
		(end 6.148578 -108.40847)
		(stroke
			(width 0.2)
			(type default)
		)
		(layer "In4.Cu")
	)
	(gr_line
		(start 6.148578 -108.40847)
		(end 6.150864 -108.40847)
		(stroke
			(width 0.2)
			(type default)
		)
		(layer "In4.Cu")
	)
	(gr_arc
		(start 6.14934 -122.413776)
		(mid 6.771894 -122.962162)
		(end 7.32028 -122.339608)
		(stroke
			(width 0.2)
			(type default)
		)
		(layer "In4.Cu")
	)
	(gr_arc
		(start 6.150864 -108.40847)
		(mid 6.758686 -108.973112)
		(end 7.323328 -108.36529)
		(stroke
			(width 0.2)
			(type default)
		)
		(layer "In4.Cu")
	)
	(gr_arc
		(start 6.164072 -162.459416)
		(mid 6.748272 -163.043616)
		(end 7.332472 -162.459416)
		(stroke
			(width 0.2)
			(type default)
		)
		(layer "In4.Cu")
	)
	(gr_line
		(start 6.164072 -161.5313)
		(end 6.164072 -162.459416)
		(stroke
			(width 0.2)
			(type default)
		)
		(layer "In4.Cu")
	)
	(gr_arc
		(start 6.169406 -134.442708)
		(mid 6.756146 -135.029448)
		(end 7.342886 -134.442708)
		(stroke
			(width 0.2)
			(type default)
		)
		(layer "In4.Cu")
	)
	(gr_line
		(start 6.169406 -133.514592)
		(end 6.169406 -134.442708)
		(stroke
			(width 0.2)
			(type default)
		)
		(layer "In4.Cu")
	)
	(gr_arc
		(start 6.16966 -112.476788)
		(mid 6.774688 -113.044732)
		(end 7.342632 -112.439704)
		(stroke
			(width 0.2)
			(type default)
		)
		(layer "In4.Cu")
	)
	(gr_line
		(start 6.205474 -165.630606)
		(end 6.272022 -166.797228)
		(stroke
			(width 0.2)
			(type default)
		)
		(layer "In4.Cu")
	)
	(gr_line
		(start 6.208014 -165.630352)
		(end 6.205474 -165.630606)
		(stroke
			(width 0.2)
			(type default)
		)
		(layer "In4.Cu")
	)
	(gr_line
		(start 6.21792 -116.441982)
		(end 6.22046 -116.441982)
		(stroke
			(width 0.2)
			(type default)
		)
		(layer "In4.Cu")
	)
	(gr_arc
		(start 6.22046 -116.441982)
		(mid 6.79069 -117.044724)
		(end 7.393432 -116.474494)
		(stroke
			(width 0.2)
			(type default)
		)
		(layer "In4.Cu")
	)
	(gr_line
		(start 6.24332 -115.515644)
		(end 6.21792 -116.441982)
		(stroke
			(width 0.2)
			(type default)
		)
		(layer "In4.Cu")
	)
	(gr_line
		(start 6.24586 -115.515644)
		(end 6.24332 -115.515644)
		(stroke
			(width 0.2)
			(type default)
		)
		(layer "In4.Cu")
	)
	(gr_line
		(start 6.272022 -166.797228)
		(end 6.274562 -166.796974)
		(stroke
			(width 0.2)
			(type default)
		)
		(layer "In4.Cu")
	)
	(gr_arc
		(start 6.274562 -166.796974)
		(mid 6.89102 -167.346884)
		(end 7.44093 -166.730426)
		(stroke
			(width 0.2)
			(type default)
		)
		(layer "In4.Cu")
	)
	(gr_arc
		(start 6.400546 -158.459678)
		(mid 6.984746 -159.043878)
		(end 7.568946 -158.459678)
		(stroke
			(width 0.2)
			(type default)
		)
		(layer "In4.Cu")
	)
	(gr_line
		(start 6.400546 -157.531562)
		(end 6.400546 -158.459678)
		(stroke
			(width 0.2)
			(type default)
		)
		(layer "In4.Cu")
	)
	(gr_arc
		(start 6.445758 -170.459654)
		(mid 7.032498 -171.046394)
		(end 7.619238 -170.459654)
		(stroke
			(width 0.2)
			(type default)
		)
		(layer "In4.Cu")
	)
	(gr_line
		(start 6.445758 -169.531538)
		(end 6.445758 -170.459654)
		(stroke
			(width 0.2)
			(type default)
		)
		(layer "In4.Cu")
	)
	(gr_arc
		(start 6.862318 -398.756378)
		(mid 6.30555 -399.366994)
		(end 6.916166 -399.923762)
		(stroke
			(width 0.2)
			(type default)
		)
		(layer "In4.Cu")
	)
	(gr_line
		(start 6.916166 -399.923762)
		(end 7.77875 -399.884138)
		(stroke
			(width 0.2)
			(type default)
		)
		(layer "In4.Cu")
	)
	(gr_line
		(start 7.003796 -352.786442)
		(end 7.004812 -352.788728)
		(stroke
			(width 0.2)
			(type default)
		)
		(layer "In4.Cu")
	)
	(gr_line
		(start 7.00405 -352.786188)
		(end 7.003796 -352.786442)
		(stroke
			(width 0.2)
			(type default)
		)
		(layer "In4.Cu")
	)
	(gr_arc
		(start 7.004812 -352.788728)
		(mid 6.70054 -353.560934)
		(end 7.47268 -353.864926)
		(stroke
			(width 0.2)
			(type default)
		)
		(layer "In4.Cu")
	)
	(gr_line
		(start 7.062978 -348.507812)
		(end 7.075932 -347.594174)
		(stroke
			(width 0.2)
			(type default)
		)
		(layer "In4.Cu")
	)
	(gr_arc
		(start 7.075932 -347.594174)
		(mid 6.500241 -347.001594)
		(end 5.907532 -347.577156)
		(stroke
			(width 0.2)
			(type default)
		)
		(layer "In4.Cu")
	)
	(gr_arc
		(start 7.215886 -413.544512)
		(mid 7.007016 -414.313851)
		(end 7.778242 -414.516062)
		(stroke
			(width 0.2)
			(type default)
		)
		(layer "In4.Cu")
	)
	(gr_line
		(start 7.249922 -422.467532)
		(end 8.113014 -422.489884)
		(stroke
			(width 0.2)
			(type default)
		)
		(layer "In4.Cu")
	)
	(gr_line
		(start 7.249922 -422.464992)
		(end 7.249922 -422.467532)
		(stroke
			(width 0.2)
			(type default)
		)
		(layer "In4.Cu")
	)
	(gr_line
		(start 7.265162 -368.402616)
		(end 8.127746 -368.441224)
		(stroke
			(width 0.2)
			(type default)
		)
		(layer "In4.Cu")
	)
	(gr_arc
		(start 7.265416 -121.477532)
		(mid 6.642862 -120.929146)
		(end 6.094476 -121.5517)
		(stroke
			(width 0.2)
			(type default)
		)
		(layer "In4.Cu")
	)
	(gr_line
		(start 7.266686 -102.457504)
		(end 7.266686 -101.498908)
		(stroke
			(width 0.2)
			(type default)
		)
		(layer "In4.Cu")
	)
	(gr_arc
		(start 7.266686 -101.498908)
		(mid 6.680073 -100.911914)
		(end 6.093206 -101.498654)
		(stroke
			(width 0.2)
			(type default)
		)
		(layer "In4.Cu")
	)
	(gr_line
		(start 7.266686 -98.457766)
		(end 7.266686 -97.49917)
		(stroke
			(width 0.2)
			(type default)
		)
		(layer "In4.Cu")
	)
	(gr_arc
		(start 7.266686 -97.49917)
		(mid 6.680073 -96.912176)
		(end 6.093206 -97.498916)
		(stroke
			(width 0.2)
			(type default)
		)
		(layer "In4.Cu")
	)
	(gr_line
		(start 7.267702 -121.477278)
		(end 7.265416 -121.477532)
		(stroke
			(width 0.2)
			(type default)
		)
		(layer "In4.Cu")
	)
	(gr_line
		(start 7.267956 -121.477532)
		(end 7.267702 -121.477278)
		(stroke
			(width 0.2)
			(type default)
		)
		(layer "In4.Cu")
	)
	(gr_arc
		(start 7.278878 -421.34282)
		(mid 6.703314 -421.889428)
		(end 7.249922 -422.464992)
		(stroke
			(width 0.2)
			(type default)
		)
		(layer "In4.Cu")
	)
	(gr_line
		(start 7.278878 -421.34028)
		(end 7.278878 -421.34282)
		(stroke
			(width 0.2)
			(type default)
		)
		(layer "In4.Cu")
	)
	(gr_arc
		(start 7.291578 -107.502198)
		(mid 6.683756 -106.937556)
		(end 6.119114 -107.545378)
		(stroke
			(width 0.2)
			(type default)
		)
		(layer "In4.Cu")
	)
	(gr_line
		(start 7.292086 -128.458214)
		(end 7.292086 -127.499618)
		(stroke
			(width 0.2)
			(type default)
		)
		(layer "In4.Cu")
	)
	(gr_arc
		(start 7.292086 -127.499618)
		(mid 6.705473 -126.912624)
		(end 6.118606 -127.499364)
		(stroke
			(width 0.2)
			(type default)
		)
		(layer "In4.Cu")
	)
	(gr_line
		(start 7.294118 -107.502198)
		(end 7.291578 -107.502198)
		(stroke
			(width 0.2)
			(type default)
		)
		(layer "In4.Cu")
	)
	(gr_arc
		(start 7.312914 -367.331752)
		(mid 6.753606 -367.843308)
		(end 7.265162 -368.402616)
		(stroke
			(width 0.2)
			(type default)
		)
		(layer "In4.Cu")
	)
	(gr_arc
		(start 7.314184 -117.510814)
		(mid 6.725539 -116.926106)
		(end 6.140704 -117.514624)
		(stroke
			(width 0.2)
			(type default)
		)
		(layer "In4.Cu")
	)
	(gr_arc
		(start 7.315454 -111.576612)
		(mid 6.710553 -111.008664)
		(end 6.142482 -111.613442)
		(stroke
			(width 0.2)
			(type default)
		)
		(layer "In4.Cu")
	)
	(gr_line
		(start 7.317486 -118.425468)
		(end 7.314184 -117.510814)
		(stroke
			(width 0.2)
			(type default)
		)
		(layer "In4.Cu")
	)
	(gr_line
		(start 7.32028 -122.339608)
		(end 7.32282 -122.339354)
		(stroke
			(width 0.2)
			(type default)
		)
		(layer "In4.Cu")
	)
	(gr_line
		(start 7.32282 -122.339354)
		(end 7.267956 -121.477532)
		(stroke
			(width 0.2)
			(type default)
		)
		(layer "In4.Cu")
	)
	(gr_line
		(start 7.323328 -108.36529)
		(end 7.325868 -108.36529)
		(stroke
			(width 0.2)
			(type default)
		)
		(layer "In4.Cu")
	)
	(gr_line
		(start 7.325868 -108.36529)
		(end 7.294118 -107.502198)
		(stroke
			(width 0.2)
			(type default)
		)
		(layer "In4.Cu")
	)
	(gr_line
		(start 7.332472 -162.459416)
		(end 7.332472 -161.531554)
		(stroke
			(width 0.2)
			(type default)
		)
		(layer "In4.Cu")
	)
	(gr_arc
		(start 7.332472 -161.531554)
		(mid 6.748399 -160.9471)
		(end 6.164072 -161.5313)
		(stroke
			(width 0.2)
			(type default)
		)
		(layer "In4.Cu")
	)
	(gr_line
		(start 7.340346 -410.396436)
		(end 8.203946 -410.396436)
		(stroke
			(width 0.2)
			(type default)
		)
		(layer "In4.Cu")
	)
	(gr_arc
		(start 7.340346 -409.273756)
		(mid 6.779006 -409.835096)
		(end 7.340346 -410.396436)
		(stroke
			(width 0.2)
			(type default)
		)
		(layer "In4.Cu")
	)
	(gr_line
		(start 7.3406 -409.273756)
		(end 7.340346 -409.273756)
		(stroke
			(width 0.2)
			(type default)
		)
		(layer "In4.Cu")
	)
	(gr_line
		(start 7.342632 -112.439704)
		(end 7.315454 -111.576612)
		(stroke
			(width 0.2)
			(type default)
		)
		(layer "In4.Cu")
	)
	(gr_line
		(start 7.342886 -134.442708)
		(end 7.342886 -133.514846)
		(stroke
			(width 0.2)
			(type default)
		)
		(layer "In4.Cu")
	)
	(gr_arc
		(start 7.342886 -133.514846)
		(mid 6.756273 -132.927852)
		(end 6.169406 -133.514592)
		(stroke
			(width 0.2)
			(type default)
		)
		(layer "In4.Cu")
	)
	(gr_arc
		(start 7.351776 -357.949754)
		(mid 6.7818 -358.54767)
		(end 7.379716 -359.117646)
		(stroke
			(width 0.2)
			(type default)
		)
		(layer "In4.Cu")
	)
	(gr_line
		(start 7.351776 -357.947214)
		(end 7.351776 -357.949754)
		(stroke
			(width 0.2)
			(type default)
		)
		(layer "In4.Cu")
	)
	(gr_line
		(start 7.358888 -424.590464)
		(end 8.22071 -424.642788)
		(stroke
			(width 0.2)
			(type default)
		)
		(layer "In4.Cu")
	)
	(gr_line
		(start 7.359142 -424.587924)
		(end 7.358888 -424.590464)
		(stroke
			(width 0.2)
			(type default)
		)
		(layer "In4.Cu")
	)
	(gr_arc
		(start 7.374382 -165.563804)
		(mid 6.757924 -165.013894)
		(end 6.208014 -165.630352)
		(stroke
			(width 0.2)
			(type default)
		)
		(layer "In4.Cu")
	)
	(gr_line
		(start 7.375398 -363.918246)
		(end 7.376922 -363.920278)
		(stroke
			(width 0.2)
			(type default)
		)
		(layer "In4.Cu")
	)
	(gr_line
		(start 7.376668 -165.563804)
		(end 7.374382 -165.563804)
		(stroke
			(width 0.2)
			(type default)
		)
		(layer "In4.Cu")
	)
	(gr_arc
		(start 7.376922 -363.920278)
		(mid 7.291324 -364.745524)
		(end 8.11657 -364.831122)
		(stroke
			(width 0.2)
			(type default)
		)
		(layer "In4.Cu")
	)
	(gr_line
		(start 7.376922 -165.563804)
		(end 7.376668 -165.563804)
		(stroke
			(width 0.2)
			(type default)
		)
		(layer "In4.Cu")
	)
	(gr_line
		(start 7.379716 -359.120186)
		(end 8.25627 -359.099358)
		(stroke
			(width 0.2)
			(type default)
		)
		(layer "In4.Cu")
	)
	(gr_line
		(start 7.379716 -359.117646)
		(end 7.379716 -359.120186)
		(stroke
			(width 0.2)
			(type default)
		)
		(layer "In4.Cu")
	)
	(gr_line
		(start 7.393432 -116.474494)
		(end 7.395972 -116.474494)
		(stroke
			(width 0.2)
			(type default)
		)
		(layer "In4.Cu")
	)
	(gr_line
		(start 7.395972 -116.474494)
		(end 7.421372 -115.54841)
		(stroke
			(width 0.2)
			(type default)
		)
		(layer "In4.Cu")
	)
	(gr_arc
		(start 7.418832 -115.548156)
		(mid 6.848602 -114.945414)
		(end 6.24586 -115.515644)
		(stroke
			(width 0.2)
			(type default)
		)
		(layer "In4.Cu")
	)
	(gr_line
		(start 7.421118 -115.548156)
		(end 7.418832 -115.548156)
		(stroke
			(width 0.2)
			(type default)
		)
		(layer "In4.Cu")
	)
	(gr_line
		(start 7.421372 -115.54841)
		(end 7.421118 -115.548156)
		(stroke
			(width 0.2)
			(type default)
		)
		(layer "In4.Cu")
	)
	(gr_arc
		(start 7.423658 -423.518076)
		(mid 6.856476 -424.020742)
		(end 7.359142 -424.587924)
		(stroke
			(width 0.2)
			(type default)
		)
		(layer "In4.Cu")
	)
	(gr_line
		(start 7.423912 -423.515536)
		(end 7.423658 -423.518076)
		(stroke
			(width 0.2)
			(type default)
		)
		(layer "In4.Cu")
	)
	(gr_line
		(start 7.44093 -166.730426)
		(end 7.44347 -166.730172)
		(stroke
			(width 0.2)
			(type default)
		)
		(layer "In4.Cu")
	)
	(gr_line
		(start 7.44347 -166.730172)
		(end 7.376922 -165.563804)
		(stroke
			(width 0.2)
			(type default)
		)
		(layer "In4.Cu")
	)
	(gr_line
		(start 7.47268 -353.864926)
		(end 7.473696 -353.867212)
		(stroke
			(width 0.2)
			(type default)
		)
		(layer "In4.Cu")
	)
	(gr_line
		(start 7.473696 -353.867212)
		(end 8.447532 -353.443794)
		(stroke
			(width 0.2)
			(type default)
		)
		(layer "In4.Cu")
	)
	(gr_line
		(start 7.516622 -418.417248)
		(end 8.380222 -418.429694)
		(stroke
			(width 0.2)
			(type default)
		)
		(layer "In4.Cu")
	)
	(gr_arc
		(start 7.53364 -417.243768)
		(mid 6.93852 -417.821999)
		(end 7.516622 -418.417248)
		(stroke
			(width 0.2)
			(type default)
		)
		(layer "In4.Cu")
	)
	(gr_arc
		(start 7.566406 -386.461)
		(mid 8.127746 -387.02234)
		(end 8.689086 -386.461)
		(stroke
			(width 0.2)
			(type default)
		)
		(layer "In4.Cu")
	)
	(gr_line
		(start 7.566406 -385.532884)
		(end 7.566406 -386.461)
		(stroke
			(width 0.2)
			(type default)
		)
		(layer "In4.Cu")
	)
	(gr_line
		(start 7.568946 -158.459678)
		(end 7.568946 -157.531816)
		(stroke
			(width 0.2)
			(type default)
		)
		(layer "In4.Cu")
	)
	(gr_arc
		(start 7.568946 -157.531816)
		(mid 6.984873 -156.947362)
		(end 6.400546 -157.531562)
		(stroke
			(width 0.2)
			(type default)
		)
		(layer "In4.Cu")
	)
	(gr_line
		(start 7.619238 -170.459654)
		(end 7.619238 -169.531792)
		(stroke
			(width 0.2)
			(type default)
		)
		(layer "In4.Cu")
	)
	(gr_arc
		(start 7.619238 -169.531792)
		(mid 7.032625 -168.944798)
		(end 6.445758 -169.531538)
		(stroke
			(width 0.2)
			(type default)
		)
		(layer "In4.Cu")
	)
	(gr_line
		(start 7.623048 -384.608832)
		(end 8.485886 -384.647186)
		(stroke
			(width 0.2)
			(type default)
		)
		(layer "In4.Cu")
	)
	(gr_arc
		(start 7.675626 -383.436368)
		(mid 7.063238 -383.996311)
		(end 7.623048 -384.608832)
		(stroke
			(width 0.2)
			(type default)
		)
		(layer "In4.Cu")
	)
	(gr_line
		(start 7.689088 -372.065804)
		(end 8.587486 -372.107206)
		(stroke
			(width 0.2)
			(type default)
		)
		(layer "In4.Cu")
	)
	(gr_line
		(start 7.725156 -398.716754)
		(end 6.862318 -398.756378)
		(stroke
			(width 0.2)
			(type default)
		)
		(layer "In4.Cu")
	)
	(gr_arc
		(start 7.74319 -370.89334)
		(mid 7.13004 -371.452521)
		(end 7.689088 -372.065804)
		(stroke
			(width 0.2)
			(type default)
		)
		(layer "In4.Cu")
	)
	(gr_line
		(start 7.746746 -380.96444)
		(end 8.660892 -380.96444)
		(stroke
			(width 0.2)
			(type default)
		)
		(layer "In4.Cu")
	)
	(gr_arc
		(start 7.746746 -379.79096)
		(mid 7.160006 -380.3777)
		(end 7.746746 -380.96444)
		(stroke
			(width 0.2)
			(type default)
		)
		(layer "In4.Cu")
	)
	(gr_line
		(start 7.778242 -414.516062)
		(end 8.581898 -414.041336)
		(stroke
			(width 0.2)
			(type default)
		)
		(layer "In4.Cu")
	)
	(gr_arc
		(start 7.77875 -399.884138)
		(mid 8.335766 -399.273649)
		(end 7.725156 -398.716754)
		(stroke
			(width 0.2)
			(type default)
		)
		(layer "In4.Cu")
	)
	(gr_line
		(start 7.817104 -375.905268)
		(end 7.817358 -375.907808)
		(stroke
			(width 0.2)
			(type default)
		)
		(layer "In4.Cu")
	)
	(gr_arc
		(start 7.817358 -375.907808)
		(mid 7.340854 -376.497088)
		(end 7.930134 -376.973592)
		(stroke
			(width 0.2)
			(type default)
		)
		(layer "In4.Cu")
	)
	(gr_line
		(start 7.930134 -376.973592)
		(end 7.930388 -376.976132)
		(stroke
			(width 0.2)
			(type default)
		)
		(layer "In4.Cu")
	)
	(gr_line
		(start 7.930388 -376.976132)
		(end 8.810498 -376.882914)
		(stroke
			(width 0.2)
			(type default)
		)
		(layer "In4.Cu")
	)
	(gr_line
		(start 7.977632 -352.36277)
		(end 7.00405 -352.786188)
		(stroke
			(width 0.2)
			(type default)
		)
		(layer "In4.Cu")
	)
	(gr_line
		(start 7.978648 -352.365056)
		(end 7.977632 -352.36277)
		(stroke
			(width 0.2)
			(type default)
		)
		(layer "In4.Cu")
	)
	(gr_line
		(start 8.010906 -413.074612)
		(end 7.215886 -413.544512)
		(stroke
			(width 0.2)
			(type default)
		)
		(layer "In4.Cu")
	)
	(gr_line
		(start 8.062976 -363.359954)
		(end 7.375398 -363.918246)
		(stroke
			(width 0.2)
			(type default)
		)
		(layer "In4.Cu")
	)
	(gr_line
		(start 8.0645 -363.361986)
		(end 8.062976 -363.359954)
		(stroke
			(width 0.2)
			(type default)
		)
		(layer "In4.Cu")
	)
	(gr_line
		(start 8.113014 -422.489884)
		(end 8.113268 -422.48963)
		(stroke
			(width 0.2)
			(type default)
		)
		(layer "In4.Cu")
	)
	(gr_line
		(start 8.113268 -422.48963)
		(end 8.113268 -422.487344)
		(stroke
			(width 0.2)
			(type default)
		)
		(layer "In4.Cu")
	)
	(gr_arc
		(start 8.113268 -422.487344)
		(mid 8.688832 -421.940736)
		(end 8.142224 -421.365172)
		(stroke
			(width 0.2)
			(type default)
		)
		(layer "In4.Cu")
	)
	(gr_line
		(start 8.11657 -364.831122)
		(end 8.118094 -364.833154)
		(stroke
			(width 0.2)
			(type default)
		)
		(layer "In4.Cu")
	)
	(gr_line
		(start 8.118094 -364.833154)
		(end 8.805672 -364.275116)
		(stroke
			(width 0.2)
			(type default)
		)
		(layer "In4.Cu")
	)
	(gr_arc
		(start 8.127746 -368.441224)
		(mid 8.687314 -367.929795)
		(end 8.175752 -367.37036)
		(stroke
			(width 0.2)
			(type default)
		)
		(layer "In4.Cu")
	)
	(gr_line
		(start 8.142224 -421.365172)
		(end 8.142224 -421.362632)
		(stroke
			(width 0.2)
			(type default)
		)
		(layer "In4.Cu")
	)
	(gr_line
		(start 8.142224 -421.362632)
		(end 7.278878 -421.34028)
		(stroke
			(width 0.2)
			(type default)
		)
		(layer "In4.Cu")
	)
	(gr_line
		(start 8.175752 -367.37036)
		(end 7.312914 -367.331752)
		(stroke
			(width 0.2)
			(type default)
		)
		(layer "In4.Cu")
	)
	(gr_arc
		(start 8.203946 -410.396436)
		(mid 8.765286 -409.835096)
		(end 8.203946 -409.273756)
		(stroke
			(width 0.2)
			(type default)
		)
		(layer "In4.Cu")
	)
	(gr_line
		(start 8.203946 -409.273756)
		(end 7.3406 -409.273756)
		(stroke
			(width 0.2)
			(type default)
		)
		(layer "In4.Cu")
	)
	(gr_line
		(start 8.22071 -424.642788)
		(end 8.220964 -424.642534)
		(stroke
			(width 0.2)
			(type default)
		)
		(layer "In4.Cu")
	)
	(gr_line
		(start 8.220964 -424.642534)
		(end 8.221218 -424.640248)
		(stroke
			(width 0.2)
			(type default)
		)
		(layer "In4.Cu")
	)
	(gr_arc
		(start 8.221218 -424.640248)
		(mid 8.7884 -424.137582)
		(end 8.285734 -423.5704)
		(stroke
			(width 0.2)
			(type default)
		)
		(layer "In4.Cu")
	)
	(gr_line
		(start 8.228584 -357.928926)
		(end 8.228584 -357.926386)
		(stroke
			(width 0.2)
			(type default)
		)
		(layer "In4.Cu")
	)
	(gr_line
		(start 8.228584 -357.926386)
		(end 7.351776 -357.947214)
		(stroke
			(width 0.2)
			(type default)
		)
		(layer "In4.Cu")
	)
	(gr_line
		(start 8.25627 -359.099358)
		(end 8.256524 -359.099104)
		(stroke
			(width 0.2)
			(type default)
		)
		(layer "In4.Cu")
	)
	(gr_line
		(start 8.256524 -359.099104)
		(end 8.256524 -359.096818)
		(stroke
			(width 0.2)
			(type default)
		)
		(layer "In4.Cu")
	)
	(gr_arc
		(start 8.256524 -359.096818)
		(mid 8.8265 -358.498902)
		(end 8.228584 -357.928926)
		(stroke
			(width 0.2)
			(type default)
		)
		(layer "In4.Cu")
	)
	(gr_line
		(start 8.285734 -423.5704)
		(end 8.285988 -423.56786)
		(stroke
			(width 0.2)
			(type default)
		)
		(layer "In4.Cu")
	)
	(gr_line
		(start 8.285988 -423.56786)
		(end 7.423912 -423.515536)
		(stroke
			(width 0.2)
			(type default)
		)
		(layer "In4.Cu")
	)
	(gr_arc
		(start 8.380222 -418.429694)
		(mid 8.975344 -417.851336)
		(end 8.396986 -417.256214)
		(stroke
			(width 0.2)
			(type default)
		)
		(layer "In4.Cu")
	)
	(gr_line
		(start 8.396986 -417.256214)
		(end 7.53364 -417.243768)
		(stroke
			(width 0.2)
			(type default)
		)
		(layer "In4.Cu")
	)
	(gr_arc
		(start 8.446516 -353.441508)
		(mid 8.750808 -352.669348)
		(end 7.978648 -352.365056)
		(stroke
			(width 0.2)
			(type default)
		)
		(layer "In4.Cu")
	)
	(gr_line
		(start 8.447532 -353.443794)
		(end 8.446516 -353.441508)
		(stroke
			(width 0.2)
			(type default)
		)
		(layer "In4.Cu")
	)
	(gr_arc
		(start 8.485886 -384.647186)
		(mid 9.09828 -384.087116)
		(end 8.53821 -383.474722)
		(stroke
			(width 0.2)
			(type default)
		)
		(layer "In4.Cu")
	)
	(gr_line
		(start 8.53821 -383.474722)
		(end 7.675626 -383.436368)
		(stroke
			(width 0.2)
			(type default)
		)
		(layer "In4.Cu")
	)
	(gr_arc
		(start 8.581898 -414.041336)
		(mid 8.779764 -413.272478)
		(end 8.010906 -413.074612)
		(stroke
			(width 0.2)
			(type default)
		)
		(layer "In4.Cu")
	)
	(gr_arc
		(start 8.587486 -372.107206)
		(mid 9.200642 -371.547898)
		(end 8.641334 -370.934742)
		(stroke
			(width 0.2)
			(type default)
		)
		(layer "In4.Cu")
	)
	(gr_line
		(start 8.641334 -370.934742)
		(end 7.74319 -370.89334)
		(stroke
			(width 0.2)
			(type default)
		)
		(layer "In4.Cu")
	)
	(gr_line
		(start 8.660892 -380.96444)
		(end 8.661146 -380.96444)
		(stroke
			(width 0.2)
			(type default)
		)
		(layer "In4.Cu")
	)
	(gr_arc
		(start 8.661146 -380.96444)
		(mid 9.247886 -380.3777)
		(end 8.661146 -379.79096)
		(stroke
			(width 0.2)
			(type default)
		)
		(layer "In4.Cu")
	)
	(gr_line
		(start 8.661146 -379.79096)
		(end 7.746746 -379.79096)
		(stroke
			(width 0.2)
			(type default)
		)
		(layer "In4.Cu")
	)
	(gr_arc
		(start 8.684006 -132.4737)
		(mid 9.270746 -133.06044)
		(end 9.857486 -132.4737)
		(stroke
			(width 0.2)
			(type default)
		)
		(layer "In4.Cu")
	)
	(gr_line
		(start 8.684006 -131.51485)
		(end 8.684006 -132.4737)
		(stroke
			(width 0.2)
			(type default)
		)
		(layer "In4.Cu")
	)
	(gr_line
		(start 8.689086 -386.461)
		(end 8.689086 -385.533138)
		(stroke
			(width 0.2)
			(type default)
		)
		(layer "In4.Cu")
	)
	(gr_arc
		(start 8.689086 -385.533138)
		(mid 8.127873 -384.971544)
		(end 7.566406 -385.532884)
		(stroke
			(width 0.2)
			(type default)
		)
		(layer "In4.Cu")
	)
	(gr_line
		(start 8.697468 -375.81205)
		(end 7.817104 -375.905268)
		(stroke
			(width 0.2)
			(type default)
		)
		(layer "In4.Cu")
	)
	(gr_line
		(start 8.697722 -375.81459)
		(end 8.697468 -375.81205)
		(stroke
			(width 0.2)
			(type default)
		)
		(layer "In4.Cu")
	)
	(gr_arc
		(start 8.804148 -364.27283)
		(mid 8.889746 -363.447584)
		(end 8.0645 -363.361986)
		(stroke
			(width 0.2)
			(type default)
		)
		(layer "In4.Cu")
	)
	(gr_line
		(start 8.805672 -364.275116)
		(end 8.805672 -364.274608)
		(stroke
			(width 0.2)
			(type default)
		)
		(layer "In4.Cu")
	)
	(gr_line
		(start 8.805672 -364.274608)
		(end 8.804148 -364.27283)
		(stroke
			(width 0.2)
			(type default)
		)
		(layer "In4.Cu")
	)
	(gr_line
		(start 8.810498 -376.882914)
		(end 8.810752 -376.88266)
		(stroke
			(width 0.2)
			(type default)
		)
		(layer "In4.Cu")
	)
	(gr_arc
		(start 8.810498 -376.880374)
		(mid 9.287002 -376.291094)
		(end 8.697722 -375.81459)
		(stroke
			(width 0.2)
			(type default)
		)
		(layer "In4.Cu")
	)
	(gr_line
		(start 8.810752 -376.88266)
		(end 8.810498 -376.880374)
		(stroke
			(width 0.2)
			(type default)
		)
		(layer "In4.Cu")
	)
	(gr_line
		(start 9.857486 -132.4737)
		(end 9.857486 -131.515104)
		(stroke
			(width 0.2)
			(type default)
		)
		(layer "In4.Cu")
	)
	(gr_arc
		(start 9.857486 -131.515104)
		(mid 9.270873 -130.92811)
		(end 8.684006 -131.51485)
		(stroke
			(width 0.2)
			(type default)
		)
		(layer "In4.Cu")
	)
	(gr_arc
		(start 11.066018 -439.032904)
		(mid 11.652631 -439.619898)
		(end 12.239498 -439.033158)
		(stroke
			(width 0.2)
			(type default)
		)
		(layer "In4.Cu")
	)
	(gr_line
		(start 11.066018 -438.105042)
		(end 11.066018 -439.032904)
		(stroke
			(width 0.2)
			(type default)
		)
		(layer "In4.Cu")
	)
	(gr_line
		(start 11.0744 -441.81014)
		(end 11.937746 -441.81014)
		(stroke
			(width 0.2)
			(type default)
		)
		(layer "In4.Cu")
	)
	(gr_arc
		(start 11.0744 -440.63666)
		(mid 10.48766 -441.2234)
		(end 11.0744 -441.81014)
		(stroke
			(width 0.2)
			(type default)
		)
		(layer "In4.Cu")
	)
	(gr_line
		(start 11.937746 -441.81014)
		(end 11.938 -441.81014)
		(stroke
			(width 0.2)
			(type default)
		)
		(layer "In4.Cu")
	)
	(gr_arc
		(start 11.938 -441.81014)
		(mid 12.52474 -441.2234)
		(end 11.938 -440.63666)
		(stroke
			(width 0.2)
			(type default)
		)
		(layer "In4.Cu")
	)
	(gr_line
		(start 11.938 -440.63666)
		(end 11.0744 -440.63666)
		(stroke
			(width 0.2)
			(type default)
		)
		(layer "In4.Cu")
	)
	(gr_arc
		(start 12.192254 -177.578004)
		(mid 12.757404 -178.180746)
		(end 13.360146 -177.615596)
		(stroke
			(width 0.2)
			(type default)
		)
		(layer "In4.Cu")
	)
	(gr_line
		(start 12.220194 -176.714658)
		(end 12.192254 -177.578004)
		(stroke
			(width 0.2)
			(type default)
		)
		(layer "In4.Cu")
	)
	(gr_line
		(start 12.239498 -439.033158)
		(end 12.239498 -438.105042)
		(stroke
			(width 0.2)
			(type default)
		)
		(layer "In4.Cu")
	)
	(gr_arc
		(start 12.239498 -438.105042)
		(mid 11.652758 -437.518302)
		(end 11.066018 -438.105042)
		(stroke
			(width 0.2)
			(type default)
		)
		(layer "In4.Cu")
	)
	(gr_line
		(start 13.360146 -177.615596)
		(end 13.388086 -176.752504)
		(stroke
			(width 0.2)
			(type default)
		)
		(layer "In4.Cu")
	)
	(gr_arc
		(start 13.388086 -176.752504)
		(mid 12.823063 -176.149766)
		(end 12.220194 -176.714658)
		(stroke
			(width 0.2)
			(type default)
		)
		(layer "In4.Cu")
	)
	(gr_arc
		(start 14.653006 -136.536938)
		(mid 15.238984 -137.12444)
		(end 15.826486 -136.538462)
		(stroke
			(width 0.2)
			(type default)
		)
		(layer "In4.Cu")
	)
	(gr_line
		(start 14.654022 -135.673338)
		(end 14.653006 -136.536938)
		(stroke
			(width 0.2)
			(type default)
		)
		(layer "In4.Cu")
	)
	(gr_arc
		(start 15.770098 -120.508268)
		(mid 16.355822 -121.096024)
		(end 16.943578 -120.5103)
		(stroke
			(width 0.2)
			(type default)
		)
		(layer "In4.Cu")
	)
	(gr_line
		(start 15.771622 -119.644668)
		(end 15.770098 -120.508268)
		(stroke
			(width 0.2)
			(type default)
		)
		(layer "In4.Cu")
	)
	(gr_line
		(start 15.826486 -136.538462)
		(end 15.827502 -135.675116)
		(stroke
			(width 0.2)
			(type default)
		)
		(layer "In4.Cu")
	)
	(gr_arc
		(start 15.827502 -135.675116)
		(mid 15.241651 -135.087614)
		(end 14.654022 -135.673338)
		(stroke
			(width 0.2)
			(type default)
		)
		(layer "In4.Cu")
	)
	(gr_line
		(start 16.943578 -120.5103)
		(end 16.945102 -119.646954)
		(stroke
			(width 0.2)
			(type default)
		)
		(layer "In4.Cu")
	)
	(gr_arc
		(start 16.945102 -119.646954)
		(mid 16.359505 -119.059198)
		(end 15.771622 -119.644668)
		(stroke
			(width 0.2)
			(type default)
		)
		(layer "In4.Cu")
	)
	(gr_line
		(start 21.053044 -444.232792)
		(end 21.090382 -445.095376)
		(stroke
			(width 0.2)
			(type default)
		)
		(layer "In4.Cu")
	)
	(gr_arc
		(start 21.090382 -445.095376)
		(mid 21.701887 -445.656457)
		(end 22.262846 -445.04483)
		(stroke
			(width 0.2)
			(type default)
		)
		(layer "In4.Cu")
	)
	(gr_arc
		(start 21.26107 -238.799624)
		(mid 21.774529 -239.451657)
		(end 22.426422 -238.938054)
		(stroke
			(width 0.2)
			(type default)
		)
		(layer "In4.Cu")
	)
	(gr_arc
		(start 21.307806 -136.15035)
		(mid 21.894546 -136.73709)
		(end 22.481286 -136.15035)
		(stroke
			(width 0.2)
			(type default)
		)
		(layer "In4.Cu")
	)
	(gr_line
		(start 21.307806 -135.1915)
		(end 21.307806 -136.15035)
		(stroke
			(width 0.2)
			(type default)
		)
		(layer "In4.Cu")
	)
	(gr_line
		(start 21.36267 -237.941612)
		(end 21.26107 -238.799624)
		(stroke
			(width 0.2)
			(type default)
		)
		(layer "In4.Cu")
	)
	(gr_line
		(start 21.411184 -32.240474)
		(end 21.487384 -33.209738)
		(stroke
			(width 0.2)
			(type default)
		)
		(layer "In4.Cu")
	)
	(gr_arc
		(start 21.48586 -342.045036)
		(mid 22.069933 -342.62949)
		(end 22.65426 -342.04529)
		(stroke
			(width 0.2)
			(type default)
		)
		(layer "In4.Cu")
	)
	(gr_line
		(start 21.48586 -341.08644)
		(end 21.48586 -342.045036)
		(stroke
			(width 0.2)
			(type default)
		)
		(layer "In4.Cu")
	)
	(gr_arc
		(start 21.487384 -33.209738)
		(mid 22.118192 -33.74897)
		(end 22.657308 -33.118044)
		(stroke
			(width 0.2)
			(type default)
		)
		(layer "In4.Cu")
	)
	(gr_arc
		(start 22.225508 -444.181992)
		(mid 21.613876 -443.62116)
		(end 21.053044 -444.232792)
		(stroke
			(width 0.2)
			(type default)
		)
		(layer "In4.Cu")
	)
	(gr_line
		(start 22.262846 -445.04483)
		(end 22.225508 -444.181992)
		(stroke
			(width 0.2)
			(type default)
		)
		(layer "In4.Cu")
	)
	(gr_line
		(start 22.426422 -238.938054)
		(end 22.528022 -238.079788)
		(stroke
			(width 0.2)
			(type default)
		)
		(layer "In4.Cu")
	)
	(gr_line
		(start 22.481286 -136.15035)
		(end 22.481286 -135.191754)
		(stroke
			(width 0.2)
			(type default)
		)
		(layer "In4.Cu")
	)
	(gr_arc
		(start 22.481286 -135.191754)
		(mid 21.894673 -134.60476)
		(end 21.307806 -135.1915)
		(stroke
			(width 0.2)
			(type default)
		)
		(layer "In4.Cu")
	)
	(gr_arc
		(start 22.528022 -238.079788)
		(mid 22.014434 -237.428024)
		(end 21.36267 -237.941612)
		(stroke
			(width 0.2)
			(type default)
		)
		(layer "In4.Cu")
	)
	(gr_arc
		(start 22.581108 -32.148526)
		(mid 21.950172 -31.609538)
		(end 21.411184 -32.240474)
		(stroke
			(width 0.2)
			(type default)
		)
		(layer "In4.Cu")
	)
	(gr_line
		(start 22.65426 -342.04529)
		(end 22.65426 -341.08644)
		(stroke
			(width 0.2)
			(type default)
		)
		(layer "In4.Cu")
	)
	(gr_arc
		(start 22.65426 -341.08644)
		(mid 22.07006 -340.50224)
		(end 21.48586 -341.08644)
		(stroke
			(width 0.2)
			(type default)
		)
		(layer "In4.Cu")
	)
	(gr_line
		(start 22.657308 -33.118044)
		(end 22.581108 -32.148526)
		(stroke
			(width 0.2)
			(type default)
		)
		(layer "In4.Cu")
	)
	(gr_arc
		(start 24.052022 -349.878904)
		(mid 24.606504 -350.496378)
		(end 25.223978 -349.941896)
		(stroke
			(width 0.2)
			(type default)
		)
		(layer "In4.Cu")
	)
	(gr_line
		(start 24.110188 -348.796102)
		(end 24.052022 -349.878904)
		(stroke
			(width 0.2)
			(type default)
		)
		(layer "In4.Cu")
	)
	(gr_line
		(start 24.257 -130.99034)
		(end 25.1206 -130.99034)
		(stroke
			(width 0.2)
			(type default)
		)
		(layer "In4.Cu")
	)
	(gr_arc
		(start 24.257 -129.81686)
		(mid 23.67026 -130.4036)
		(end 24.257 -130.99034)
		(stroke
			(width 0.2)
			(type default)
		)
		(layer "In4.Cu")
	)
	(gr_arc
		(start 25.1206 -130.99034)
		(mid 25.70734 -130.4036)
		(end 25.1206 -129.81686)
		(stroke
			(width 0.2)
			(type default)
		)
		(layer "In4.Cu")
	)
	(gr_line
		(start 25.1206 -129.81686)
		(end 24.257 -129.81686)
		(stroke
			(width 0.2)
			(type default)
		)
		(layer "In4.Cu")
	)
	(gr_line
		(start 25.223978 -349.941896)
		(end 25.282144 -348.859348)
		(stroke
			(width 0.2)
			(type default)
		)
		(layer "In4.Cu")
	)
	(gr_arc
		(start 25.282144 -348.859348)
		(mid 24.727789 -348.241881)
		(end 24.110188 -348.796102)
		(stroke
			(width 0.2)
			(type default)
		)
		(layer "In4.Cu")
	)
	(gr_arc
		(start 25.41016 -342.431116)
		(mid 25.9969 -343.017856)
		(end 26.58364 -342.431116)
		(stroke
			(width 0.2)
			(type default)
		)
		(layer "In4.Cu")
	)
	(gr_line
		(start 25.41016 -341.503)
		(end 25.41016 -342.431116)
		(stroke
			(width 0.2)
			(type default)
		)
		(layer "In4.Cu")
	)
	(gr_line
		(start 26.06675 -365.929672)
		(end 26.083006 -367.02365)
		(stroke
			(width 0.2)
			(type default)
		)
		(layer "In4.Cu")
	)
	(gr_arc
		(start 26.083006 -367.02365)
		(mid 26.678382 -367.601754)
		(end 27.256486 -367.006378)
		(stroke
			(width 0.2)
			(type default)
		)
		(layer "In4.Cu")
	)
	(gr_line
		(start 26.58364 -342.431116)
		(end 26.58364 -341.503254)
		(stroke
			(width 0.2)
			(type default)
		)
		(layer "In4.Cu")
	)
	(gr_arc
		(start 26.58364 -341.503254)
		(mid 25.997027 -340.91626)
		(end 25.41016 -341.503)
		(stroke
			(width 0.2)
			(type default)
		)
		(layer "In4.Cu")
	)
	(gr_arc
		(start 27.061414 -236.59719)
		(mid 27.602942 -237.226094)
		(end 28.231846 -236.684566)
		(stroke
			(width 0.2)
			(type default)
		)
		(layer "In4.Cu")
	)
	(gr_line
		(start 27.12593 -235.731812)
		(end 27.061414 -236.59719)
		(stroke
			(width 0.2)
			(type default)
		)
		(layer "In4.Cu")
	)
	(gr_arc
		(start 27.157172 -339.620606)
		(mid 27.743785 -340.2076)
		(end 28.330652 -339.62086)
		(stroke
			(width 0.2)
			(type default)
		)
		(layer "In4.Cu")
	)
	(gr_line
		(start 27.157172 -338.66201)
		(end 27.157172 -339.620606)
		(stroke
			(width 0.2)
			(type default)
		)
		(layer "In4.Cu")
	)
	(gr_line
		(start 27.19832 -441.860432)
		(end 27.22372 -442.876178)
		(stroke
			(width 0.2)
			(type default)
		)
		(layer "In4.Cu")
	)
	(gr_line
		(start 27.20086 -441.860432)
		(end 27.19832 -441.860432)
		(stroke
			(width 0.2)
			(type default)
		)
		(layer "In4.Cu")
	)
	(gr_line
		(start 27.22372 -442.876178)
		(end 27.223974 -442.876432)
		(stroke
			(width 0.2)
			(type default)
		)
		(layer "In4.Cu")
	)
	(gr_line
		(start 27.223974 -442.876432)
		(end 27.22626 -442.876432)
		(stroke
			(width 0.2)
			(type default)
		)
		(layer "In4.Cu")
	)
	(gr_arc
		(start 27.22626 -442.876432)
		(mid 27.827478 -443.448186)
		(end 28.399232 -442.846968)
		(stroke
			(width 0.2)
			(type default)
		)
		(layer "In4.Cu")
	)
	(gr_arc
		(start 27.24023 -365.912654)
		(mid 26.644981 -365.334548)
		(end 26.06675 -365.929672)
		(stroke
			(width 0.2)
			(type default)
		)
		(layer "In4.Cu")
	)
	(gr_line
		(start 27.256486 -367.006378)
		(end 27.24023 -365.912654)
		(stroke
			(width 0.2)
			(type default)
		)
		(layer "In4.Cu")
	)
	(gr_line
		(start 27.980894 -345.078304)
		(end 28.12288 -345.93022)
		(stroke
			(width 0.2)
			(type default)
		)
		(layer "In4.Cu")
	)
	(gr_arc
		(start 28.12288 -345.93022)
		(mid 28.798266 -346.412566)
		(end 29.280612 -345.73718)
		(stroke
			(width 0.2)
			(type default)
		)
		(layer "In4.Cu")
	)
	(gr_line
		(start 28.231846 -236.684566)
		(end 28.296362 -235.819442)
		(stroke
			(width 0.2)
			(type default)
		)
		(layer "In4.Cu")
	)
	(gr_arc
		(start 28.24226 -342.431116)
		(mid 28.829 -343.017856)
		(end 29.41574 -342.431116)
		(stroke
			(width 0.2)
			(type default)
		)
		(layer "In4.Cu")
	)
	(gr_line
		(start 28.24226 -341.503)
		(end 28.24226 -342.431116)
		(stroke
			(width 0.2)
			(type default)
		)
		(layer "In4.Cu")
	)
	(gr_arc
		(start 28.296362 -235.819442)
		(mid 27.75496 -235.190547)
		(end 27.12593 -235.731812)
		(stroke
			(width 0.2)
			(type default)
		)
		(layer "In4.Cu")
	)
	(gr_line
		(start 28.330652 -339.62086)
		(end 28.330652 -338.66201)
		(stroke
			(width 0.2)
			(type default)
		)
		(layer "In4.Cu")
	)
	(gr_arc
		(start 28.330652 -338.66201)
		(mid 27.743912 -338.07527)
		(end 27.157172 -338.66201)
		(stroke
			(width 0.2)
			(type default)
		)
		(layer "In4.Cu")
	)
	(gr_arc
		(start 28.373832 -441.830968)
		(mid 27.772614 -441.259214)
		(end 27.20086 -441.860432)
		(stroke
			(width 0.2)
			(type default)
		)
		(layer "In4.Cu")
	)
	(gr_line
		(start 28.376372 -441.830968)
		(end 28.373832 -441.830968)
		(stroke
			(width 0.2)
			(type default)
		)
		(layer "In4.Cu")
	)
	(gr_line
		(start 28.399232 -442.846968)
		(end 28.401772 -442.846968)
		(stroke
			(width 0.2)
			(type default)
		)
		(layer "In4.Cu")
	)
	(gr_line
		(start 28.401772 -442.846968)
		(end 28.376372 -441.830968)
		(stroke
			(width 0.2)
			(type default)
		)
		(layer "In4.Cu")
	)
	(gr_arc
		(start 28.896564 -33.0327)
		(mid 29.432504 -33.56864)
		(end 29.968444 -33.0327)
		(stroke
			(width 0.2)
			(type default)
		)
		(layer "In4.Cu")
	)
	(gr_line
		(start 28.896564 -31.997142)
		(end 28.896564 -33.0327)
		(stroke
			(width 0.2)
			(type default)
		)
		(layer "In4.Cu")
	)
	(gr_arc
		(start 29.138626 -344.885518)
		(mid 28.463364 -344.403151)
		(end 27.980894 -345.078304)
		(stroke
			(width 0.2)
			(type default)
		)
		(layer "In4.Cu")
	)
	(gr_arc
		(start 29.23032 -363.213904)
		(mid 29.81706 -363.800644)
		(end 30.4038 -363.213904)
		(stroke
			(width 0.2)
			(type default)
		)
		(layer "In4.Cu")
	)
	(gr_line
		(start 29.23032 -362.255054)
		(end 29.23032 -363.213904)
		(stroke
			(width 0.2)
			(type default)
		)
		(layer "In4.Cu")
	)
	(gr_line
		(start 29.280612 -345.73718)
		(end 29.138626 -344.885518)
		(stroke
			(width 0.2)
			(type default)
		)
		(layer "In4.Cu")
	)
	(gr_line
		(start 29.41574 -342.431116)
		(end 29.41574 -341.503254)
		(stroke
			(width 0.2)
			(type default)
		)
		(layer "In4.Cu")
	)
	(gr_arc
		(start 29.41574 -341.503254)
		(mid 28.829127 -340.91626)
		(end 28.24226 -341.503)
		(stroke
			(width 0.2)
			(type default)
		)
		(layer "In4.Cu")
	)
	(gr_line
		(start 29.968444 -33.0327)
		(end 29.968444 -31.997396)
		(stroke
			(width 0.2)
			(type default)
		)
		(layer "In4.Cu")
	)
	(gr_arc
		(start 29.968444 -31.997396)
		(mid 29.432631 -31.461202)
		(end 28.896564 -31.997142)
		(stroke
			(width 0.2)
			(type default)
		)
		(layer "In4.Cu")
	)
	(gr_line
		(start 30.4038 -363.213904)
		(end 30.4038 -362.255308)
		(stroke
			(width 0.2)
			(type default)
		)
		(layer "In4.Cu")
	)
	(gr_arc
		(start 30.4038 -362.255308)
		(mid 29.817187 -361.668314)
		(end 29.23032 -362.255054)
		(stroke
			(width 0.2)
			(type default)
		)
		(layer "In4.Cu")
	)
	(gr_line
		(start 30.503368 -64.11595)
		(end 30.503622 -64.116204)
		(stroke
			(width 0.2)
			(type default)
		)
		(layer "In4.Cu")
	)
	(gr_line
		(start 30.503622 -64.116204)
		(end 30.505908 -64.116458)
		(stroke
			(width 0.2)
			(type default)
		)
		(layer "In4.Cu")
	)
	(gr_arc
		(start 30.505908 -64.116458)
		(mid 31.022544 -64.765682)
		(end 31.671768 -64.249046)
		(stroke
			(width 0.2)
			(type default)
		)
		(layer "In4.Cu")
	)
	(gr_line
		(start 30.605476 -63.217552)
		(end 30.503368 -64.11595)
		(stroke
			(width 0.2)
			(type default)
		)
		(layer "In4.Cu")
	)
	(gr_line
		(start 30.608016 -63.217806)
		(end 30.605476 -63.217552)
		(stroke
			(width 0.2)
			(type default)
		)
		(layer "In4.Cu")
	)
	(gr_line
		(start 30.753558 -475.23273)
		(end 30.804104 -476.09506)
		(stroke
			(width 0.2)
			(type default)
		)
		(layer "In4.Cu")
	)
	(gr_line
		(start 30.756098 -475.232476)
		(end 30.753558 -475.23273)
		(stroke
			(width 0.2)
			(type default)
		)
		(layer "In4.Cu")
	)
	(gr_line
		(start 30.804104 -476.09506)
		(end 30.806644 -476.094806)
		(stroke
			(width 0.2)
			(type default)
		)
		(layer "In4.Cu")
	)
	(gr_arc
		(start 30.806644 -476.094806)
		(mid 31.426658 -476.64624)
		(end 31.978092 -476.026226)
		(stroke
			(width 0.2)
			(type default)
		)
		(layer "In4.Cu")
	)
	(gr_arc
		(start 30.909006 -267.728446)
		(mid 31.495619 -268.31544)
		(end 32.082486 -267.7287)
		(stroke
			(width 0.2)
			(type default)
		)
		(layer "In4.Cu")
	)
	(gr_line
		(start 30.909006 -266.8651)
		(end 30.909006 -267.728446)
		(stroke
			(width 0.2)
			(type default)
		)
		(layer "In4.Cu")
	)
	(gr_line
		(start 30.912308 -372.184168)
		(end 31.034736 -373.248428)
		(stroke
			(width 0.2)
			(type default)
		)
		(layer "In4.Cu")
	)
	(gr_line
		(start 30.914848 -372.183914)
		(end 30.912308 -372.184168)
		(stroke
			(width 0.2)
			(type default)
		)
		(layer "In4.Cu")
	)
	(gr_arc
		(start 31.016702 -274.618958)
		(mid 31.603442 -275.205698)
		(end 32.190182 -274.618958)
		(stroke
			(width 0.2)
			(type default)
		)
		(layer "In4.Cu")
	)
	(gr_line
		(start 31.016702 -273.690842)
		(end 31.016702 -274.618958)
		(stroke
			(width 0.2)
			(type default)
		)
		(layer "In4.Cu")
	)
	(gr_line
		(start 31.034736 -373.248428)
		(end 31.03499 -373.248682)
		(stroke
			(width 0.2)
			(type default)
		)
		(layer "In4.Cu")
	)
	(gr_line
		(start 31.03499 -373.248682)
		(end 31.037276 -373.248428)
		(stroke
			(width 0.2)
			(type default)
		)
		(layer "In4.Cu")
	)
	(gr_arc
		(start 31.037276 -373.248428)
		(mid 31.630874 -373.719598)
		(end 32.102044 -373.126)
		(stroke
			(width 0.2)
			(type default)
		)
		(layer "In4.Cu")
	)
	(gr_arc
		(start 31.290006 -162.2933)
		(mid 31.876746 -162.88004)
		(end 32.463486 -162.2933)
		(stroke
			(width 0.2)
			(type default)
		)
		(layer "In4.Cu")
	)
	(gr_line
		(start 31.290006 -161.4297)
		(end 31.290006 -162.2933)
		(stroke
			(width 0.2)
			(type default)
		)
		(layer "In4.Cu")
	)
	(gr_line
		(start 31.671768 -64.249046)
		(end 31.674308 -64.2493)
		(stroke
			(width 0.2)
			(type default)
		)
		(layer "In4.Cu")
	)
	(gr_line
		(start 31.674308 -64.2493)
		(end 31.776416 -63.350648)
		(stroke
			(width 0.2)
			(type default)
		)
		(layer "In4.Cu")
	)
	(gr_arc
		(start 31.773876 -63.350394)
		(mid 31.25724 -62.70117)
		(end 30.608016 -63.217806)
		(stroke
			(width 0.2)
			(type default)
		)
		(layer "In4.Cu")
	)
	(gr_line
		(start 31.776416 -63.350648)
		(end 31.773876 -63.350394)
		(stroke
			(width 0.2)
			(type default)
		)
		(layer "In4.Cu")
	)
	(gr_arc
		(start 31.927546 -475.163896)
		(mid 31.307532 -474.612462)
		(end 30.756098 -475.232476)
		(stroke
			(width 0.2)
			(type default)
		)
		(layer "In4.Cu")
	)
	(gr_line
		(start 31.929832 -475.163642)
		(end 31.927546 -475.163896)
		(stroke
			(width 0.2)
			(type default)
		)
		(layer "In4.Cu")
	)
	(gr_line
		(start 31.930086 -475.163896)
		(end 31.929832 -475.163642)
		(stroke
			(width 0.2)
			(type default)
		)
		(layer "In4.Cu")
	)
	(gr_line
		(start 31.978092 -476.026226)
		(end 31.980632 -476.025972)
		(stroke
			(width 0.2)
			(type default)
		)
		(layer "In4.Cu")
	)
	(gr_arc
		(start 31.979616 -372.061486)
		(mid 31.386018 -371.590316)
		(end 30.914848 -372.183914)
		(stroke
			(width 0.2)
			(type default)
		)
		(layer "In4.Cu")
	)
	(gr_line
		(start 31.980632 -476.025972)
		(end 31.930086 -475.163896)
		(stroke
			(width 0.2)
			(type default)
		)
		(layer "In4.Cu")
	)
	(gr_line
		(start 31.982156 -372.061232)
		(end 31.979616 -372.061486)
		(stroke
			(width 0.2)
			(type default)
		)
		(layer "In4.Cu")
	)
	(gr_line
		(start 32.082486 -267.7287)
		(end 32.082486 -266.8651)
		(stroke
			(width 0.2)
			(type default)
		)
		(layer "In4.Cu")
	)
	(gr_arc
		(start 32.082486 -266.8651)
		(mid 31.495746 -266.27836)
		(end 30.909006 -266.8651)
		(stroke
			(width 0.2)
			(type default)
		)
		(layer "In4.Cu")
	)
	(gr_line
		(start 32.102044 -373.126)
		(end 32.104584 -373.125746)
		(stroke
			(width 0.2)
			(type default)
		)
		(layer "In4.Cu")
	)
	(gr_line
		(start 32.104584 -373.125746)
		(end 31.982156 -372.061232)
		(stroke
			(width 0.2)
			(type default)
		)
		(layer "In4.Cu")
	)
	(gr_line
		(start 32.190182 -274.618958)
		(end 32.190182 -273.691096)
		(stroke
			(width 0.2)
			(type default)
		)
		(layer "In4.Cu")
	)
	(gr_arc
		(start 32.190182 -273.691096)
		(mid 31.603569 -273.104102)
		(end 31.016702 -273.690842)
		(stroke
			(width 0.2)
			(type default)
		)
		(layer "In4.Cu")
	)
	(gr_arc
		(start 32.361886 -163.402518)
		(mid 31.945616 -164.123487)
		(end 32.66948 -164.53485)
		(stroke
			(width 0.2)
			(type default)
		)
		(layer "In4.Cu")
	)
	(gr_line
		(start 32.463486 -162.2933)
		(end 32.463486 -161.429954)
		(stroke
			(width 0.2)
			(type default)
		)
		(layer "In4.Cu")
	)
	(gr_arc
		(start 32.463486 -161.429954)
		(mid 31.876873 -160.84296)
		(end 31.290006 -161.4297)
		(stroke
			(width 0.2)
			(type default)
		)
		(layer "In4.Cu")
	)
	(gr_line
		(start 32.66948 -164.53485)
		(end 33.533334 -164.29355)
		(stroke
			(width 0.2)
			(type default)
		)
		(layer "In4.Cu")
	)
	(gr_line
		(start 33.217866 -163.16325)
		(end 32.361886 -163.402518)
		(stroke
			(width 0.2)
			(type default)
		)
		(layer "In4.Cu")
	)
	(gr_arc
		(start 33.533334 -164.29355)
		(mid 33.94075 -163.570666)
		(end 33.217866 -163.16325)
		(stroke
			(width 0.2)
			(type default)
		)
		(layer "In4.Cu")
	)
	(gr_arc
		(start 34.332418 -274.618196)
		(mid 34.918396 -275.205698)
		(end 35.505898 -274.61972)
		(stroke
			(width 0.2)
			(type default)
		)
		(layer "In4.Cu")
	)
	(gr_line
		(start 34.333434 -273.698716)
		(end 34.332418 -274.618196)
		(stroke
			(width 0.2)
			(type default)
		)
		(layer "In4.Cu")
	)
	(gr_arc
		(start 34.465006 -473.748354)
		(mid 35.051746 -474.335094)
		(end 35.638486 -473.748354)
		(stroke
			(width 0.2)
			(type default)
		)
		(layer "In4.Cu")
	)
	(gr_line
		(start 34.465006 -472.820238)
		(end 34.465006 -473.748354)
		(stroke
			(width 0.2)
			(type default)
		)
		(layer "In4.Cu")
	)
	(gr_line
		(start 35.505898 -274.61972)
		(end 35.506914 -273.700494)
		(stroke
			(width 0.2)
			(type default)
		)
		(layer "In4.Cu")
	)
	(gr_arc
		(start 35.506914 -273.700494)
		(mid 34.921063 -273.112992)
		(end 34.333434 -273.698716)
		(stroke
			(width 0.2)
			(type default)
		)
		(layer "In4.Cu")
	)
	(gr_line
		(start 35.638486 -473.748354)
		(end 35.638486 -472.820492)
		(stroke
			(width 0.2)
			(type default)
		)
		(layer "In4.Cu")
	)
	(gr_arc
		(start 35.638486 -472.820492)
		(mid 35.051873 -472.233498)
		(end 34.465006 -472.820238)
		(stroke
			(width 0.2)
			(type default)
		)
		(layer "In4.Cu")
	)
	(gr_line
		(start 35.707574 -370.823998)
		(end 35.710114 -370.823998)
		(stroke
			(width 0.2)
			(type default)
		)
		(layer "In4.Cu")
	)
	(gr_arc
		(start 35.710114 -370.823998)
		(mid 36.280598 -371.426486)
		(end 36.883086 -370.856002)
		(stroke
			(width 0.2)
			(type default)
		)
		(layer "In4.Cu")
	)
	(gr_line
		(start 35.73272 -369.90274)
		(end 35.707574 -370.823998)
		(stroke
			(width 0.2)
			(type default)
		)
		(layer "In4.Cu")
	)
	(gr_line
		(start 35.73526 -369.90274)
		(end 35.73272 -369.90274)
		(stroke
			(width 0.2)
			(type default)
		)
		(layer "In4.Cu")
	)
	(gr_arc
		(start 36.049712 -164.879274)
		(mid 36.636452 -165.466014)
		(end 37.223192 -164.879274)
		(stroke
			(width 0.2)
			(type default)
		)
		(layer "In4.Cu")
	)
	(gr_line
		(start 36.049712 -163.920424)
		(end 36.049712 -164.879274)
		(stroke
			(width 0.2)
			(type default)
		)
		(layer "In4.Cu")
	)
	(gr_line
		(start 36.883086 -370.856002)
		(end 36.885626 -370.856002)
		(stroke
			(width 0.2)
			(type default)
		)
		(layer "In4.Cu")
	)
	(gr_line
		(start 36.885626 -370.856002)
		(end 36.910772 -369.934998)
		(stroke
			(width 0.2)
			(type default)
		)
		(layer "In4.Cu")
	)
	(gr_arc
		(start 36.908232 -369.934744)
		(mid 36.337748 -369.332256)
		(end 35.73526 -369.90274)
		(stroke
			(width 0.2)
			(type default)
		)
		(layer "In4.Cu")
	)
	(gr_line
		(start 36.910518 -369.934744)
		(end 36.908232 -369.934744)
		(stroke
			(width 0.2)
			(type default)
		)
		(layer "In4.Cu")
	)
	(gr_line
		(start 36.910772 -369.934998)
		(end 36.910518 -369.934744)
		(stroke
			(width 0.2)
			(type default)
		)
		(layer "In4.Cu")
	)
	(gr_line
		(start 37.223192 -164.879274)
		(end 37.223192 -163.920678)
		(stroke
			(width 0.2)
			(type default)
		)
		(layer "In4.Cu")
	)
	(gr_arc
		(start 37.223192 -163.920678)
		(mid 36.636579 -163.333684)
		(end 36.049712 -163.920424)
		(stroke
			(width 0.2)
			(type default)
		)
		(layer "In4.Cu")
	)
	(gr_arc
		(start 37.513006 -61.850016)
		(mid 38.099746 -62.436756)
		(end 38.686486 -61.850016)
		(stroke
			(width 0.2)
			(type default)
		)
		(layer "In4.Cu")
	)
	(gr_line
		(start 37.513006 -60.891166)
		(end 37.513006 -61.850016)
		(stroke
			(width 0.2)
			(type default)
		)
		(layer "In4.Cu")
	)
	(gr_line
		(start 38.686486 -61.850016)
		(end 38.686486 -60.89142)
		(stroke
			(width 0.2)
			(type default)
		)
		(layer "In4.Cu")
	)
	(gr_arc
		(start 38.686486 -60.89142)
		(mid 38.099873 -60.304426)
		(end 37.513006 -60.891166)
		(stroke
			(width 0.2)
			(type default)
		)
		(layer "In4.Cu")
	)
	(gr_arc
		(start 215.1888 -269.032228)
		(mid 214.610442 -269.62735)
		(end 215.205564 -270.205708)
		(stroke
			(width 0.2)
			(type default)
		)
		(layer "In4.Cu")
	)
	(gr_line
		(start 215.205564 -270.205708)
		(end 216.11971 -270.192754)
		(stroke
			(width 0.2)
			(type default)
		)
		(layer "In4.Cu")
	)
	(gr_line
		(start 215.32342 -167.05072)
		(end 216.186766 -167.066468)
		(stroke
			(width 0.2)
			(type default)
		)
		(layer "In4.Cu")
	)
	(gr_arc
		(start 215.344756 -165.87724)
		(mid 214.747348 -166.453312)
		(end 215.32342 -167.05072)
		(stroke
			(width 0.2)
			(type default)
		)
		(layer "In4.Cu")
	)
	(gr_arc
		(start 215.349836 -62.92342)
		(mid 214.774524 -63.521463)
		(end 215.372442 -64.0969)
		(stroke
			(width 0.2)
			(type default)
		)
		(layer "In4.Cu")
	)
	(gr_line
		(start 215.372442 -64.0969)
		(end 216.236042 -64.080136)
		(stroke
			(width 0.2)
			(type default)
		)
		(layer "In4.Cu")
	)
	(gr_arc
		(start 215.608154 -371.879368)
		(mid 215.031064 -372.475633)
		(end 215.627204 -373.052848)
		(stroke
			(width 0.2)
			(type default)
		)
		(layer "In4.Cu")
	)
	(gr_line
		(start 215.627204 -373.052848)
		(end 216.490804 -373.038624)
		(stroke
			(width 0.2)
			(type default)
		)
		(layer "In4.Cu")
	)
	(gr_arc
		(start 215.92159 -474.661484)
		(mid 215.338406 -475.25178)
		(end 215.928702 -475.834964)
		(stroke
			(width 0.2)
			(type default)
		)
		(layer "In4.Cu")
	)
	(gr_line
		(start 215.928702 -475.834964)
		(end 216.792048 -475.829884)
		(stroke
			(width 0.2)
			(type default)
		)
		(layer "In4.Cu")
	)
	(gr_line
		(start 216.1032 -269.019274)
		(end 215.1888 -269.032228)
		(stroke
			(width 0.2)
			(type default)
		)
		(layer "In4.Cu")
	)
	(gr_arc
		(start 216.11971 -270.192754)
		(mid 216.69832 -269.597759)
		(end 216.1032 -269.019274)
		(stroke
			(width 0.2)
			(type default)
		)
		(layer "In4.Cu")
	)
	(gr_arc
		(start 216.186766 -167.066468)
		(mid 216.78443 -166.490523)
		(end 216.208356 -165.892988)
		(stroke
			(width 0.2)
			(type default)
		)
		(layer "In4.Cu")
	)
	(gr_line
		(start 216.208356 -165.892988)
		(end 215.344756 -165.87724)
		(stroke
			(width 0.2)
			(type default)
		)
		(layer "In4.Cu")
	)
	(gr_line
		(start 216.213182 -62.906656)
		(end 215.349836 -62.92342)
		(stroke
			(width 0.2)
			(type default)
		)
		(layer "In4.Cu")
	)
	(gr_arc
		(start 216.236042 -64.080136)
		(mid 216.811352 -63.481966)
		(end 216.213182 -62.906656)
		(stroke
			(width 0.2)
			(type default)
		)
		(layer "In4.Cu")
	)
	(gr_line
		(start 216.4715 -371.865144)
		(end 215.608154 -371.879368)
		(stroke
			(width 0.2)
			(type default)
		)
		(layer "In4.Cu")
	)
	(gr_arc
		(start 216.490804 -373.038624)
		(mid 217.067892 -372.442232)
		(end 216.4715 -371.865144)
		(stroke
			(width 0.2)
			(type default)
		)
		(layer "In4.Cu")
	)
	(gr_line
		(start 216.78519 -474.656404)
		(end 215.92159 -474.661484)
		(stroke
			(width 0.2)
			(type default)
		)
		(layer "In4.Cu")
	)
	(gr_arc
		(start 216.792048 -475.829884)
		(mid 217.375485 -475.239715)
		(end 216.78519 -474.656404)
		(stroke
			(width 0.2)
			(type default)
		)
		(layer "In4.Cu")
	)
	(gr_arc
		(start 219.609416 -473.86621)
		(mid 220.196156 -474.45295)
		(end 220.782896 -473.86621)
		(stroke
			(width 0.2)
			(type default)
		)
		(layer "In4.Cu")
	)
	(gr_line
		(start 219.609416 -472.90736)
		(end 219.609416 -473.86621)
		(stroke
			(width 0.2)
			(type default)
		)
		(layer "In4.Cu")
	)
	(gr_line
		(start 220.782896 -473.86621)
		(end 220.782896 -472.907614)
		(stroke
			(width 0.2)
			(type default)
		)
		(layer "In4.Cu")
	)
	(gr_arc
		(start 220.782896 -472.907614)
		(mid 220.196283 -472.32062)
		(end 219.609416 -472.90736)
		(stroke
			(width 0.2)
			(type default)
		)
		(layer "In4.Cu")
	)
	(gr_line
		(start 222.386398 -370.80444)
		(end 222.388938 -370.804694)
		(stroke
			(width 0.2)
			(type default)
		)
		(layer "In4.Cu")
	)
	(gr_arc
		(start 222.388938 -370.804694)
		(mid 222.941642 -371.423438)
		(end 223.560386 -370.870734)
		(stroke
			(width 0.2)
			(type default)
		)
		(layer "In4.Cu")
	)
	(gr_arc
		(start 222.417894 -267.792708)
		(mid 222.956374 -268.424152)
		(end 223.587818 -267.885672)
		(stroke
			(width 0.2)
			(type default)
		)
		(layer "In4.Cu")
	)
	(gr_line
		(start 222.437452 -369.905026)
		(end 222.386398 -370.80444)
		(stroke
			(width 0.2)
			(type default)
		)
		(layer "In4.Cu")
	)
	(gr_line
		(start 222.439992 -369.90528)
		(end 222.437452 -369.905026)
		(stroke
			(width 0.2)
			(type default)
		)
		(layer "In4.Cu")
	)
	(gr_arc
		(start 222.445072 -61.945012)
		(mid 223.031812 -62.531752)
		(end 223.618552 -61.945012)
		(stroke
			(width 0.2)
			(type default)
		)
		(layer "In4.Cu")
	)
	(gr_line
		(start 222.445072 -60.986162)
		(end 222.445072 -61.945012)
		(stroke
			(width 0.2)
			(type default)
		)
		(layer "In4.Cu")
	)
	(gr_line
		(start 222.48622 -266.931648)
		(end 222.417894 -267.792708)
		(stroke
			(width 0.2)
			(type default)
		)
		(layer "In4.Cu")
	)
	(gr_arc
		(start 222.576644 -164.934392)
		(mid 223.163384 -165.521132)
		(end 223.750124 -164.934392)
		(stroke
			(width 0.2)
			(type default)
		)
		(layer "In4.Cu")
	)
	(gr_line
		(start 222.576644 -163.975542)
		(end 222.576644 -164.934392)
		(stroke
			(width 0.2)
			(type default)
		)
		(layer "In4.Cu")
	)
	(gr_line
		(start 223.560386 -370.870734)
		(end 223.562926 -370.870988)
		(stroke
			(width 0.2)
			(type default)
		)
		(layer "In4.Cu")
	)
	(gr_line
		(start 223.562926 -370.870988)
		(end 223.61398 -369.971828)
		(stroke
			(width 0.2)
			(type default)
		)
		(layer "In4.Cu")
	)
	(gr_line
		(start 223.587818 -267.885672)
		(end 223.656144 -267.024866)
		(stroke
			(width 0.2)
			(type default)
		)
		(layer "In4.Cu")
	)
	(gr_arc
		(start 223.61144 -369.971574)
		(mid 223.058863 -369.352569)
		(end 222.439992 -369.90528)
		(stroke
			(width 0.2)
			(type default)
		)
		(layer "In4.Cu")
	)
	(gr_line
		(start 223.613726 -369.971574)
		(end 223.61144 -369.971574)
		(stroke
			(width 0.2)
			(type default)
		)
		(layer "In4.Cu")
	)
	(gr_line
		(start 223.61398 -369.971828)
		(end 223.613726 -369.971574)
		(stroke
			(width 0.2)
			(type default)
		)
		(layer "In4.Cu")
	)
	(gr_line
		(start 223.618552 -61.945012)
		(end 223.618552 -60.986416)
		(stroke
			(width 0.2)
			(type default)
		)
		(layer "In4.Cu")
	)
	(gr_arc
		(start 223.618552 -60.986416)
		(mid 223.031939 -60.399422)
		(end 222.445072 -60.986162)
		(stroke
			(width 0.2)
			(type default)
		)
		(layer "In4.Cu")
	)
	(gr_arc
		(start 223.656144 -267.024866)
		(mid 223.11779 -266.393432)
		(end 222.48622 -266.931648)
		(stroke
			(width 0.2)
			(type default)
		)
		(layer "In4.Cu")
	)
	(gr_line
		(start 223.750124 -164.934392)
		(end 223.750124 -163.975796)
		(stroke
			(width 0.2)
			(type default)
		)
		(layer "In4.Cu")
	)
	(gr_arc
		(start 223.750124 -163.975796)
		(mid 223.163511 -163.388802)
		(end 222.576644 -163.975542)
		(stroke
			(width 0.2)
			(type default)
		)
		(layer "In4.Cu")
	)
	(gr_line
		(start 10.985754 -439.991246)
		(end 10.9855 -439.9915)
		(stroke
			(width 0.05715)
			(type default)
		)
		(layer "In5.Cu")
	)
	(gr_line
		(start 11.0744 -441.2234)
		(end 11.081512 -441.216288)
		(stroke
			(width 0.05715)
			(type default)
		)
		(layer "In5.Cu")
	)
	(gr_arc
		(start 11.081512 -441.216288)
		(mid 11.207812 -441.027266)
		(end 11.2522 -440.8043)
		(stroke
			(width 0.05715)
			(type default)
		)
		(layer "In5.Cu")
	)
	(gr_line
		(start 11.201146 -439.775854)
		(end 11.416792 -439.9915)
		(stroke
			(width 0.05715)
			(type default)
		)
		(layer "In5.Cu")
	)
	(gr_line
		(start 11.2395 -437.120792)
		(end 11.455146 -436.905146)
		(stroke
			(width 0.05715)
			(type default)
		)
		(layer "In5.Cu")
	)
	(gr_line
		(start 11.2395 -436.6895)
		(end 11.239754 -436.689754)
		(stroke
			(width 0.05715)
			(type default)
		)
		(layer "In5.Cu")
	)
	(gr_arc
		(start 11.557 -440.563)
		(mid 11.608375 -440.821156)
		(end 11.754612 -441.040012)
		(stroke
			(width 0.05715)
			(type default)
		)
		(layer "In5.Cu")
	)
	(gr_arc
		(start 11.652758 -438.105042)
		(mid 11.997927 -438.335726)
		(end 12.405106 -438.4167)
		(stroke
			(width 0.05715)
			(type default)
		)
		(layer "In5.Cu")
	)
	(gr_line
		(start 11.754612 -441.040012)
		(end 11.938 -441.2234)
		(stroke
			(width 0.05715)
			(type default)
		)
		(layer "In5.Cu")
	)
	(gr_arc
		(start 12.405106 -438.7215)
		(mid 11.997943 -438.802518)
		(end 11.652758 -439.033158)
		(stroke
			(width 0.05715)
			(type default)
		)
		(layer "In5.Cu")
	)
	(gr_arc
		(start 12.80414 -176.733454)
		(mid 13.11366 -176.940269)
		(end 13.478764 -177.012854)
		(stroke
			(width 0.05715)
			(type default)
		)
		(layer "In5.Cu")
	)
	(gr_arc
		(start 13.450062 -177.317654)
		(mid 13.085362 -177.390202)
		(end 12.7762 -177.5968)
		(stroke
			(width 0.05715)
			(type default)
		)
		(layer "In5.Cu")
	)
	(gr_line
		(start 15.239746 -136.5377)
		(end 15.368016 -136.409176)
		(stroke
			(width 0.05715)
			(type default)
		)
		(layer "In5.Cu")
	)
	(gr_line
		(start 15.240762 -135.6741)
		(end 15.258796 -135.692134)
		(stroke
			(width 0.05715)
			(type default)
		)
		(layer "In5.Cu")
	)
	(gr_arc
		(start 15.258796 -135.692134)
		(mid 15.529743 -135.873175)
		(end 15.849346 -135.936736)
		(stroke
			(width 0.05715)
			(type default)
		)
		(layer "In5.Cu")
	)
	(gr_arc
		(start 15.773146 -136.241536)
		(mid 15.553899 -136.28505)
		(end 15.368016 -136.409176)
		(stroke
			(width 0.05715)
			(type default)
		)
		(layer "In5.Cu")
	)
	(gr_arc
		(start 16.301212 -123.499118)
		(mid 16.66364 -123.741284)
		(end 17.091152 -123.82627)
		(stroke
			(width 0.05715)
			(type default)
		)
		(layer "In5.Cu")
	)
	(gr_line
		(start 16.356838 -120.509284)
		(end 16.578834 -120.287288)
		(stroke
			(width 0.05715)
			(type default)
		)
		(layer "In5.Cu")
	)
	(gr_arc
		(start 16.358362 -119.645684)
		(mid 16.58654 -119.798148)
		(end 16.855694 -119.851678)
		(stroke
			(width 0.05715)
			(type default)
		)
		(layer "In5.Cu")
	)
	(gr_arc
		(start 16.882364 -124.13107)
		(mid 16.580085 -124.191234)
		(end 16.323818 -124.362464)
		(stroke
			(width 0.05715)
			(type default)
		)
		(layer "In5.Cu")
	)
	(gr_arc
		(start 16.894556 -120.156478)
		(mid 16.723715 -120.190536)
		(end 16.578834 -120.287288)
		(stroke
			(width 0.05715)
			(type default)
		)
		(layer "In5.Cu")
	)
	(gr_line
		(start 17.527016 -177.798984)
		(end 17.742662 -178.01463)
		(stroke
			(width 0.05715)
			(type default)
		)
		(layer "In5.Cu")
	)
	(gr_line
		(start 17.742662 -177.583338)
		(end 17.742408 -177.583592)
		(stroke
			(width 0.05715)
			(type default)
		)
		(layer "In5.Cu")
	)
	(gr_line
		(start 17.818608 -439.127392)
		(end 17.818354 -439.127646)
		(stroke
			(width 0.05715)
			(type default)
		)
		(layer "In5.Cu")
	)
	(gr_line
		(start 18.008854 -437.032146)
		(end 18.2245 -437.247792)
		(stroke
			(width 0.05715)
			(type default)
		)
		(layer "In5.Cu")
	)
	(gr_line
		(start 18.034 -438.912)
		(end 18.249646 -439.127646)
		(stroke
			(width 0.05715)
			(type default)
		)
		(layer "In5.Cu")
	)
	(gr_line
		(start 18.2245 -436.8165)
		(end 18.224246 -436.816754)
		(stroke
			(width 0.05715)
			(type default)
		)
		(layer "In5.Cu")
	)
	(gr_arc
		(start 20.246848 -439.8264)
		(mid 20.351713 -439.801175)
		(end 20.434808 -439.73242)
		(stroke
			(width 0.05715)
			(type default)
		)
		(layer "In5.Cu")
	)
	(gr_line
		(start 20.5486 -236.0422)
		(end 20.548854 -236.042454)
		(stroke
			(width 0.05715)
			(type default)
		)
		(layer "In5.Cu")
	)
	(gr_line
		(start 20.554188 -440.1312)
		(end 21.034248 -440.1312)
		(stroke
			(width 0.05715)
			(type default)
		)
		(layer "In5.Cu")
	)
	(gr_arc
		(start 20.622768 -439.63844)
		(mid 20.517928 -439.663684)
		(end 20.434808 -439.73242)
		(stroke
			(width 0.05715)
			(type default)
		)
		(layer "In5.Cu")
	)
	(gr_line
		(start 20.622768 -439.63844)
		(end 20.965668 -439.63844)
		(stroke
			(width 0.05715)
			(type default)
		)
		(layer "In5.Cu")
	)
	(gr_line
		(start 20.713954 -235.876846)
		(end 20.9296 -235.6612)
		(stroke
			(width 0.05715)
			(type default)
		)
		(layer "In5.Cu")
	)
	(gr_line
		(start 20.764246 -236.257846)
		(end 20.979892 -236.0422)
		(stroke
			(width 0.05715)
			(type default)
		)
		(layer "In5.Cu")
	)
	(gr_line
		(start 20.853654 -239.903254)
		(end 21.0693 -240.1189)
		(stroke
			(width 0.05715)
			(type default)
		)
		(layer "In5.Cu")
	)
	(gr_line
		(start 21.144992 -235.876592)
		(end 21.145246 -235.876846)
		(stroke
			(width 0.05715)
			(type default)
		)
		(layer "In5.Cu")
	)
	(gr_arc
		(start 21.153628 -439.73242)
		(mid 21.070534 -439.663684)
		(end 20.965668 -439.63844)
		(stroke
			(width 0.05715)
			(type default)
		)
		(layer "In5.Cu")
	)
	(gr_arc
		(start 21.153628 -439.73242)
		(mid 21.236736 -439.801151)
		(end 21.341588 -439.8264)
		(stroke
			(width 0.05715)
			(type default)
		)
		(layer "In5.Cu")
	)
	(gr_line
		(start 21.284946 -239.903254)
		(end 21.284692 -239.903508)
		(stroke
			(width 0.05715)
			(type default)
		)
		(layer "In5.Cu")
	)
	(gr_arc
		(start 21.684488 -439.8264)
		(mid 21.789342 -439.801161)
		(end 21.872448 -439.73242)
		(stroke
			(width 0.05715)
			(type default)
		)
		(layer "In5.Cu")
	)
	(gr_line
		(start 21.818346 -133.6167)
		(end 22.123146 -133.6167)
		(stroke
			(width 0.05715)
			(type default)
		)
		(layer "In5.Cu")
	)
	(gr_line
		(start 21.894546 -136.15035)
		(end 22.109938 -135.934704)
		(stroke
			(width 0.05715)
			(type default)
		)
		(layer "In5.Cu")
	)
	(gr_line
		(start 21.894546 -135.4709)
		(end 21.919946 -135.4963)
		(stroke
			(width 0.05715)
			(type default)
		)
		(layer "In5.Cu")
	)
	(gr_arc
		(start 21.894546 -135.1915)
		(mid 21.836667 -135.3312)
		(end 21.894546 -135.4709)
		(stroke
			(width 0.05715)
			(type default)
		)
		(layer "In5.Cu")
	)
	(gr_arc
		(start 21.919946 -135.4963)
		(mid 22.00431 -135.552703)
		(end 22.103842 -135.5725)
		(stroke
			(width 0.05715)
			(type default)
		)
		(layer "In5.Cu")
	)
	(gr_line
		(start 21.991828 -440.1312)
		(end 22.471888 -440.1312)
		(stroke
			(width 0.05715)
			(type default)
		)
		(layer "In5.Cu")
	)
	(gr_arc
		(start 22.060408 -439.63844)
		(mid 21.955568 -439.663684)
		(end 21.872448 -439.73242)
		(stroke
			(width 0.05715)
			(type default)
		)
		(layer "In5.Cu")
	)
	(gr_line
		(start 22.060408 -439.63844)
		(end 22.403308 -439.63844)
		(stroke
			(width 0.05715)
			(type default)
		)
		(layer "In5.Cu")
	)
	(gr_line
		(start 22.123146 -133.3119)
		(end 22.123146 -133.312154)
		(stroke
			(width 0.05715)
			(type default)
		)
		(layer "In5.Cu")
	)
	(gr_arc
		(start 22.248876 -135.8773)
		(mid 22.173685 -135.892163)
		(end 22.109938 -135.934704)
		(stroke
			(width 0.05715)
			(type default)
		)
		(layer "In5.Cu")
	)
	(gr_arc
		(start 22.591268 -439.73242)
		(mid 22.508174 -439.663684)
		(end 22.403308 -439.63844)
		(stroke
			(width 0.05715)
			(type default)
		)
		(layer "In5.Cu")
	)
	(gr_arc
		(start 22.591268 -439.73242)
		(mid 22.674372 -439.801172)
		(end 22.779228 -439.8264)
		(stroke
			(width 0.05715)
			(type default)
		)
		(layer "In5.Cu")
	)
	(gr_arc
		(start 23.122128 -439.8264)
		(mid 23.226971 -439.801147)
		(end 23.310088 -439.73242)
		(stroke
			(width 0.05715)
			(type default)
		)
		(layer "In5.Cu")
	)
	(gr_line
		(start 23.429468 -440.1312)
		(end 23.909528 -440.1312)
		(stroke
			(width 0.05715)
			(type default)
		)
		(layer "In5.Cu")
	)
	(gr_arc
		(start 23.498048 -439.63844)
		(mid 23.393208 -439.663684)
		(end 23.310088 -439.73242)
		(stroke
			(width 0.05715)
			(type default)
		)
		(layer "In5.Cu")
	)
	(gr_line
		(start 23.498048 -439.63844)
		(end 23.840948 -439.63844)
		(stroke
			(width 0.05715)
			(type default)
		)
		(layer "In5.Cu")
	)
	(gr_arc
		(start 24.028908 -439.73242)
		(mid 23.945814 -439.663684)
		(end 23.840948 -439.63844)
		(stroke
			(width 0.05715)
			(type default)
		)
		(layer "In5.Cu")
	)
	(gr_arc
		(start 24.028908 -439.73242)
		(mid 24.112015 -439.801158)
		(end 24.216868 -439.8264)
		(stroke
			(width 0.05715)
			(type default)
		)
		(layer "In5.Cu")
	)
	(gr_line
		(start 24.103076 -250.318778)
		(end 24.318722 -250.534424)
		(stroke
			(width 0.05715)
			(type default)
		)
		(layer "In5.Cu")
	)
	(gr_line
		(start 24.534368 -250.318778)
		(end 24.534114 -250.319032)
		(stroke
			(width 0.05715)
			(type default)
		)
		(layer "In5.Cu")
	)
	(gr_arc
		(start 24.559768 -439.8264)
		(mid 24.664628 -439.801168)
		(end 24.747728 -439.73242)
		(stroke
			(width 0.05715)
			(type default)
		)
		(layer "In5.Cu")
	)
	(gr_line
		(start 24.867108 -440.1312)
		(end 25.347168 -440.1312)
		(stroke
			(width 0.05715)
			(type default)
		)
		(layer "In5.Cu")
	)
	(gr_arc
		(start 24.935688 -439.63844)
		(mid 24.830848 -439.663684)
		(end 24.747728 -439.73242)
		(stroke
			(width 0.05715)
			(type default)
		)
		(layer "In5.Cu")
	)
	(gr_line
		(start 24.935688 -439.63844)
		(end 25.278588 -439.63844)
		(stroke
			(width 0.05715)
			(type default)
		)
		(layer "In5.Cu")
	)
	(gr_line
		(start 25.082754 -268.668246)
		(end 25.0825 -268.6685)
		(stroke
			(width 0.05715)
			(type default)
		)
		(layer "In5.Cu")
	)
	(gr_line
		(start 25.298146 -268.452854)
		(end 25.513792 -268.6685)
		(stroke
			(width 0.05715)
			(type default)
		)
		(layer "In5.Cu")
	)
	(gr_arc
		(start 25.466548 -439.73242)
		(mid 25.383454 -439.663684)
		(end 25.278588 -439.63844)
		(stroke
			(width 0.05715)
			(type default)
		)
		(layer "In5.Cu")
	)
	(gr_arc
		(start 25.466548 -439.73242)
		(mid 25.54965 -439.801179)
		(end 25.654508 -439.8264)
		(stroke
			(width 0.05715)
			(type default)
		)
		(layer "In5.Cu")
	)
	(gr_line
		(start 28.449016 -440.33313)
		(end 28.664662 -440.548776)
		(stroke
			(width 0.05715)
			(type default)
		)
		(layer "In5.Cu")
	)
	(gr_line
		(start 28.664662 -440.117484)
		(end 28.664408 -440.117738)
		(stroke
			(width 0.05715)
			(type default)
		)
		(layer "In5.Cu")
	)
	(gr_arc
		(start 28.829 -341.503)
		(mid 29.174175 -341.733658)
		(end 29.581348 -341.814658)
		(stroke
			(width 0.05715)
			(type default)
		)
		(layer "In5.Cu")
	)
	(gr_arc
		(start 29.581348 -342.119458)
		(mid 29.174171 -342.200451)
		(end 28.829 -342.431116)
		(stroke
			(width 0.05715)
			(type default)
		)
		(layer "In5.Cu")
	)
	(gr_line
		(start 30.112716 -441.565538)
		(end 30.328362 -441.781184)
		(stroke
			(width 0.05715)
			(type default)
		)
		(layer "In5.Cu")
	)
	(gr_line
		(start 30.11297 -441.996576)
		(end 30.112716 -441.99683)
		(stroke
			(width 0.05715)
			(type default)
		)
		(layer "In5.Cu")
	)
	(gr_line
		(start 30.301946 -156.991304)
		(end 30.301946 -157.471364)
		(stroke
			(width 0.05715)
			(type default)
		)
		(layer "In5.Cu")
	)
	(gr_line
		(start 30.301946 -155.553664)
		(end 30.301946 -156.033724)
		(stroke
			(width 0.05715)
			(type default)
		)
		(layer "In5.Cu")
	)
	(gr_arc
		(start 30.606746 -156.683964)
		(mid 30.63199 -156.788804)
		(end 30.700726 -156.871924)
		(stroke
			(width 0.05715)
			(type default)
		)
		(layer "In5.Cu")
	)
	(gr_arc
		(start 30.606746 -155.246324)
		(mid 30.631901 -155.351234)
		(end 30.700726 -155.434284)
		(stroke
			(width 0.05715)
			(type default)
		)
		(layer "In5.Cu")
	)
	(gr_arc
		(start 30.700726 -157.590744)
		(mid 30.63199 -157.673838)
		(end 30.606746 -157.778704)
		(stroke
			(width 0.05715)
			(type default)
		)
		(layer "In5.Cu")
	)
	(gr_arc
		(start 30.700726 -157.590744)
		(mid 30.76948 -157.507641)
		(end 30.794706 -157.402784)
		(stroke
			(width 0.05715)
			(type default)
		)
		(layer "In5.Cu")
	)
	(gr_arc
		(start 30.700726 -156.153104)
		(mid 30.63199 -156.236198)
		(end 30.606746 -156.341064)
		(stroke
			(width 0.05715)
			(type default)
		)
		(layer "In5.Cu")
	)
	(gr_arc
		(start 30.700726 -156.153104)
		(mid 30.769541 -156.07004)
		(end 30.794706 -155.965144)
		(stroke
			(width 0.05715)
			(type default)
		)
		(layer "In5.Cu")
	)
	(gr_arc
		(start 30.794706 -157.059884)
		(mid 30.769458 -156.955037)
		(end 30.700726 -156.871924)
		(stroke
			(width 0.05715)
			(type default)
		)
		(layer "In5.Cu")
	)
	(gr_line
		(start 30.794706 -157.059884)
		(end 30.794706 -157.402784)
		(stroke
			(width 0.05715)
			(type default)
		)
		(layer "In5.Cu")
	)
	(gr_arc
		(start 30.794706 -155.622244)
		(mid 30.769479 -155.51738)
		(end 30.700726 -155.434284)
		(stroke
			(width 0.05715)
			(type default)
		)
		(layer "In5.Cu")
	)
	(gr_line
		(start 30.794706 -155.622244)
		(end 30.794706 -155.965144)
		(stroke
			(width 0.05715)
			(type default)
		)
		(layer "In5.Cu")
	)
	(gr_line
		(start 31.089346 -274.32)
		(end 31.0896 -274.32)
		(stroke
			(width 0.05715)
			(type default)
		)
		(layer "In5.Cu")
	)
	(gr_arc
		(start 31.0896 -274.0152)
		(mid 31.264606 -273.980295)
		(end 31.412942 -273.881088)
		(stroke
			(width 0.05715)
			(type default)
		)
		(layer "In5.Cu")
	)
	(gr_line
		(start 31.165546 -161.937446)
		(end 31.165546 -161.9377)
		(stroke
			(width 0.05715)
			(type default)
		)
		(layer "In5.Cu")
	)
	(gr_line
		(start 31.165546 -161.6329)
		(end 31.444946 -161.6329)
		(stroke
			(width 0.05715)
			(type default)
		)
		(layer "In5.Cu")
	)
	(gr_line
		(start 31.412942 -273.881088)
		(end 31.603442 -273.690842)
		(stroke
			(width 0.05715)
			(type default)
		)
		(layer "In5.Cu")
	)
	(gr_arc
		(start 31.444946 -161.6329)
		(mid 31.656219 -161.590969)
		(end 31.835344 -161.471356)
		(stroke
			(width 0.05715)
			(type default)
		)
		(layer "In5.Cu")
	)
	(gr_arc
		(start 31.456376 -274.471892)
		(mid 31.288085 -274.359501)
		(end 31.0896 -274.32)
		(stroke
			(width 0.05715)
			(type default)
		)
		(layer "In5.Cu")
	)
	(gr_line
		(start 31.456376 -274.471892)
		(end 31.603442 -274.618958)
		(stroke
			(width 0.05715)
			(type default)
		)
		(layer "In5.Cu")
	)
	(gr_arc
		(start 31.574994 -161.991548)
		(mid 31.515324 -161.951687)
		(end 31.444946 -161.9377)
		(stroke
			(width 0.05715)
			(type default)
		)
		(layer "In5.Cu")
	)
	(gr_line
		(start 31.574994 -161.991548)
		(end 31.876746 -162.2933)
		(stroke
			(width 0.05715)
			(type default)
		)
		(layer "In5.Cu")
	)
	(gr_line
		(start 31.835344 -161.471356)
		(end 31.876746 -161.4297)
		(stroke
			(width 0.05715)
			(type default)
		)
		(layer "In5.Cu")
	)
	(gr_line
		(start 32.1945 -437.8325)
		(end 32.410146 -437.616854)
		(stroke
			(width 0.05715)
			(type default)
		)
		(layer "In5.Cu")
	)
	(gr_line
		(start 32.409892 -438.047892)
		(end 32.410146 -438.048146)
		(stroke
			(width 0.05715)
			(type default)
		)
		(layer "In5.Cu")
	)
	(gr_arc
		(start 33.885886 -390.48944)
		(mid 33.911142 -390.594281)
		(end 33.979866 -390.6774)
		(stroke
			(width 0.05715)
			(type default)
		)
		(layer "In5.Cu")
	)
	(gr_line
		(start 33.885886 -390.14654)
		(end 33.885886 -390.48944)
		(stroke
			(width 0.05715)
			(type default)
		)
		(layer "In5.Cu")
	)
	(gr_arc
		(start 33.885886 -389.0518)
		(mid 33.911128 -389.156652)
		(end 33.979866 -389.23976)
		(stroke
			(width 0.05715)
			(type default)
		)
		(layer "In5.Cu")
	)
	(gr_line
		(start 33.885886 -388.7089)
		(end 33.885886 -389.0518)
		(stroke
			(width 0.05715)
			(type default)
		)
		(layer "In5.Cu")
	)
	(gr_arc
		(start 33.885886 -387.61416)
		(mid 33.911114 -387.719023)
		(end 33.979866 -387.80212)
		(stroke
			(width 0.05715)
			(type default)
		)
		(layer "In5.Cu")
	)
	(gr_line
		(start 33.885886 -387.27126)
		(end 33.885886 -387.61416)
		(stroke
			(width 0.05715)
			(type default)
		)
		(layer "In5.Cu")
	)
	(gr_arc
		(start 33.885886 -386.17652)
		(mid 33.911135 -386.281367)
		(end 33.979866 -386.36448)
		(stroke
			(width 0.05715)
			(type default)
		)
		(layer "In5.Cu")
	)
	(gr_line
		(start 33.885886 -385.83362)
		(end 33.885886 -386.17652)
		(stroke
			(width 0.05715)
			(type default)
		)
		(layer "In5.Cu")
	)
	(gr_arc
		(start 33.885886 -384.73888)
		(mid 33.911121 -384.843738)
		(end 33.979866 -384.92684)
		(stroke
			(width 0.05715)
			(type default)
		)
		(layer "In5.Cu")
	)
	(gr_line
		(start 33.885886 -384.39598)
		(end 33.885886 -384.73888)
		(stroke
			(width 0.05715)
			(type default)
		)
		(layer "In5.Cu")
	)
	(gr_arc
		(start 33.885886 -365.354362)
		(mid 33.911026 -365.459274)
		(end 33.979866 -365.542322)
		(stroke
			(width 0.05715)
			(type default)
		)
		(layer "In5.Cu")
	)
	(gr_line
		(start 33.885886 -365.011462)
		(end 33.885886 -365.354362)
		(stroke
			(width 0.05715)
			(type default)
		)
		(layer "In5.Cu")
	)
	(gr_arc
		(start 33.885886 -363.916722)
		(mid 33.911047 -364.021618)
		(end 33.979866 -364.104682)
		(stroke
			(width 0.05715)
			(type default)
		)
		(layer "In5.Cu")
	)
	(gr_line
		(start 33.885886 -363.573822)
		(end 33.885886 -363.916722)
		(stroke
			(width 0.05715)
			(type default)
		)
		(layer "In5.Cu")
	)
	(gr_arc
		(start 33.885886 -362.479082)
		(mid 33.911033 -362.583989)
		(end 33.979866 -362.667042)
		(stroke
			(width 0.05715)
			(type default)
		)
		(layer "In5.Cu")
	)
	(gr_line
		(start 33.885886 -362.136182)
		(end 33.885886 -362.479082)
		(stroke
			(width 0.05715)
			(type default)
		)
		(layer "In5.Cu")
	)
	(gr_arc
		(start 33.885886 -361.041442)
		(mid 33.911054 -361.146332)
		(end 33.979866 -361.229402)
		(stroke
			(width 0.05715)
			(type default)
		)
		(layer "In5.Cu")
	)
	(gr_line
		(start 33.885886 -360.698542)
		(end 33.885886 -361.041442)
		(stroke
			(width 0.05715)
			(type default)
		)
		(layer "In5.Cu")
	)
	(gr_arc
		(start 33.885886 -359.603802)
		(mid 33.91104 -359.708703)
		(end 33.979866 -359.791762)
		(stroke
			(width 0.05715)
			(type default)
		)
		(layer "In5.Cu")
	)
	(gr_line
		(start 33.885886 -359.260902)
		(end 33.885886 -359.603802)
		(stroke
			(width 0.05715)
			(type default)
		)
		(layer "In5.Cu")
	)
	(gr_arc
		(start 33.979866 -389.95858)
		(mid 33.911048 -390.041644)
		(end 33.885886 -390.14654)
		(stroke
			(width 0.05715)
			(type default)
		)
		(layer "In5.Cu")
	)
	(gr_arc
		(start 33.979866 -389.95858)
		(mid 34.048602 -389.875486)
		(end 34.073846 -389.77062)
		(stroke
			(width 0.05715)
			(type default)
		)
		(layer "In5.Cu")
	)
	(gr_arc
		(start 33.979866 -388.52094)
		(mid 33.911034 -388.604001)
		(end 33.885886 -388.7089)
		(stroke
			(width 0.05715)
			(type default)
		)
		(layer "In5.Cu")
	)
	(gr_arc
		(start 33.979866 -388.52094)
		(mid 34.048602 -388.437846)
		(end 34.073846 -388.33298)
		(stroke
			(width 0.05715)
			(type default)
		)
		(layer "In5.Cu")
	)
	(gr_arc
		(start 33.979866 -387.0833)
		(mid 33.911055 -387.166365)
		(end 33.885886 -387.27126)
		(stroke
			(width 0.05715)
			(type default)
		)
		(layer "In5.Cu")
	)
	(gr_arc
		(start 33.979866 -387.0833)
		(mid 34.048602 -387.000206)
		(end 34.073846 -386.89534)
		(stroke
			(width 0.05715)
			(type default)
		)
		(layer "In5.Cu")
	)
	(gr_arc
		(start 33.979866 -385.64566)
		(mid 33.911041 -385.728722)
		(end 33.885886 -385.83362)
		(stroke
			(width 0.05715)
			(type default)
		)
		(layer "In5.Cu")
	)
	(gr_arc
		(start 33.979866 -385.64566)
		(mid 34.048602 -385.562566)
		(end 34.073846 -385.4577)
		(stroke
			(width 0.05715)
			(type default)
		)
		(layer "In5.Cu")
	)
	(gr_arc
		(start 33.979866 -384.20802)
		(mid 33.911062 -384.291087)
		(end 33.885886 -384.39598)
		(stroke
			(width 0.05715)
			(type default)
		)
		(layer "In5.Cu")
	)
	(gr_arc
		(start 33.979866 -384.20802)
		(mid 34.048602 -384.124926)
		(end 34.073846 -384.02006)
		(stroke
			(width 0.05715)
			(type default)
		)
		(layer "In5.Cu")
	)
	(gr_arc
		(start 33.979866 -364.823502)
		(mid 33.911056 -364.906567)
		(end 33.885886 -365.011462)
		(stroke
			(width 0.05715)
			(type default)
		)
		(layer "In5.Cu")
	)
	(gr_arc
		(start 33.979866 -364.823502)
		(mid 34.048691 -364.740427)
		(end 34.073846 -364.635542)
		(stroke
			(width 0.05715)
			(type default)
		)
		(layer "In5.Cu")
	)
	(gr_arc
		(start 33.979866 -363.385862)
		(mid 33.911042 -363.468924)
		(end 33.885886 -363.573822)
		(stroke
			(width 0.05715)
			(type default)
		)
		(layer "In5.Cu")
	)
	(gr_arc
		(start 33.979866 -363.385862)
		(mid 34.048691 -363.302787)
		(end 34.073846 -363.197902)
		(stroke
			(width 0.05715)
			(type default)
		)
		(layer "In5.Cu")
	)
	(gr_arc
		(start 33.979866 -361.948222)
		(mid 33.911063 -362.031289)
		(end 33.885886 -362.136182)
		(stroke
			(width 0.05715)
			(type default)
		)
		(layer "In5.Cu")
	)
	(gr_arc
		(start 33.979866 -361.948222)
		(mid 34.048691 -361.865147)
		(end 34.073846 -361.760262)
		(stroke
			(width 0.05715)
			(type default)
		)
		(layer "In5.Cu")
	)
	(gr_arc
		(start 33.979866 -360.510582)
		(mid 33.911049 -360.593646)
		(end 33.885886 -360.698542)
		(stroke
			(width 0.05715)
			(type default)
		)
		(layer "In5.Cu")
	)
	(gr_arc
		(start 33.979866 -360.510582)
		(mid 34.048691 -360.427507)
		(end 34.073846 -360.322622)
		(stroke
			(width 0.05715)
			(type default)
		)
		(layer "In5.Cu")
	)
	(gr_arc
		(start 33.979866 -359.072942)
		(mid 33.911035 -359.156003)
		(end 33.885886 -359.260902)
		(stroke
			(width 0.05715)
			(type default)
		)
		(layer "In5.Cu")
	)
	(gr_arc
		(start 33.979866 -359.072942)
		(mid 34.048691 -358.989867)
		(end 34.073846 -358.884982)
		(stroke
			(width 0.05715)
			(type default)
		)
		(layer "In5.Cu")
	)
	(gr_arc
		(start 34.073846 -390.86536)
		(mid 34.048691 -390.76045)
		(end 33.979866 -390.6774)
		(stroke
			(width 0.05715)
			(type default)
		)
		(layer "In5.Cu")
	)
	(gr_arc
		(start 34.073846 -389.42772)
		(mid 34.048691 -389.32281)
		(end 33.979866 -389.23976)
		(stroke
			(width 0.05715)
			(type default)
		)
		(layer "In5.Cu")
	)
	(gr_arc
		(start 34.073846 -387.99008)
		(mid 34.048691 -387.88517)
		(end 33.979866 -387.80212)
		(stroke
			(width 0.05715)
			(type default)
		)
		(layer "In5.Cu")
	)
	(gr_arc
		(start 34.073846 -386.55244)
		(mid 34.048691 -386.44753)
		(end 33.979866 -386.36448)
		(stroke
			(width 0.05715)
			(type default)
		)
		(layer "In5.Cu")
	)
	(gr_arc
		(start 34.073846 -385.1148)
		(mid 34.048691 -385.00989)
		(end 33.979866 -384.92684)
		(stroke
			(width 0.05715)
			(type default)
		)
		(layer "In5.Cu")
	)
	(gr_arc
		(start 34.073846 -365.730282)
		(mid 34.048691 -365.625372)
		(end 33.979866 -365.542322)
		(stroke
			(width 0.05715)
			(type default)
		)
		(layer "In5.Cu")
	)
	(gr_arc
		(start 34.073846 -364.292642)
		(mid 34.048691 -364.187732)
		(end 33.979866 -364.104682)
		(stroke
			(width 0.05715)
			(type default)
		)
		(layer "In5.Cu")
	)
	(gr_arc
		(start 34.073846 -362.855002)
		(mid 34.048691 -362.750092)
		(end 33.979866 -362.667042)
		(stroke
			(width 0.05715)
			(type default)
		)
		(layer "In5.Cu")
	)
	(gr_arc
		(start 34.073846 -361.417362)
		(mid 34.048691 -361.312452)
		(end 33.979866 -361.229402)
		(stroke
			(width 0.05715)
			(type default)
		)
		(layer "In5.Cu")
	)
	(gr_arc
		(start 34.073846 -359.979722)
		(mid 34.048691 -359.874812)
		(end 33.979866 -359.791762)
		(stroke
			(width 0.05715)
			(type default)
		)
		(layer "In5.Cu")
	)
	(gr_line
		(start 34.378646 -390.07796)
		(end 34.378646 -390.55802)
		(stroke
			(width 0.05715)
			(type default)
		)
		(layer "In5.Cu")
	)
	(gr_line
		(start 34.378646 -388.64032)
		(end 34.378646 -389.12038)
		(stroke
			(width 0.05715)
			(type default)
		)
		(layer "In5.Cu")
	)
	(gr_line
		(start 34.378646 -387.20268)
		(end 34.378646 -387.68274)
		(stroke
			(width 0.05715)
			(type default)
		)
		(layer "In5.Cu")
	)
	(gr_line
		(start 34.378646 -385.76504)
		(end 34.378646 -386.2451)
		(stroke
			(width 0.05715)
			(type default)
		)
		(layer "In5.Cu")
	)
	(gr_line
		(start 34.378646 -384.3274)
		(end 34.378646 -384.80746)
		(stroke
			(width 0.05715)
			(type default)
		)
		(layer "In5.Cu")
	)
	(gr_line
		(start 34.378646 -364.942882)
		(end 34.378646 -365.422942)
		(stroke
			(width 0.05715)
			(type default)
		)
		(layer "In5.Cu")
	)
	(gr_line
		(start 34.378646 -363.505242)
		(end 34.378646 -363.985302)
		(stroke
			(width 0.05715)
			(type default)
		)
		(layer "In5.Cu")
	)
	(gr_line
		(start 34.378646 -362.067602)
		(end 34.378646 -362.547662)
		(stroke
			(width 0.05715)
			(type default)
		)
		(layer "In5.Cu")
	)
	(gr_line
		(start 34.378646 -360.629962)
		(end 34.378646 -361.110022)
		(stroke
			(width 0.05715)
			(type default)
		)
		(layer "In5.Cu")
	)
	(gr_line
		(start 34.378646 -359.192322)
		(end 34.378646 -359.672382)
		(stroke
			(width 0.05715)
			(type default)
		)
		(layer "In5.Cu")
	)
	(gr_arc
		(start 34.920174 -273.699478)
		(mid 35.261156 -273.92733)
		(end 35.663378 -274.007326)
		(stroke
			(width 0.05715)
			(type default)
		)
		(layer "In5.Cu")
	)
	(gr_arc
		(start 35.659822 -274.312126)
		(mid 35.25899 -274.391909)
		(end 34.919158 -274.618958)
		(stroke
			(width 0.05715)
			(type default)
		)
		(layer "In5.Cu")
	)
	(gr_arc
		(start 36.383976 -164.1729)
		(mid 36.562503 -164.098951)
		(end 36.636452 -163.920424)
		(stroke
			(width 0.05715)
			(type default)
		)
		(layer "In5.Cu")
	)
	(gr_arc
		(start 36.636452 -164.879274)
		(mid 36.518834 -164.595318)
		(end 36.234878 -164.4777)
		(stroke
			(width 0.05715)
			(type default)
		)
		(layer "In5.Cu")
	)
	(gr_line
		(start 37.6555 -424.8785)
		(end 37.655754 -424.878754)
		(stroke
			(width 0.05715)
			(type default)
		)
		(layer "In5.Cu")
	)
	(gr_line
		(start 37.871146 -425.094146)
		(end 38.086792 -424.8785)
		(stroke
			(width 0.05715)
			(type default)
		)
		(layer "In5.Cu")
	)
	(gr_line
		(start 41.694354 -420.839646)
		(end 41.91 -420.624)
		(stroke
			(width 0.05715)
			(type default)
		)
		(layer "In5.Cu")
	)
	(gr_line
		(start 42.125392 -420.839392)
		(end 42.125646 -420.839646)
		(stroke
			(width 0.05715)
			(type default)
		)
		(layer "In5.Cu")
	)
	(gr_line
		(start 47.17923 -441.84443)
		(end 47.394876 -441.628784)
		(stroke
			(width 0.05715)
			(type default)
		)
		(layer "In5.Cu")
	)
	(gr_line
		(start 47.394622 -442.059822)
		(end 47.394876 -442.060076)
		(stroke
			(width 0.05715)
			(type default)
		)
		(layer "In5.Cu")
	)
	(gr_line
		(start 47.396654 -284.124654)
		(end 47.6123 -284.3403)
		(stroke
			(width 0.05715)
			(type default)
		)
		(layer "In5.Cu")
	)
	(gr_line
		(start 47.827946 -284.124654)
		(end 47.827692 -284.124908)
		(stroke
			(width 0.05715)
			(type default)
		)
		(layer "In5.Cu")
	)
	(gr_arc
		(start 47.836836 -406.617932)
		(mid 47.86208 -406.722772)
		(end 47.930816 -406.805892)
		(stroke
			(width 0.05715)
			(type default)
		)
		(layer "In5.Cu")
	)
	(gr_line
		(start 47.836836 -406.275032)
		(end 47.836836 -406.617932)
		(stroke
			(width 0.05715)
			(type default)
		)
		(layer "In5.Cu")
	)
	(gr_arc
		(start 47.836836 -405.180292)
		(mid 47.86208 -405.285132)
		(end 47.930816 -405.368252)
		(stroke
			(width 0.05715)
			(type default)
		)
		(layer "In5.Cu")
	)
	(gr_line
		(start 47.836836 -404.837392)
		(end 47.836836 -405.180292)
		(stroke
			(width 0.05715)
			(type default)
		)
		(layer "In5.Cu")
	)
	(gr_arc
		(start 47.836836 -403.742652)
		(mid 47.86208 -403.847492)
		(end 47.930816 -403.930612)
		(stroke
			(width 0.05715)
			(type default)
		)
		(layer "In5.Cu")
	)
	(gr_line
		(start 47.836836 -403.399752)
		(end 47.836836 -403.742652)
		(stroke
			(width 0.05715)
			(type default)
		)
		(layer "In5.Cu")
	)
	(gr_arc
		(start 47.836836 -402.305012)
		(mid 47.86208 -402.409852)
		(end 47.930816 -402.492972)
		(stroke
			(width 0.05715)
			(type default)
		)
		(layer "In5.Cu")
	)
	(gr_line
		(start 47.836836 -401.962112)
		(end 47.836836 -402.305012)
		(stroke
			(width 0.05715)
			(type default)
		)
		(layer "In5.Cu")
	)
	(gr_arc
		(start 47.836836 -397.314674)
		(mid 47.86208 -397.419514)
		(end 47.930816 -397.502634)
		(stroke
			(width 0.05715)
			(type default)
		)
		(layer "In5.Cu")
	)
	(gr_line
		(start 47.836836 -396.971774)
		(end 47.836836 -397.314674)
		(stroke
			(width 0.05715)
			(type default)
		)
		(layer "In5.Cu")
	)
	(gr_arc
		(start 47.930816 -406.087072)
		(mid 47.86208 -406.170166)
		(end 47.836836 -406.275032)
		(stroke
			(width 0.05715)
			(type default)
		)
		(layer "In5.Cu")
	)
	(gr_arc
		(start 47.930816 -406.087072)
		(mid 47.999548 -406.003964)
		(end 48.024796 -405.899112)
		(stroke
			(width 0.05715)
			(type default)
		)
		(layer "In5.Cu")
	)
	(gr_arc
		(start 47.930816 -404.649432)
		(mid 47.86208 -404.732526)
		(end 47.836836 -404.837392)
		(stroke
			(width 0.05715)
			(type default)
		)
		(layer "In5.Cu")
	)
	(gr_arc
		(start 47.930816 -404.649432)
		(mid 47.999569 -404.566329)
		(end 48.024796 -404.461472)
		(stroke
			(width 0.05715)
			(type default)
		)
		(layer "In5.Cu")
	)
	(gr_arc
		(start 47.930816 -403.211792)
		(mid 47.86208 -403.294886)
		(end 47.836836 -403.399752)
		(stroke
			(width 0.05715)
			(type default)
		)
		(layer "In5.Cu")
	)
	(gr_arc
		(start 47.930816 -403.211792)
		(mid 47.999555 -403.128686)
		(end 48.024796 -403.023832)
		(stroke
			(width 0.05715)
			(type default)
		)
		(layer "In5.Cu")
	)
	(gr_arc
		(start 47.930816 -401.774152)
		(mid 47.86208 -401.857246)
		(end 47.836836 -401.962112)
		(stroke
			(width 0.05715)
			(type default)
		)
		(layer "In5.Cu")
	)
	(gr_arc
		(start 47.930816 -401.774152)
		(mid 47.999576 -401.69105)
		(end 48.024796 -401.586192)
		(stroke
			(width 0.05715)
			(type default)
		)
		(layer "In5.Cu")
	)
	(gr_arc
		(start 47.930816 -396.783814)
		(mid 47.86208 -396.866908)
		(end 47.836836 -396.971774)
		(stroke
			(width 0.05715)
			(type default)
		)
		(layer "In5.Cu")
	)
	(gr_arc
		(start 47.930816 -396.783814)
		(mid 47.999563 -396.700709)
		(end 48.024796 -396.595854)
		(stroke
			(width 0.05715)
			(type default)
		)
		(layer "In5.Cu")
	)
	(gr_arc
		(start 48.024796 -406.993852)
		(mid 47.999571 -406.888987)
		(end 47.930816 -406.805892)
		(stroke
			(width 0.05715)
			(type default)
		)
		(layer "In5.Cu")
	)
	(gr_arc
		(start 48.024796 -405.556212)
		(mid 47.999557 -405.451358)
		(end 47.930816 -405.368252)
		(stroke
			(width 0.05715)
			(type default)
		)
		(layer "In5.Cu")
	)
	(gr_arc
		(start 48.024796 -404.118572)
		(mid 47.999543 -404.013729)
		(end 47.930816 -403.930612)
		(stroke
			(width 0.05715)
			(type default)
		)
		(layer "In5.Cu")
	)
	(gr_arc
		(start 48.024796 -402.680932)
		(mid 47.999564 -402.576073)
		(end 47.930816 -402.492972)
		(stroke
			(width 0.05715)
			(type default)
		)
		(layer "In5.Cu")
	)
	(gr_arc
		(start 48.024796 -397.690594)
		(mid 47.99955 -397.585745)
		(end 47.930816 -397.502634)
		(stroke
			(width 0.05715)
			(type default)
		)
		(layer "In5.Cu")
	)
	(gr_line
		(start 48.329596 -406.206452)
		(end 48.329596 -406.686512)
		(stroke
			(width 0.05715)
			(type default)
		)
		(layer "In5.Cu")
	)
	(gr_line
		(start 48.329596 -404.768812)
		(end 48.329596 -405.248872)
		(stroke
			(width 0.05715)
			(type default)
		)
		(layer "In5.Cu")
	)
	(gr_line
		(start 48.329596 -403.331172)
		(end 48.329596 -403.811232)
		(stroke
			(width 0.05715)
			(type default)
		)
		(layer "In5.Cu")
	)
	(gr_line
		(start 48.329596 -401.893532)
		(end 48.329596 -402.373592)
		(stroke
			(width 0.05715)
			(type default)
		)
		(layer "In5.Cu")
	)
	(gr_line
		(start 48.329596 -396.903194)
		(end 48.329596 -397.383254)
		(stroke
			(width 0.05715)
			(type default)
		)
		(layer "In5.Cu")
	)
	(gr_line
		(start 1.388872 -422.855644)
		(end 1.388872 -422.144444)
		(stroke
			(width 0.2)
			(type default)
		)
		(layer "In6.Cu")
	)
	(gr_line
		(start 1.388872 -422.144444)
		(end 4.995672 -422.144444)
		(stroke
			(width 0.2)
			(type default)
		)
		(layer "In6.Cu")
	)
	(gr_line
		(start 1.388872 -421.855646)
		(end 1.388872 -421.144446)
		(stroke
			(width 0.2)
			(type default)
		)
		(layer "In6.Cu")
	)
	(gr_line
		(start 1.388872 -421.144446)
		(end 4.995672 -421.144446)
		(stroke
			(width 0.2)
			(type default)
		)
		(layer "In6.Cu")
	)
	(gr_line
		(start 1.388872 -418.855652)
		(end 1.388872 -418.144452)
		(stroke
			(width 0.2)
			(type default)
		)
		(layer "In6.Cu")
	)
	(gr_line
		(start 1.388872 -418.144452)
		(end 4.995672 -418.144452)
		(stroke
			(width 0.2)
			(type default)
		)
		(layer "In6.Cu")
	)
	(gr_line
		(start 1.388872 -417.855654)
		(end 1.388872 -417.144454)
		(stroke
			(width 0.2)
			(type default)
		)
		(layer "In6.Cu")
	)
	(gr_line
		(start 1.388872 -417.144454)
		(end 4.995672 -417.144454)
		(stroke
			(width 0.2)
			(type default)
		)
		(layer "In6.Cu")
	)
	(gr_line
		(start 1.388872 -414.85566)
		(end 1.388872 -414.14446)
		(stroke
			(width 0.2)
			(type default)
		)
		(layer "In6.Cu")
	)
	(gr_line
		(start 1.388872 -414.14446)
		(end 4.995672 -414.14446)
		(stroke
			(width 0.2)
			(type default)
		)
		(layer "In6.Cu")
	)
	(gr_line
		(start 1.388872 -413.855662)
		(end 1.388872 -413.144462)
		(stroke
			(width 0.2)
			(type default)
		)
		(layer "In6.Cu")
	)
	(gr_line
		(start 1.388872 -413.144462)
		(end 4.995672 -413.144462)
		(stroke
			(width 0.2)
			(type default)
		)
		(layer "In6.Cu")
	)
	(gr_line
		(start 1.388872 -410.855668)
		(end 1.388872 -410.144468)
		(stroke
			(width 0.2)
			(type default)
		)
		(layer "In6.Cu")
	)
	(gr_line
		(start 1.388872 -410.144468)
		(end 4.995672 -410.144468)
		(stroke
			(width 0.2)
			(type default)
		)
		(layer "In6.Cu")
	)
	(gr_line
		(start 1.388872 -409.85567)
		(end 1.388872 -409.14447)
		(stroke
			(width 0.2)
			(type default)
		)
		(layer "In6.Cu")
	)
	(gr_line
		(start 1.388872 -409.14447)
		(end 4.995672 -409.14447)
		(stroke
			(width 0.2)
			(type default)
		)
		(layer "In6.Cu")
	)
	(gr_line
		(start 1.388872 -406.855676)
		(end 1.388872 -406.144476)
		(stroke
			(width 0.2)
			(type default)
		)
		(layer "In6.Cu")
	)
	(gr_line
		(start 1.388872 -406.144476)
		(end 4.995672 -406.144476)
		(stroke
			(width 0.2)
			(type default)
		)
		(layer "In6.Cu")
	)
	(gr_line
		(start 1.388872 -405.855678)
		(end 1.388872 -405.144478)
		(stroke
			(width 0.2)
			(type default)
		)
		(layer "In6.Cu")
	)
	(gr_line
		(start 1.388872 -405.144478)
		(end 4.995672 -405.144478)
		(stroke
			(width 0.2)
			(type default)
		)
		(layer "In6.Cu")
	)
	(gr_line
		(start 1.388872 -398.855692)
		(end 1.388872 -398.144492)
		(stroke
			(width 0.2)
			(type default)
		)
		(layer "In6.Cu")
	)
	(gr_line
		(start 1.388872 -398.144492)
		(end 4.995672 -398.144492)
		(stroke
			(width 0.2)
			(type default)
		)
		(layer "In6.Cu")
	)
	(gr_line
		(start 1.388872 -397.855694)
		(end 1.388872 -397.144494)
		(stroke
			(width 0.2)
			(type default)
		)
		(layer "In6.Cu")
	)
	(gr_line
		(start 1.388872 -397.144494)
		(end 4.995672 -397.144494)
		(stroke
			(width 0.2)
			(type default)
		)
		(layer "In6.Cu")
	)
	(gr_line
		(start 1.388872 -384.85572)
		(end 1.388872 -384.14452)
		(stroke
			(width 0.2)
			(type default)
		)
		(layer "In6.Cu")
	)
	(gr_line
		(start 1.388872 -384.14452)
		(end 4.995672 -384.14452)
		(stroke
			(width 0.2)
			(type default)
		)
		(layer "In6.Cu")
	)
	(gr_line
		(start 1.388872 -383.855722)
		(end 1.388872 -383.144522)
		(stroke
			(width 0.2)
			(type default)
		)
		(layer "In6.Cu")
	)
	(gr_line
		(start 1.388872 -383.144522)
		(end 4.995672 -383.144522)
		(stroke
			(width 0.2)
			(type default)
		)
		(layer "In6.Cu")
	)
	(gr_line
		(start 1.388872 -380.855728)
		(end 1.388872 -380.144528)
		(stroke
			(width 0.2)
			(type default)
		)
		(layer "In6.Cu")
	)
	(gr_line
		(start 1.388872 -380.144528)
		(end 4.995672 -380.144528)
		(stroke
			(width 0.2)
			(type default)
		)
		(layer "In6.Cu")
	)
	(gr_line
		(start 1.388872 -379.85573)
		(end 1.388872 -379.14453)
		(stroke
			(width 0.2)
			(type default)
		)
		(layer "In6.Cu")
	)
	(gr_line
		(start 1.388872 -379.14453)
		(end 4.995672 -379.14453)
		(stroke
			(width 0.2)
			(type default)
		)
		(layer "In6.Cu")
	)
	(gr_line
		(start 1.388872 -376.855736)
		(end 1.388872 -376.144536)
		(stroke
			(width 0.2)
			(type default)
		)
		(layer "In6.Cu")
	)
	(gr_line
		(start 1.388872 -376.144536)
		(end 4.995672 -376.144536)
		(stroke
			(width 0.2)
			(type default)
		)
		(layer "In6.Cu")
	)
	(gr_line
		(start 1.388872 -375.855738)
		(end 1.388872 -375.144538)
		(stroke
			(width 0.2)
			(type default)
		)
		(layer "In6.Cu")
	)
	(gr_line
		(start 1.388872 -375.144538)
		(end 4.995672 -375.144538)
		(stroke
			(width 0.2)
			(type default)
		)
		(layer "In6.Cu")
	)
	(gr_line
		(start 1.388872 -372.855744)
		(end 1.388872 -372.144544)
		(stroke
			(width 0.2)
			(type default)
		)
		(layer "In6.Cu")
	)
	(gr_line
		(start 1.388872 -372.144544)
		(end 4.995672 -372.144544)
		(stroke
			(width 0.2)
			(type default)
		)
		(layer "In6.Cu")
	)
	(gr_line
		(start 1.388872 -371.855746)
		(end 1.388872 -371.144546)
		(stroke
			(width 0.2)
			(type default)
		)
		(layer "In6.Cu")
	)
	(gr_line
		(start 1.388872 -371.144546)
		(end 4.995672 -371.144546)
		(stroke
			(width 0.2)
			(type default)
		)
		(layer "In6.Cu")
	)
	(gr_line
		(start 1.388872 -368.855752)
		(end 1.388872 -368.144552)
		(stroke
			(width 0.2)
			(type default)
		)
		(layer "In6.Cu")
	)
	(gr_line
		(start 1.388872 -368.144552)
		(end 4.995672 -368.144552)
		(stroke
			(width 0.2)
			(type default)
		)
		(layer "In6.Cu")
	)
	(gr_line
		(start 1.388872 -367.855754)
		(end 1.388872 -367.144554)
		(stroke
			(width 0.2)
			(type default)
		)
		(layer "In6.Cu")
	)
	(gr_line
		(start 1.388872 -367.144554)
		(end 4.995672 -367.144554)
		(stroke
			(width 0.2)
			(type default)
		)
		(layer "In6.Cu")
	)
	(gr_line
		(start 1.388872 -364.85576)
		(end 1.388872 -364.14456)
		(stroke
			(width 0.2)
			(type default)
		)
		(layer "In6.Cu")
	)
	(gr_line
		(start 1.388872 -364.14456)
		(end 4.995672 -364.14456)
		(stroke
			(width 0.2)
			(type default)
		)
		(layer "In6.Cu")
	)
	(gr_line
		(start 1.388872 -363.855762)
		(end 1.388872 -363.144562)
		(stroke
			(width 0.2)
			(type default)
		)
		(layer "In6.Cu")
	)
	(gr_line
		(start 1.388872 -363.144562)
		(end 4.995672 -363.144562)
		(stroke
			(width 0.2)
			(type default)
		)
		(layer "In6.Cu")
	)
	(gr_line
		(start 1.388872 -360.855768)
		(end 1.388872 -360.144568)
		(stroke
			(width 0.2)
			(type default)
		)
		(layer "In6.Cu")
	)
	(gr_line
		(start 1.388872 -360.144568)
		(end 4.995672 -360.144568)
		(stroke
			(width 0.2)
			(type default)
		)
		(layer "In6.Cu")
	)
	(gr_line
		(start 1.388872 -359.85577)
		(end 1.388872 -359.14457)
		(stroke
			(width 0.2)
			(type default)
		)
		(layer "In6.Cu")
	)
	(gr_line
		(start 1.388872 -359.14457)
		(end 4.995672 -359.14457)
		(stroke
			(width 0.2)
			(type default)
		)
		(layer "In6.Cu")
	)
	(gr_line
		(start 1.388872 -354.855272)
		(end 1.388872 -354.144072)
		(stroke
			(width 0.2)
			(type default)
		)
		(layer "In6.Cu")
	)
	(gr_line
		(start 1.388872 -354.144072)
		(end 4.995672 -354.144072)
		(stroke
			(width 0.2)
			(type default)
		)
		(layer "In6.Cu")
	)
	(gr_line
		(start 1.388872 -353.855274)
		(end 1.388872 -353.144074)
		(stroke
			(width 0.2)
			(type default)
		)
		(layer "In6.Cu")
	)
	(gr_line
		(start 1.388872 -353.144074)
		(end 4.995672 -353.144074)
		(stroke
			(width 0.2)
			(type default)
		)
		(layer "In6.Cu")
	)
	(gr_line
		(start 1.388872 -350.85528)
		(end 1.388872 -350.14408)
		(stroke
			(width 0.2)
			(type default)
		)
		(layer "In6.Cu")
	)
	(gr_line
		(start 1.388872 -350.14408)
		(end 4.995672 -350.14408)
		(stroke
			(width 0.2)
			(type default)
		)
		(layer "In6.Cu")
	)
	(gr_line
		(start 1.388872 -349.855282)
		(end 1.388872 -349.144082)
		(stroke
			(width 0.2)
			(type default)
		)
		(layer "In6.Cu")
	)
	(gr_line
		(start 1.388872 -349.144082)
		(end 4.995672 -349.144082)
		(stroke
			(width 0.2)
			(type default)
		)
		(layer "In6.Cu")
	)
	(gr_line
		(start 1.388872 -346.855288)
		(end 1.388872 -346.144088)
		(stroke
			(width 0.2)
			(type default)
		)
		(layer "In6.Cu")
	)
	(gr_line
		(start 1.388872 -346.144088)
		(end 4.995672 -346.144088)
		(stroke
			(width 0.2)
			(type default)
		)
		(layer "In6.Cu")
	)
	(gr_line
		(start 1.388872 -345.85529)
		(end 1.388872 -345.14409)
		(stroke
			(width 0.2)
			(type default)
		)
		(layer "In6.Cu")
	)
	(gr_line
		(start 1.388872 -345.14409)
		(end 4.995672 -345.14409)
		(stroke
			(width 0.2)
			(type default)
		)
		(layer "In6.Cu")
	)
	(gr_line
		(start 1.388872 -172.855636)
		(end 1.388872 -172.144436)
		(stroke
			(width 0.2)
			(type default)
		)
		(layer "In6.Cu")
	)
	(gr_line
		(start 1.388872 -172.144436)
		(end 4.995672 -172.144436)
		(stroke
			(width 0.2)
			(type default)
		)
		(layer "In6.Cu")
	)
	(gr_line
		(start 1.388872 -171.855638)
		(end 1.388872 -171.144438)
		(stroke
			(width 0.2)
			(type default)
		)
		(layer "In6.Cu")
	)
	(gr_line
		(start 1.388872 -171.144438)
		(end 4.995672 -171.144438)
		(stroke
			(width 0.2)
			(type default)
		)
		(layer "In6.Cu")
	)
	(gr_line
		(start 1.388872 -168.855644)
		(end 1.388872 -168.144444)
		(stroke
			(width 0.2)
			(type default)
		)
		(layer "In6.Cu")
	)
	(gr_line
		(start 1.388872 -168.144444)
		(end 4.995672 -168.144444)
		(stroke
			(width 0.2)
			(type default)
		)
		(layer "In6.Cu")
	)
	(gr_line
		(start 1.388872 -167.855646)
		(end 1.388872 -167.144446)
		(stroke
			(width 0.2)
			(type default)
		)
		(layer "In6.Cu")
	)
	(gr_line
		(start 1.388872 -167.144446)
		(end 4.995672 -167.144446)
		(stroke
			(width 0.2)
			(type default)
		)
		(layer "In6.Cu")
	)
	(gr_line
		(start 1.388872 -164.855652)
		(end 1.388872 -164.144452)
		(stroke
			(width 0.2)
			(type default)
		)
		(layer "In6.Cu")
	)
	(gr_line
		(start 1.388872 -164.144452)
		(end 4.995672 -164.144452)
		(stroke
			(width 0.2)
			(type default)
		)
		(layer "In6.Cu")
	)
	(gr_line
		(start 1.388872 -163.855654)
		(end 1.388872 -163.144454)
		(stroke
			(width 0.2)
			(type default)
		)
		(layer "In6.Cu")
	)
	(gr_line
		(start 1.388872 -163.144454)
		(end 4.995672 -163.144454)
		(stroke
			(width 0.2)
			(type default)
		)
		(layer "In6.Cu")
	)
	(gr_line
		(start 1.388872 -160.85566)
		(end 1.388872 -160.14446)
		(stroke
			(width 0.2)
			(type default)
		)
		(layer "In6.Cu")
	)
	(gr_line
		(start 1.388872 -160.14446)
		(end 4.995672 -160.14446)
		(stroke
			(width 0.2)
			(type default)
		)
		(layer "In6.Cu")
	)
	(gr_line
		(start 1.388872 -159.855662)
		(end 1.388872 -159.144462)
		(stroke
			(width 0.2)
			(type default)
		)
		(layer "In6.Cu")
	)
	(gr_line
		(start 1.388872 -159.144462)
		(end 4.995672 -159.144462)
		(stroke
			(width 0.2)
			(type default)
		)
		(layer "In6.Cu")
	)
	(gr_line
		(start 1.388872 -156.855668)
		(end 1.388872 -156.144468)
		(stroke
			(width 0.2)
			(type default)
		)
		(layer "In6.Cu")
	)
	(gr_line
		(start 1.388872 -156.144468)
		(end 4.995672 -156.144468)
		(stroke
			(width 0.2)
			(type default)
		)
		(layer "In6.Cu")
	)
	(gr_line
		(start 1.388872 -155.85567)
		(end 1.388872 -155.14447)
		(stroke
			(width 0.2)
			(type default)
		)
		(layer "In6.Cu")
	)
	(gr_line
		(start 1.388872 -155.14447)
		(end 4.995672 -155.14447)
		(stroke
			(width 0.2)
			(type default)
		)
		(layer "In6.Cu")
	)
	(gr_line
		(start 1.388872 -148.855684)
		(end 1.388872 -148.144484)
		(stroke
			(width 0.2)
			(type default)
		)
		(layer "In6.Cu")
	)
	(gr_line
		(start 1.388872 -148.144484)
		(end 4.995672 -148.144484)
		(stroke
			(width 0.2)
			(type default)
		)
		(layer "In6.Cu")
	)
	(gr_line
		(start 1.388872 -147.855686)
		(end 1.388872 -147.144486)
		(stroke
			(width 0.2)
			(type default)
		)
		(layer "In6.Cu")
	)
	(gr_line
		(start 1.388872 -147.144486)
		(end 4.995672 -147.144486)
		(stroke
			(width 0.2)
			(type default)
		)
		(layer "In6.Cu")
	)
	(gr_line
		(start 1.388872 -134.855712)
		(end 1.388872 -134.144512)
		(stroke
			(width 0.2)
			(type default)
		)
		(layer "In6.Cu")
	)
	(gr_line
		(start 1.388872 -134.144512)
		(end 4.995672 -134.144512)
		(stroke
			(width 0.2)
			(type default)
		)
		(layer "In6.Cu")
	)
	(gr_line
		(start 1.388872 -133.855714)
		(end 1.388872 -133.144514)
		(stroke
			(width 0.2)
			(type default)
		)
		(layer "In6.Cu")
	)
	(gr_line
		(start 1.388872 -133.144514)
		(end 4.995672 -133.144514)
		(stroke
			(width 0.2)
			(type default)
		)
		(layer "In6.Cu")
	)
	(gr_line
		(start 1.388872 -130.85572)
		(end 1.388872 -130.14452)
		(stroke
			(width 0.2)
			(type default)
		)
		(layer "In6.Cu")
	)
	(gr_line
		(start 1.388872 -130.14452)
		(end 4.995672 -130.14452)
		(stroke
			(width 0.2)
			(type default)
		)
		(layer "In6.Cu")
	)
	(gr_line
		(start 1.388872 -129.855722)
		(end 1.388872 -129.144522)
		(stroke
			(width 0.2)
			(type default)
		)
		(layer "In6.Cu")
	)
	(gr_line
		(start 1.388872 -129.144522)
		(end 4.995672 -129.144522)
		(stroke
			(width 0.2)
			(type default)
		)
		(layer "In6.Cu")
	)
	(gr_line
		(start 1.388872 -126.855728)
		(end 1.388872 -126.144528)
		(stroke
			(width 0.2)
			(type default)
		)
		(layer "In6.Cu")
	)
	(gr_line
		(start 1.388872 -126.144528)
		(end 4.995672 -126.144528)
		(stroke
			(width 0.2)
			(type default)
		)
		(layer "In6.Cu")
	)
	(gr_line
		(start 1.388872 -125.85573)
		(end 1.388872 -125.14453)
		(stroke
			(width 0.2)
			(type default)
		)
		(layer "In6.Cu")
	)
	(gr_line
		(start 1.388872 -125.14453)
		(end 4.995672 -125.14453)
		(stroke
			(width 0.2)
			(type default)
		)
		(layer "In6.Cu")
	)
	(gr_line
		(start 1.388872 -122.855736)
		(end 1.388872 -122.144536)
		(stroke
			(width 0.2)
			(type default)
		)
		(layer "In6.Cu")
	)
	(gr_line
		(start 1.388872 -122.144536)
		(end 4.995672 -122.144536)
		(stroke
			(width 0.2)
			(type default)
		)
		(layer "In6.Cu")
	)
	(gr_line
		(start 1.388872 -121.855738)
		(end 1.388872 -121.144538)
		(stroke
			(width 0.2)
			(type default)
		)
		(layer "In6.Cu")
	)
	(gr_line
		(start 1.388872 -121.144538)
		(end 4.995672 -121.144538)
		(stroke
			(width 0.2)
			(type default)
		)
		(layer "In6.Cu")
	)
	(gr_line
		(start 1.388872 -118.855744)
		(end 1.388872 -118.144544)
		(stroke
			(width 0.2)
			(type default)
		)
		(layer "In6.Cu")
	)
	(gr_line
		(start 1.388872 -118.144544)
		(end 4.995672 -118.144544)
		(stroke
			(width 0.2)
			(type default)
		)
		(layer "In6.Cu")
	)
	(gr_line
		(start 1.388872 -117.855746)
		(end 1.388872 -117.144546)
		(stroke
			(width 0.2)
			(type default)
		)
		(layer "In6.Cu")
	)
	(gr_line
		(start 1.388872 -117.144546)
		(end 4.995672 -117.144546)
		(stroke
			(width 0.2)
			(type default)
		)
		(layer "In6.Cu")
	)
	(gr_line
		(start 1.388872 -114.855752)
		(end 1.388872 -114.144552)
		(stroke
			(width 0.2)
			(type default)
		)
		(layer "In6.Cu")
	)
	(gr_line
		(start 1.388872 -114.144552)
		(end 4.995672 -114.144552)
		(stroke
			(width 0.2)
			(type default)
		)
		(layer "In6.Cu")
	)
	(gr_line
		(start 1.388872 -113.855754)
		(end 1.388872 -113.144554)
		(stroke
			(width 0.2)
			(type default)
		)
		(layer "In6.Cu")
	)
	(gr_line
		(start 1.388872 -113.144554)
		(end 4.995672 -113.144554)
		(stroke
			(width 0.2)
			(type default)
		)
		(layer "In6.Cu")
	)
	(gr_line
		(start 1.388872 -110.85576)
		(end 1.388872 -110.14456)
		(stroke
			(width 0.2)
			(type default)
		)
		(layer "In6.Cu")
	)
	(gr_line
		(start 1.388872 -110.14456)
		(end 4.995672 -110.14456)
		(stroke
			(width 0.2)
			(type default)
		)
		(layer "In6.Cu")
	)
	(gr_line
		(start 1.388872 -109.855762)
		(end 1.388872 -109.144562)
		(stroke
			(width 0.2)
			(type default)
		)
		(layer "In6.Cu")
	)
	(gr_line
		(start 1.388872 -109.144562)
		(end 4.995672 -109.144562)
		(stroke
			(width 0.2)
			(type default)
		)
		(layer "In6.Cu")
	)
	(gr_line
		(start 1.388872 -104.855264)
		(end 1.388872 -104.144064)
		(stroke
			(width 0.2)
			(type default)
		)
		(layer "In6.Cu")
	)
	(gr_line
		(start 1.388872 -104.144064)
		(end 4.995672 -104.144064)
		(stroke
			(width 0.2)
			(type default)
		)
		(layer "In6.Cu")
	)
	(gr_line
		(start 1.388872 -103.855266)
		(end 1.388872 -103.144066)
		(stroke
			(width 0.2)
			(type default)
		)
		(layer "In6.Cu")
	)
	(gr_line
		(start 1.388872 -103.144066)
		(end 4.995672 -103.144066)
		(stroke
			(width 0.2)
			(type default)
		)
		(layer "In6.Cu")
	)
	(gr_line
		(start 1.388872 -100.855272)
		(end 1.388872 -100.144072)
		(stroke
			(width 0.2)
			(type default)
		)
		(layer "In6.Cu")
	)
	(gr_line
		(start 1.388872 -100.144072)
		(end 4.995672 -100.144072)
		(stroke
			(width 0.2)
			(type default)
		)
		(layer "In6.Cu")
	)
	(gr_line
		(start 1.388872 -99.855274)
		(end 1.388872 -99.144074)
		(stroke
			(width 0.2)
			(type default)
		)
		(layer "In6.Cu")
	)
	(gr_line
		(start 1.388872 -99.144074)
		(end 4.995672 -99.144074)
		(stroke
			(width 0.2)
			(type default)
		)
		(layer "In6.Cu")
	)
	(gr_line
		(start 1.388872 -96.85528)
		(end 1.388872 -96.14408)
		(stroke
			(width 0.2)
			(type default)
		)
		(layer "In6.Cu")
	)
	(gr_line
		(start 1.388872 -96.14408)
		(end 4.995672 -96.14408)
		(stroke
			(width 0.2)
			(type default)
		)
		(layer "In6.Cu")
	)
	(gr_line
		(start 1.388872 -95.855282)
		(end 1.388872 -95.144082)
		(stroke
			(width 0.2)
			(type default)
		)
		(layer "In6.Cu")
	)
	(gr_line
		(start 1.388872 -95.144082)
		(end 4.995672 -95.144082)
		(stroke
			(width 0.2)
			(type default)
		)
		(layer "In6.Cu")
	)
	(gr_line
		(start 4.995672 -422.855644)
		(end 1.388872 -422.855644)
		(stroke
			(width 0.2)
			(type default)
		)
		(layer "In6.Cu")
	)
	(gr_line
		(start 4.995672 -422.144444)
		(end 4.995672 -422.855644)
		(stroke
			(width 0.2)
			(type default)
		)
		(layer "In6.Cu")
	)
	(gr_line
		(start 4.995672 -421.855646)
		(end 1.388872 -421.855646)
		(stroke
			(width 0.2)
			(type default)
		)
		(layer "In6.Cu")
	)
	(gr_line
		(start 4.995672 -421.144446)
		(end 4.995672 -421.855646)
		(stroke
			(width 0.2)
			(type default)
		)
		(layer "In6.Cu")
	)
	(gr_line
		(start 4.995672 -418.855652)
		(end 1.388872 -418.855652)
		(stroke
			(width 0.2)
			(type default)
		)
		(layer "In6.Cu")
	)
	(gr_line
		(start 4.995672 -418.144452)
		(end 4.995672 -418.855652)
		(stroke
			(width 0.2)
			(type default)
		)
		(layer "In6.Cu")
	)
	(gr_line
		(start 4.995672 -417.855654)
		(end 1.388872 -417.855654)
		(stroke
			(width 0.2)
			(type default)
		)
		(layer "In6.Cu")
	)
	(gr_line
		(start 4.995672 -417.144454)
		(end 4.995672 -417.855654)
		(stroke
			(width 0.2)
			(type default)
		)
		(layer "In6.Cu")
	)
	(gr_line
		(start 4.995672 -414.85566)
		(end 1.388872 -414.85566)
		(stroke
			(width 0.2)
			(type default)
		)
		(layer "In6.Cu")
	)
	(gr_line
		(start 4.995672 -414.14446)
		(end 4.995672 -414.85566)
		(stroke
			(width 0.2)
			(type default)
		)
		(layer "In6.Cu")
	)
	(gr_line
		(start 4.995672 -413.855662)
		(end 1.388872 -413.855662)
		(stroke
			(width 0.2)
			(type default)
		)
		(layer "In6.Cu")
	)
	(gr_line
		(start 4.995672 -413.144462)
		(end 4.995672 -413.855662)
		(stroke
			(width 0.2)
			(type default)
		)
		(layer "In6.Cu")
	)
	(gr_line
		(start 4.995672 -410.855668)
		(end 1.388872 -410.855668)
		(stroke
			(width 0.2)
			(type default)
		)
		(layer "In6.Cu")
	)
	(gr_line
		(start 4.995672 -410.144468)
		(end 4.995672 -410.855668)
		(stroke
			(width 0.2)
			(type default)
		)
		(layer "In6.Cu")
	)
	(gr_line
		(start 4.995672 -409.85567)
		(end 1.388872 -409.85567)
		(stroke
			(width 0.2)
			(type default)
		)
		(layer "In6.Cu")
	)
	(gr_line
		(start 4.995672 -409.14447)
		(end 4.995672 -409.85567)
		(stroke
			(width 0.2)
			(type default)
		)
		(layer "In6.Cu")
	)
	(gr_line
		(start 4.995672 -406.855676)
		(end 1.388872 -406.855676)
		(stroke
			(width 0.2)
			(type default)
		)
		(layer "In6.Cu")
	)
	(gr_line
		(start 4.995672 -406.144476)
		(end 4.995672 -406.855676)
		(stroke
			(width 0.2)
			(type default)
		)
		(layer "In6.Cu")
	)
	(gr_line
		(start 4.995672 -405.855678)
		(end 1.388872 -405.855678)
		(stroke
			(width 0.2)
			(type default)
		)
		(layer "In6.Cu")
	)
	(gr_line
		(start 4.995672 -405.144478)
		(end 4.995672 -405.855678)
		(stroke
			(width 0.2)
			(type default)
		)
		(layer "In6.Cu")
	)
	(gr_line
		(start 4.995672 -398.855692)
		(end 1.388872 -398.855692)
		(stroke
			(width 0.2)
			(type default)
		)
		(layer "In6.Cu")
	)
	(gr_line
		(start 4.995672 -398.144492)
		(end 4.995672 -398.855692)
		(stroke
			(width 0.2)
			(type default)
		)
		(layer "In6.Cu")
	)
	(gr_line
		(start 4.995672 -397.855694)
		(end 1.388872 -397.855694)
		(stroke
			(width 0.2)
			(type default)
		)
		(layer "In6.Cu")
	)
	(gr_line
		(start 4.995672 -397.144494)
		(end 4.995672 -397.855694)
		(stroke
			(width 0.2)
			(type default)
		)
		(layer "In6.Cu")
	)
	(gr_line
		(start 4.995672 -384.85572)
		(end 1.388872 -384.85572)
		(stroke
			(width 0.2)
			(type default)
		)
		(layer "In6.Cu")
	)
	(gr_line
		(start 4.995672 -384.14452)
		(end 4.995672 -384.85572)
		(stroke
			(width 0.2)
			(type default)
		)
		(layer "In6.Cu")
	)
	(gr_line
		(start 4.995672 -383.855722)
		(end 1.388872 -383.855722)
		(stroke
			(width 0.2)
			(type default)
		)
		(layer "In6.Cu")
	)
	(gr_line
		(start 4.995672 -383.144522)
		(end 4.995672 -383.855722)
		(stroke
			(width 0.2)
			(type default)
		)
		(layer "In6.Cu")
	)
	(gr_line
		(start 4.995672 -380.855728)
		(end 1.388872 -380.855728)
		(stroke
			(width 0.2)
			(type default)
		)
		(layer "In6.Cu")
	)
	(gr_line
		(start 4.995672 -380.144528)
		(end 4.995672 -380.855728)
		(stroke
			(width 0.2)
			(type default)
		)
		(layer "In6.Cu")
	)
	(gr_line
		(start 4.995672 -379.85573)
		(end 1.388872 -379.85573)
		(stroke
			(width 0.2)
			(type default)
		)
		(layer "In6.Cu")
	)
	(gr_line
		(start 4.995672 -379.14453)
		(end 4.995672 -379.85573)
		(stroke
			(width 0.2)
			(type default)
		)
		(layer "In6.Cu")
	)
	(gr_line
		(start 4.995672 -376.855736)
		(end 1.388872 -376.855736)
		(stroke
			(width 0.2)
			(type default)
		)
		(layer "In6.Cu")
	)
	(gr_line
		(start 4.995672 -376.144536)
		(end 4.995672 -376.855736)
		(stroke
			(width 0.2)
			(type default)
		)
		(layer "In6.Cu")
	)
	(gr_line
		(start 4.995672 -375.855738)
		(end 1.388872 -375.855738)
		(stroke
			(width 0.2)
			(type default)
		)
		(layer "In6.Cu")
	)
	(gr_line
		(start 4.995672 -375.144538)
		(end 4.995672 -375.855738)
		(stroke
			(width 0.2)
			(type default)
		)
		(layer "In6.Cu")
	)
	(gr_line
		(start 4.995672 -372.855744)
		(end 1.388872 -372.855744)
		(stroke
			(width 0.2)
			(type default)
		)
		(layer "In6.Cu")
	)
	(gr_line
		(start 4.995672 -372.144544)
		(end 4.995672 -372.855744)
		(stroke
			(width 0.2)
			(type default)
		)
		(layer "In6.Cu")
	)
	(gr_line
		(start 4.995672 -371.855746)
		(end 1.388872 -371.855746)
		(stroke
			(width 0.2)
			(type default)
		)
		(layer "In6.Cu")
	)
	(gr_line
		(start 4.995672 -371.144546)
		(end 4.995672 -371.855746)
		(stroke
			(width 0.2)
			(type default)
		)
		(layer "In6.Cu")
	)
	(gr_line
		(start 4.995672 -368.855752)
		(end 1.388872 -368.855752)
		(stroke
			(width 0.2)
			(type default)
		)
		(layer "In6.Cu")
	)
	(gr_line
		(start 4.995672 -368.144552)
		(end 4.995672 -368.855752)
		(stroke
			(width 0.2)
			(type default)
		)
		(layer "In6.Cu")
	)
	(gr_line
		(start 4.995672 -367.855754)
		(end 1.388872 -367.855754)
		(stroke
			(width 0.2)
			(type default)
		)
		(layer "In6.Cu")
	)
	(gr_line
		(start 4.995672 -367.144554)
		(end 4.995672 -367.855754)
		(stroke
			(width 0.2)
			(type default)
		)
		(layer "In6.Cu")
	)
	(gr_line
		(start 4.995672 -364.85576)
		(end 1.388872 -364.85576)
		(stroke
			(width 0.2)
			(type default)
		)
		(layer "In6.Cu")
	)
	(gr_line
		(start 4.995672 -364.14456)
		(end 4.995672 -364.85576)
		(stroke
			(width 0.2)
			(type default)
		)
		(layer "In6.Cu")
	)
	(gr_line
		(start 4.995672 -363.855762)
		(end 1.388872 -363.855762)
		(stroke
			(width 0.2)
			(type default)
		)
		(layer "In6.Cu")
	)
	(gr_line
		(start 4.995672 -363.144562)
		(end 4.995672 -363.855762)
		(stroke
			(width 0.2)
			(type default)
		)
		(layer "In6.Cu")
	)
	(gr_line
		(start 4.995672 -360.855768)
		(end 1.388872 -360.855768)
		(stroke
			(width 0.2)
			(type default)
		)
		(layer "In6.Cu")
	)
	(gr_line
		(start 4.995672 -360.144568)
		(end 4.995672 -360.855768)
		(stroke
			(width 0.2)
			(type default)
		)
		(layer "In6.Cu")
	)
	(gr_line
		(start 4.995672 -359.85577)
		(end 1.388872 -359.85577)
		(stroke
			(width 0.2)
			(type default)
		)
		(layer "In6.Cu")
	)
	(gr_line
		(start 4.995672 -359.14457)
		(end 4.995672 -359.85577)
		(stroke
			(width 0.2)
			(type default)
		)
		(layer "In6.Cu")
	)
	(gr_line
		(start 4.995672 -354.855272)
		(end 1.388872 -354.855272)
		(stroke
			(width 0.2)
			(type default)
		)
		(layer "In6.Cu")
	)
	(gr_line
		(start 4.995672 -354.144072)
		(end 4.995672 -354.855272)
		(stroke
			(width 0.2)
			(type default)
		)
		(layer "In6.Cu")
	)
	(gr_line
		(start 4.995672 -353.855274)
		(end 1.388872 -353.855274)
		(stroke
			(width 0.2)
			(type default)
		)
		(layer "In6.Cu")
	)
	(gr_line
		(start 4.995672 -353.144074)
		(end 4.995672 -353.855274)
		(stroke
			(width 0.2)
			(type default)
		)
		(layer "In6.Cu")
	)
	(gr_line
		(start 4.995672 -350.85528)
		(end 1.388872 -350.85528)
		(stroke
			(width 0.2)
			(type default)
		)
		(layer "In6.Cu")
	)
	(gr_line
		(start 4.995672 -350.14408)
		(end 4.995672 -350.85528)
		(stroke
			(width 0.2)
			(type default)
		)
		(layer "In6.Cu")
	)
	(gr_line
		(start 4.995672 -349.855282)
		(end 1.388872 -349.855282)
		(stroke
			(width 0.2)
			(type default)
		)
		(layer "In6.Cu")
	)
	(gr_line
		(start 4.995672 -349.144082)
		(end 4.995672 -349.855282)
		(stroke
			(width 0.2)
			(type default)
		)
		(layer "In6.Cu")
	)
	(gr_line
		(start 4.995672 -346.855288)
		(end 1.388872 -346.855288)
		(stroke
			(width 0.2)
			(type default)
		)
		(layer "In6.Cu")
	)
	(gr_line
		(start 4.995672 -346.144088)
		(end 4.995672 -346.855288)
		(stroke
			(width 0.2)
			(type default)
		)
		(layer "In6.Cu")
	)
	(gr_line
		(start 4.995672 -345.85529)
		(end 1.388872 -345.85529)
		(stroke
			(width 0.2)
			(type default)
		)
		(layer "In6.Cu")
	)
	(gr_line
		(start 4.995672 -345.14409)
		(end 4.995672 -345.85529)
		(stroke
			(width 0.2)
			(type default)
		)
		(layer "In6.Cu")
	)
	(gr_line
		(start 4.995672 -172.855636)
		(end 1.388872 -172.855636)
		(stroke
			(width 0.2)
			(type default)
		)
		(layer "In6.Cu")
	)
	(gr_line
		(start 4.995672 -172.144436)
		(end 4.995672 -172.855636)
		(stroke
			(width 0.2)
			(type default)
		)
		(layer "In6.Cu")
	)
	(gr_line
		(start 4.995672 -171.855638)
		(end 1.388872 -171.855638)
		(stroke
			(width 0.2)
			(type default)
		)
		(layer "In6.Cu")
	)
	(gr_line
		(start 4.995672 -171.144438)
		(end 4.995672 -171.855638)
		(stroke
			(width 0.2)
			(type default)
		)
		(layer "In6.Cu")
	)
	(gr_line
		(start 4.995672 -168.855644)
		(end 1.388872 -168.855644)
		(stroke
			(width 0.2)
			(type default)
		)
		(layer "In6.Cu")
	)
	(gr_line
		(start 4.995672 -168.144444)
		(end 4.995672 -168.855644)
		(stroke
			(width 0.2)
			(type default)
		)
		(layer "In6.Cu")
	)
	(gr_line
		(start 4.995672 -167.855646)
		(end 1.388872 -167.855646)
		(stroke
			(width 0.2)
			(type default)
		)
		(layer "In6.Cu")
	)
	(gr_line
		(start 4.995672 -167.144446)
		(end 4.995672 -167.855646)
		(stroke
			(width 0.2)
			(type default)
		)
		(layer "In6.Cu")
	)
	(gr_line
		(start 4.995672 -164.855652)
		(end 1.388872 -164.855652)
		(stroke
			(width 0.2)
			(type default)
		)
		(layer "In6.Cu")
	)
	(gr_line
		(start 4.995672 -164.144452)
		(end 4.995672 -164.855652)
		(stroke
			(width 0.2)
			(type default)
		)
		(layer "In6.Cu")
	)
	(gr_line
		(start 4.995672 -163.855654)
		(end 1.388872 -163.855654)
		(stroke
			(width 0.2)
			(type default)
		)
		(layer "In6.Cu")
	)
	(gr_line
		(start 4.995672 -163.144454)
		(end 4.995672 -163.855654)
		(stroke
			(width 0.2)
			(type default)
		)
		(layer "In6.Cu")
	)
	(gr_line
		(start 4.995672 -160.85566)
		(end 1.388872 -160.85566)
		(stroke
			(width 0.2)
			(type default)
		)
		(layer "In6.Cu")
	)
	(gr_line
		(start 4.995672 -160.14446)
		(end 4.995672 -160.85566)
		(stroke
			(width 0.2)
			(type default)
		)
		(layer "In6.Cu")
	)
	(gr_line
		(start 4.995672 -159.855662)
		(end 1.388872 -159.855662)
		(stroke
			(width 0.2)
			(type default)
		)
		(layer "In6.Cu")
	)
	(gr_line
		(start 4.995672 -159.144462)
		(end 4.995672 -159.855662)
		(stroke
			(width 0.2)
			(type default)
		)
		(layer "In6.Cu")
	)
	(gr_line
		(start 4.995672 -156.855668)
		(end 1.388872 -156.855668)
		(stroke
			(width 0.2)
			(type default)
		)
		(layer "In6.Cu")
	)
	(gr_line
		(start 4.995672 -156.144468)
		(end 4.995672 -156.855668)
		(stroke
			(width 0.2)
			(type default)
		)
		(layer "In6.Cu")
	)
	(gr_line
		(start 4.995672 -155.85567)
		(end 1.388872 -155.85567)
		(stroke
			(width 0.2)
			(type default)
		)
		(layer "In6.Cu")
	)
	(gr_line
		(start 4.995672 -155.14447)
		(end 4.995672 -155.85567)
		(stroke
			(width 0.2)
			(type default)
		)
		(layer "In6.Cu")
	)
	(gr_line
		(start 4.995672 -148.855684)
		(end 1.388872 -148.855684)
		(stroke
			(width 0.2)
			(type default)
		)
		(layer "In6.Cu")
	)
	(gr_line
		(start 4.995672 -148.144484)
		(end 4.995672 -148.855684)
		(stroke
			(width 0.2)
			(type default)
		)
		(layer "In6.Cu")
	)
	(gr_line
		(start 4.995672 -147.855686)
		(end 1.388872 -147.855686)
		(stroke
			(width 0.2)
			(type default)
		)
		(layer "In6.Cu")
	)
	(gr_line
		(start 4.995672 -147.144486)
		(end 4.995672 -147.855686)
		(stroke
			(width 0.2)
			(type default)
		)
		(layer "In6.Cu")
	)
	(gr_line
		(start 4.995672 -134.855712)
		(end 1.388872 -134.855712)
		(stroke
			(width 0.2)
			(type default)
		)
		(layer "In6.Cu")
	)
	(gr_line
		(start 4.995672 -134.144512)
		(end 4.995672 -134.855712)
		(stroke
			(width 0.2)
			(type default)
		)
		(layer "In6.Cu")
	)
	(gr_line
		(start 4.995672 -133.855714)
		(end 1.388872 -133.855714)
		(stroke
			(width 0.2)
			(type default)
		)
		(layer "In6.Cu")
	)
	(gr_line
		(start 4.995672 -133.144514)
		(end 4.995672 -133.855714)
		(stroke
			(width 0.2)
			(type default)
		)
		(layer "In6.Cu")
	)
	(gr_line
		(start 4.995672 -130.85572)
		(end 1.388872 -130.85572)
		(stroke
			(width 0.2)
			(type default)
		)
		(layer "In6.Cu")
	)
	(gr_line
		(start 4.995672 -130.14452)
		(end 4.995672 -130.85572)
		(stroke
			(width 0.2)
			(type default)
		)
		(layer "In6.Cu")
	)
	(gr_line
		(start 4.995672 -129.855722)
		(end 1.388872 -129.855722)
		(stroke
			(width 0.2)
			(type default)
		)
		(layer "In6.Cu")
	)
	(gr_line
		(start 4.995672 -129.144522)
		(end 4.995672 -129.855722)
		(stroke
			(width 0.2)
			(type default)
		)
		(layer "In6.Cu")
	)
	(gr_line
		(start 4.995672 -126.855728)
		(end 1.388872 -126.855728)
		(stroke
			(width 0.2)
			(type default)
		)
		(layer "In6.Cu")
	)
	(gr_line
		(start 4.995672 -126.144528)
		(end 4.995672 -126.855728)
		(stroke
			(width 0.2)
			(type default)
		)
		(layer "In6.Cu")
	)
	(gr_line
		(start 4.995672 -125.85573)
		(end 1.388872 -125.85573)
		(stroke
			(width 0.2)
			(type default)
		)
		(layer "In6.Cu")
	)
	(gr_line
		(start 4.995672 -125.14453)
		(end 4.995672 -125.85573)
		(stroke
			(width 0.2)
			(type default)
		)
		(layer "In6.Cu")
	)
	(gr_line
		(start 4.995672 -122.855736)
		(end 1.388872 -122.855736)
		(stroke
			(width 0.2)
			(type default)
		)
		(layer "In6.Cu")
	)
	(gr_line
		(start 4.995672 -122.144536)
		(end 4.995672 -122.855736)
		(stroke
			(width 0.2)
			(type default)
		)
		(layer "In6.Cu")
	)
	(gr_line
		(start 4.995672 -121.855738)
		(end 1.388872 -121.855738)
		(stroke
			(width 0.2)
			(type default)
		)
		(layer "In6.Cu")
	)
	(gr_line
		(start 4.995672 -121.144538)
		(end 4.995672 -121.855738)
		(stroke
			(width 0.2)
			(type default)
		)
		(layer "In6.Cu")
	)
	(gr_line
		(start 4.995672 -118.855744)
		(end 1.388872 -118.855744)
		(stroke
			(width 0.2)
			(type default)
		)
		(layer "In6.Cu")
	)
	(gr_line
		(start 4.995672 -118.144544)
		(end 4.995672 -118.855744)
		(stroke
			(width 0.2)
			(type default)
		)
		(layer "In6.Cu")
	)
	(gr_line
		(start 4.995672 -117.855746)
		(end 1.388872 -117.855746)
		(stroke
			(width 0.2)
			(type default)
		)
		(layer "In6.Cu")
	)
	(gr_line
		(start 4.995672 -117.144546)
		(end 4.995672 -117.855746)
		(stroke
			(width 0.2)
			(type default)
		)
		(layer "In6.Cu")
	)
	(gr_line
		(start 4.995672 -114.855752)
		(end 1.388872 -114.855752)
		(stroke
			(width 0.2)
			(type default)
		)
		(layer "In6.Cu")
	)
	(gr_line
		(start 4.995672 -114.144552)
		(end 4.995672 -114.855752)
		(stroke
			(width 0.2)
			(type default)
		)
		(layer "In6.Cu")
	)
	(gr_line
		(start 4.995672 -113.855754)
		(end 1.388872 -113.855754)
		(stroke
			(width 0.2)
			(type default)
		)
		(layer "In6.Cu")
	)
	(gr_line
		(start 4.995672 -113.144554)
		(end 4.995672 -113.855754)
		(stroke
			(width 0.2)
			(type default)
		)
		(layer "In6.Cu")
	)
	(gr_line
		(start 4.995672 -110.85576)
		(end 1.388872 -110.85576)
		(stroke
			(width 0.2)
			(type default)
		)
		(layer "In6.Cu")
	)
	(gr_line
		(start 4.995672 -110.14456)
		(end 4.995672 -110.85576)
		(stroke
			(width 0.2)
			(type default)
		)
		(layer "In6.Cu")
	)
	(gr_line
		(start 4.995672 -109.855762)
		(end 1.388872 -109.855762)
		(stroke
			(width 0.2)
			(type default)
		)
		(layer "In6.Cu")
	)
	(gr_line
		(start 4.995672 -109.144562)
		(end 4.995672 -109.855762)
		(stroke
			(width 0.2)
			(type default)
		)
		(layer "In6.Cu")
	)
	(gr_line
		(start 4.995672 -104.855264)
		(end 1.388872 -104.855264)
		(stroke
			(width 0.2)
			(type default)
		)
		(layer "In6.Cu")
	)
	(gr_line
		(start 4.995672 -104.144064)
		(end 4.995672 -104.855264)
		(stroke
			(width 0.2)
			(type default)
		)
		(layer "In6.Cu")
	)
	(gr_line
		(start 4.995672 -103.855266)
		(end 1.388872 -103.855266)
		(stroke
			(width 0.2)
			(type default)
		)
		(layer "In6.Cu")
	)
	(gr_line
		(start 4.995672 -103.144066)
		(end 4.995672 -103.855266)
		(stroke
			(width 0.2)
			(type default)
		)
		(layer "In6.Cu")
	)
	(gr_line
		(start 4.995672 -100.855272)
		(end 1.388872 -100.855272)
		(stroke
			(width 0.2)
			(type default)
		)
		(layer "In6.Cu")
	)
	(gr_line
		(start 4.995672 -100.144072)
		(end 4.995672 -100.855272)
		(stroke
			(width 0.2)
			(type default)
		)
		(layer "In6.Cu")
	)
	(gr_line
		(start 4.995672 -99.855274)
		(end 1.388872 -99.855274)
		(stroke
			(width 0.2)
			(type default)
		)
		(layer "In6.Cu")
	)
	(gr_line
		(start 4.995672 -99.144074)
		(end 4.995672 -99.855274)
		(stroke
			(width 0.2)
			(type default)
		)
		(layer "In6.Cu")
	)
	(gr_line
		(start 4.995672 -96.85528)
		(end 1.388872 -96.85528)
		(stroke
			(width 0.2)
			(type default)
		)
		(layer "In6.Cu")
	)
	(gr_line
		(start 4.995672 -96.14408)
		(end 4.995672 -96.85528)
		(stroke
			(width 0.2)
			(type default)
		)
		(layer "In6.Cu")
	)
	(gr_line
		(start 4.995672 -95.855282)
		(end 1.388872 -95.855282)
		(stroke
			(width 0.2)
			(type default)
		)
		(layer "In6.Cu")
	)
	(gr_line
		(start 4.995672 -95.144082)
		(end 4.995672 -95.855282)
		(stroke
			(width 0.2)
			(type default)
		)
		(layer "In6.Cu")
	)
	(gr_arc
		(start 5.894578 -348.491048)
		(mid 6.470396 -349.08363)
		(end 7.062978 -348.507812)
		(stroke
			(width 0.2)
			(type default)
		)
		(layer "In6.Cu")
	)
	(gr_line
		(start 5.907532 -347.577156)
		(end 5.894578 -348.491048)
		(stroke
			(width 0.2)
			(type default)
		)
		(layer "In6.Cu")
	)
	(gr_line
		(start 6.091936 -121.551954)
		(end 6.1468 -122.41403)
		(stroke
			(width 0.2)
			(type default)
		)
		(layer "In6.Cu")
	)
	(gr_arc
		(start 6.093206 -102.457504)
		(mid 6.679946 -103.044244)
		(end 7.266686 -102.457504)
		(stroke
			(width 0.2)
			(type default)
		)
		(layer "In6.Cu")
	)
	(gr_line
		(start 6.093206 -101.498654)
		(end 6.093206 -102.457504)
		(stroke
			(width 0.2)
			(type default)
		)
		(layer "In6.Cu")
	)
	(gr_arc
		(start 6.093206 -98.457766)
		(mid 6.679946 -99.044506)
		(end 7.266686 -98.457766)
		(stroke
			(width 0.2)
			(type default)
		)
		(layer "In6.Cu")
	)
	(gr_line
		(start 6.093206 -97.498916)
		(end 6.093206 -98.457766)
		(stroke
			(width 0.2)
			(type default)
		)
		(layer "In6.Cu")
	)
	(gr_line
		(start 6.094476 -121.5517)
		(end 6.091936 -121.551954)
		(stroke
			(width 0.2)
			(type default)
		)
		(layer "In6.Cu")
	)
	(gr_line
		(start 6.116574 -107.545378)
		(end 6.148324 -108.408216)
		(stroke
			(width 0.2)
			(type default)
		)
		(layer "In6.Cu")
	)
	(gr_arc
		(start 6.118606 -128.458214)
		(mid 6.705346 -129.044954)
		(end 7.292086 -128.458214)
		(stroke
			(width 0.2)
			(type default)
		)
		(layer "In6.Cu")
	)
	(gr_line
		(start 6.118606 -127.499364)
		(end 6.118606 -128.458214)
		(stroke
			(width 0.2)
			(type default)
		)
		(layer "In6.Cu")
	)
	(gr_line
		(start 6.119114 -107.545378)
		(end 6.116574 -107.545378)
		(stroke
			(width 0.2)
			(type default)
		)
		(layer "In6.Cu")
	)
	(gr_line
		(start 6.140704 -117.514624)
		(end 6.144006 -118.429532)
		(stroke
			(width 0.2)
			(type default)
		)
		(layer "In6.Cu")
	)
	(gr_line
		(start 6.142482 -111.613442)
		(end 6.16966 -112.476788)
		(stroke
			(width 0.2)
			(type default)
		)
		(layer "In6.Cu")
	)
	(gr_arc
		(start 6.144006 -118.429532)
		(mid 6.732778 -119.01424)
		(end 7.317486 -118.425468)
		(stroke
			(width 0.2)
			(type default)
		)
		(layer "In6.Cu")
	)
	(gr_line
		(start 6.1468 -122.41403)
		(end 6.14934 -122.413776)
		(stroke
			(width 0.2)
			(type default)
		)
		(layer "In6.Cu")
	)
	(gr_line
		(start 6.148324 -108.408216)
		(end 6.148578 -108.40847)
		(stroke
			(width 0.2)
			(type default)
		)
		(layer "In6.Cu")
	)
	(gr_line
		(start 6.148578 -108.40847)
		(end 6.150864 -108.40847)
		(stroke
			(width 0.2)
			(type default)
		)
		(layer "In6.Cu")
	)
	(gr_arc
		(start 6.14934 -122.413776)
		(mid 6.771894 -122.962162)
		(end 7.32028 -122.339608)
		(stroke
			(width 0.2)
			(type default)
		)
		(layer "In6.Cu")
	)
	(gr_arc
		(start 6.150864 -108.40847)
		(mid 6.758686 -108.973112)
		(end 7.323328 -108.36529)
		(stroke
			(width 0.2)
			(type default)
		)
		(layer "In6.Cu")
	)
	(gr_arc
		(start 6.164072 -162.459416)
		(mid 6.748272 -163.043616)
		(end 7.332472 -162.459416)
		(stroke
			(width 0.2)
			(type default)
		)
		(layer "In6.Cu")
	)
	(gr_line
		(start 6.164072 -161.5313)
		(end 6.164072 -162.459416)
		(stroke
			(width 0.2)
			(type default)
		)
		(layer "In6.Cu")
	)
	(gr_arc
		(start 6.169406 -134.442708)
		(mid 6.756146 -135.029448)
		(end 7.342886 -134.442708)
		(stroke
			(width 0.2)
			(type default)
		)
		(layer "In6.Cu")
	)
	(gr_line
		(start 6.169406 -133.514592)
		(end 6.169406 -134.442708)
		(stroke
			(width 0.2)
			(type default)
		)
		(layer "In6.Cu")
	)
	(gr_arc
		(start 6.16966 -112.476788)
		(mid 6.774688 -113.044732)
		(end 7.342632 -112.439704)
		(stroke
			(width 0.2)
			(type default)
		)
		(layer "In6.Cu")
	)
	(gr_line
		(start 6.205474 -165.630606)
		(end 6.272022 -166.797228)
		(stroke
			(width 0.2)
			(type default)
		)
		(layer "In6.Cu")
	)
	(gr_line
		(start 6.208014 -165.630352)
		(end 6.205474 -165.630606)
		(stroke
			(width 0.2)
			(type default)
		)
		(layer "In6.Cu")
	)
	(gr_line
		(start 6.21792 -116.441982)
		(end 6.22046 -116.441982)
		(stroke
			(width 0.2)
			(type default)
		)
		(layer "In6.Cu")
	)
	(gr_arc
		(start 6.22046 -116.441982)
		(mid 6.79069 -117.044724)
		(end 7.393432 -116.474494)
		(stroke
			(width 0.2)
			(type default)
		)
		(layer "In6.Cu")
	)
	(gr_line
		(start 6.24332 -115.515644)
		(end 6.21792 -116.441982)
		(stroke
			(width 0.2)
			(type default)
		)
		(layer "In6.Cu")
	)
	(gr_line
		(start 6.24586 -115.515644)
		(end 6.24332 -115.515644)
		(stroke
			(width 0.2)
			(type default)
		)
		(layer "In6.Cu")
	)
	(gr_line
		(start 6.272022 -166.797228)
		(end 6.274562 -166.796974)
		(stroke
			(width 0.2)
			(type default)
		)
		(layer "In6.Cu")
	)
	(gr_arc
		(start 6.274562 -166.796974)
		(mid 6.89102 -167.346884)
		(end 7.44093 -166.730426)
		(stroke
			(width 0.2)
			(type default)
		)
		(layer "In6.Cu")
	)
	(gr_arc
		(start 6.400546 -158.459678)
		(mid 6.984746 -159.043878)
		(end 7.568946 -158.459678)
		(stroke
			(width 0.2)
			(type default)
		)
		(layer "In6.Cu")
	)
	(gr_line
		(start 6.400546 -157.531562)
		(end 6.400546 -158.459678)
		(stroke
			(width 0.2)
			(type default)
		)
		(layer "In6.Cu")
	)
	(gr_arc
		(start 6.445758 -170.459654)
		(mid 7.032498 -171.046394)
		(end 7.619238 -170.459654)
		(stroke
			(width 0.2)
			(type default)
		)
		(layer "In6.Cu")
	)
	(gr_line
		(start 6.445758 -169.531538)
		(end 6.445758 -170.459654)
		(stroke
			(width 0.2)
			(type default)
		)
		(layer "In6.Cu")
	)
	(gr_arc
		(start 6.862318 -398.756378)
		(mid 6.30555 -399.366994)
		(end 6.916166 -399.923762)
		(stroke
			(width 0.2)
			(type default)
		)
		(layer "In6.Cu")
	)
	(gr_line
		(start 6.916166 -399.923762)
		(end 7.77875 -399.884138)
		(stroke
			(width 0.2)
			(type default)
		)
		(layer "In6.Cu")
	)
	(gr_line
		(start 7.003796 -352.786442)
		(end 7.004812 -352.788728)
		(stroke
			(width 0.2)
			(type default)
		)
		(layer "In6.Cu")
	)
	(gr_line
		(start 7.00405 -352.786188)
		(end 7.003796 -352.786442)
		(stroke
			(width 0.2)
			(type default)
		)
		(layer "In6.Cu")
	)
	(gr_arc
		(start 7.004812 -352.788728)
		(mid 6.70054 -353.560934)
		(end 7.47268 -353.864926)
		(stroke
			(width 0.2)
			(type default)
		)
		(layer "In6.Cu")
	)
	(gr_line
		(start 7.062978 -348.507812)
		(end 7.075932 -347.594174)
		(stroke
			(width 0.2)
			(type default)
		)
		(layer "In6.Cu")
	)
	(gr_arc
		(start 7.075932 -347.594174)
		(mid 6.500241 -347.001594)
		(end 5.907532 -347.577156)
		(stroke
			(width 0.2)
			(type default)
		)
		(layer "In6.Cu")
	)
	(gr_arc
		(start 7.215886 -413.544512)
		(mid 7.007016 -414.313851)
		(end 7.778242 -414.516062)
		(stroke
			(width 0.2)
			(type default)
		)
		(layer "In6.Cu")
	)
	(gr_line
		(start 7.249922 -422.467532)
		(end 8.113014 -422.489884)
		(stroke
			(width 0.2)
			(type default)
		)
		(layer "In6.Cu")
	)
	(gr_line
		(start 7.249922 -422.464992)
		(end 7.249922 -422.467532)
		(stroke
			(width 0.2)
			(type default)
		)
		(layer "In6.Cu")
	)
	(gr_line
		(start 7.265162 -368.402616)
		(end 8.127746 -368.441224)
		(stroke
			(width 0.2)
			(type default)
		)
		(layer "In6.Cu")
	)
	(gr_arc
		(start 7.265416 -121.477532)
		(mid 6.642862 -120.929146)
		(end 6.094476 -121.5517)
		(stroke
			(width 0.2)
			(type default)
		)
		(layer "In6.Cu")
	)
	(gr_line
		(start 7.266686 -102.457504)
		(end 7.266686 -101.498908)
		(stroke
			(width 0.2)
			(type default)
		)
		(layer "In6.Cu")
	)
	(gr_arc
		(start 7.266686 -101.498908)
		(mid 6.680073 -100.911914)
		(end 6.093206 -101.498654)
		(stroke
			(width 0.2)
			(type default)
		)
		(layer "In6.Cu")
	)
	(gr_line
		(start 7.266686 -98.457766)
		(end 7.266686 -97.49917)
		(stroke
			(width 0.2)
			(type default)
		)
		(layer "In6.Cu")
	)
	(gr_arc
		(start 7.266686 -97.49917)
		(mid 6.680073 -96.912176)
		(end 6.093206 -97.498916)
		(stroke
			(width 0.2)
			(type default)
		)
		(layer "In6.Cu")
	)
	(gr_line
		(start 7.267702 -121.477278)
		(end 7.265416 -121.477532)
		(stroke
			(width 0.2)
			(type default)
		)
		(layer "In6.Cu")
	)
	(gr_line
		(start 7.267956 -121.477532)
		(end 7.267702 -121.477278)
		(stroke
			(width 0.2)
			(type default)
		)
		(layer "In6.Cu")
	)
	(gr_arc
		(start 7.278878 -421.34282)
		(mid 6.703314 -421.889428)
		(end 7.249922 -422.464992)
		(stroke
			(width 0.2)
			(type default)
		)
		(layer "In6.Cu")
	)
	(gr_line
		(start 7.278878 -421.34028)
		(end 7.278878 -421.34282)
		(stroke
			(width 0.2)
			(type default)
		)
		(layer "In6.Cu")
	)
	(gr_arc
		(start 7.291578 -107.502198)
		(mid 6.683756 -106.937556)
		(end 6.119114 -107.545378)
		(stroke
			(width 0.2)
			(type default)
		)
		(layer "In6.Cu")
	)
	(gr_line
		(start 7.292086 -128.458214)
		(end 7.292086 -127.499618)
		(stroke
			(width 0.2)
			(type default)
		)
		(layer "In6.Cu")
	)
	(gr_arc
		(start 7.292086 -127.499618)
		(mid 6.705473 -126.912624)
		(end 6.118606 -127.499364)
		(stroke
			(width 0.2)
			(type default)
		)
		(layer "In6.Cu")
	)
	(gr_line
		(start 7.294118 -107.502198)
		(end 7.291578 -107.502198)
		(stroke
			(width 0.2)
			(type default)
		)
		(layer "In6.Cu")
	)
	(gr_arc
		(start 7.312914 -367.331752)
		(mid 6.753606 -367.843308)
		(end 7.265162 -368.402616)
		(stroke
			(width 0.2)
			(type default)
		)
		(layer "In6.Cu")
	)
	(gr_arc
		(start 7.314184 -117.510814)
		(mid 6.725539 -116.926106)
		(end 6.140704 -117.514624)
		(stroke
			(width 0.2)
			(type default)
		)
		(layer "In6.Cu")
	)
	(gr_arc
		(start 7.315454 -111.576612)
		(mid 6.710553 -111.008664)
		(end 6.142482 -111.613442)
		(stroke
			(width 0.2)
			(type default)
		)
		(layer "In6.Cu")
	)
	(gr_line
		(start 7.317486 -118.425468)
		(end 7.314184 -117.510814)
		(stroke
			(width 0.2)
			(type default)
		)
		(layer "In6.Cu")
	)
	(gr_line
		(start 7.32028 -122.339608)
		(end 7.32282 -122.339354)
		(stroke
			(width 0.2)
			(type default)
		)
		(layer "In6.Cu")
	)
	(gr_line
		(start 7.32282 -122.339354)
		(end 7.267956 -121.477532)
		(stroke
			(width 0.2)
			(type default)
		)
		(layer "In6.Cu")
	)
	(gr_line
		(start 7.323328 -108.36529)
		(end 7.325868 -108.36529)
		(stroke
			(width 0.2)
			(type default)
		)
		(layer "In6.Cu")
	)
	(gr_line
		(start 7.325868 -108.36529)
		(end 7.294118 -107.502198)
		(stroke
			(width 0.2)
			(type default)
		)
		(layer "In6.Cu")
	)
	(gr_line
		(start 7.332472 -162.459416)
		(end 7.332472 -161.531554)
		(stroke
			(width 0.2)
			(type default)
		)
		(layer "In6.Cu")
	)
	(gr_arc
		(start 7.332472 -161.531554)
		(mid 6.748399 -160.9471)
		(end 6.164072 -161.5313)
		(stroke
			(width 0.2)
			(type default)
		)
		(layer "In6.Cu")
	)
	(gr_line
		(start 7.340346 -410.396436)
		(end 8.203946 -410.396436)
		(stroke
			(width 0.2)
			(type default)
		)
		(layer "In6.Cu")
	)
	(gr_arc
		(start 7.340346 -409.273756)
		(mid 6.779006 -409.835096)
		(end 7.340346 -410.396436)
		(stroke
			(width 0.2)
			(type default)
		)
		(layer "In6.Cu")
	)
	(gr_line
		(start 7.3406 -409.273756)
		(end 7.340346 -409.273756)
		(stroke
			(width 0.2)
			(type default)
		)
		(layer "In6.Cu")
	)
	(gr_line
		(start 7.342632 -112.439704)
		(end 7.315454 -111.576612)
		(stroke
			(width 0.2)
			(type default)
		)
		(layer "In6.Cu")
	)
	(gr_line
		(start 7.342886 -134.442708)
		(end 7.342886 -133.514846)
		(stroke
			(width 0.2)
			(type default)
		)
		(layer "In6.Cu")
	)
	(gr_arc
		(start 7.342886 -133.514846)
		(mid 6.756273 -132.927852)
		(end 6.169406 -133.514592)
		(stroke
			(width 0.2)
			(type default)
		)
		(layer "In6.Cu")
	)
	(gr_arc
		(start 7.351776 -357.949754)
		(mid 6.7818 -358.54767)
		(end 7.379716 -359.117646)
		(stroke
			(width 0.2)
			(type default)
		)
		(layer "In6.Cu")
	)
	(gr_line
		(start 7.351776 -357.947214)
		(end 7.351776 -357.949754)
		(stroke
			(width 0.2)
			(type default)
		)
		(layer "In6.Cu")
	)
	(gr_line
		(start 7.358888 -424.590464)
		(end 8.22071 -424.642788)
		(stroke
			(width 0.2)
			(type default)
		)
		(layer "In6.Cu")
	)
	(gr_line
		(start 7.359142 -424.587924)
		(end 7.358888 -424.590464)
		(stroke
			(width 0.2)
			(type default)
		)
		(layer "In6.Cu")
	)
	(gr_arc
		(start 7.374382 -165.563804)
		(mid 6.757924 -165.013894)
		(end 6.208014 -165.630352)
		(stroke
			(width 0.2)
			(type default)
		)
		(layer "In6.Cu")
	)
	(gr_line
		(start 7.375398 -363.918246)
		(end 7.376922 -363.920278)
		(stroke
			(width 0.2)
			(type default)
		)
		(layer "In6.Cu")
	)
	(gr_line
		(start 7.376668 -165.563804)
		(end 7.374382 -165.563804)
		(stroke
			(width 0.2)
			(type default)
		)
		(layer "In6.Cu")
	)
	(gr_arc
		(start 7.376922 -363.920278)
		(mid 7.291324 -364.745524)
		(end 8.11657 -364.831122)
		(stroke
			(width 0.2)
			(type default)
		)
		(layer "In6.Cu")
	)
	(gr_line
		(start 7.376922 -165.563804)
		(end 7.376668 -165.563804)
		(stroke
			(width 0.2)
			(type default)
		)
		(layer "In6.Cu")
	)
	(gr_line
		(start 7.379716 -359.120186)
		(end 8.25627 -359.099358)
		(stroke
			(width 0.2)
			(type default)
		)
		(layer "In6.Cu")
	)
	(gr_line
		(start 7.379716 -359.117646)
		(end 7.379716 -359.120186)
		(stroke
			(width 0.2)
			(type default)
		)
		(layer "In6.Cu")
	)
	(gr_line
		(start 7.393432 -116.474494)
		(end 7.395972 -116.474494)
		(stroke
			(width 0.2)
			(type default)
		)
		(layer "In6.Cu")
	)
	(gr_line
		(start 7.395972 -116.474494)
		(end 7.421372 -115.54841)
		(stroke
			(width 0.2)
			(type default)
		)
		(layer "In6.Cu")
	)
	(gr_arc
		(start 7.418832 -115.548156)
		(mid 6.848602 -114.945414)
		(end 6.24586 -115.515644)
		(stroke
			(width 0.2)
			(type default)
		)
		(layer "In6.Cu")
	)
	(gr_line
		(start 7.421118 -115.548156)
		(end 7.418832 -115.548156)
		(stroke
			(width 0.2)
			(type default)
		)
		(layer "In6.Cu")
	)
	(gr_line
		(start 7.421372 -115.54841)
		(end 7.421118 -115.548156)
		(stroke
			(width 0.2)
			(type default)
		)
		(layer "In6.Cu")
	)
	(gr_arc
		(start 7.423658 -423.518076)
		(mid 6.856476 -424.020742)
		(end 7.359142 -424.587924)
		(stroke
			(width 0.2)
			(type default)
		)
		(layer "In6.Cu")
	)
	(gr_line
		(start 7.423912 -423.515536)
		(end 7.423658 -423.518076)
		(stroke
			(width 0.2)
			(type default)
		)
		(layer "In6.Cu")
	)
	(gr_line
		(start 7.44093 -166.730426)
		(end 7.44347 -166.730172)
		(stroke
			(width 0.2)
			(type default)
		)
		(layer "In6.Cu")
	)
	(gr_line
		(start 7.44347 -166.730172)
		(end 7.376922 -165.563804)
		(stroke
			(width 0.2)
			(type default)
		)
		(layer "In6.Cu")
	)
	(gr_line
		(start 7.47268 -353.864926)
		(end 7.473696 -353.867212)
		(stroke
			(width 0.2)
			(type default)
		)
		(layer "In6.Cu")
	)
	(gr_line
		(start 7.473696 -353.867212)
		(end 8.447532 -353.443794)
		(stroke
			(width 0.2)
			(type default)
		)
		(layer "In6.Cu")
	)
	(gr_line
		(start 7.516622 -418.417248)
		(end 8.380222 -418.429694)
		(stroke
			(width 0.2)
			(type default)
		)
		(layer "In6.Cu")
	)
	(gr_arc
		(start 7.53364 -417.243768)
		(mid 6.93852 -417.821999)
		(end 7.516622 -418.417248)
		(stroke
			(width 0.2)
			(type default)
		)
		(layer "In6.Cu")
	)
	(gr_arc
		(start 7.566406 -386.461)
		(mid 8.127746 -387.02234)
		(end 8.689086 -386.461)
		(stroke
			(width 0.2)
			(type default)
		)
		(layer "In6.Cu")
	)
	(gr_line
		(start 7.566406 -385.532884)
		(end 7.566406 -386.461)
		(stroke
			(width 0.2)
			(type default)
		)
		(layer "In6.Cu")
	)
	(gr_line
		(start 7.568946 -158.459678)
		(end 7.568946 -157.531816)
		(stroke
			(width 0.2)
			(type default)
		)
		(layer "In6.Cu")
	)
	(gr_arc
		(start 7.568946 -157.531816)
		(mid 6.984873 -156.947362)
		(end 6.400546 -157.531562)
		(stroke
			(width 0.2)
			(type default)
		)
		(layer "In6.Cu")
	)
	(gr_line
		(start 7.619238 -170.459654)
		(end 7.619238 -169.531792)
		(stroke
			(width 0.2)
			(type default)
		)
		(layer "In6.Cu")
	)
	(gr_arc
		(start 7.619238 -169.531792)
		(mid 7.032625 -168.944798)
		(end 6.445758 -169.531538)
		(stroke
			(width 0.2)
			(type default)
		)
		(layer "In6.Cu")
	)
	(gr_line
		(start 7.623048 -384.608832)
		(end 8.485886 -384.647186)
		(stroke
			(width 0.2)
			(type default)
		)
		(layer "In6.Cu")
	)
	(gr_arc
		(start 7.675626 -383.436368)
		(mid 7.063238 -383.996311)
		(end 7.623048 -384.608832)
		(stroke
			(width 0.2)
			(type default)
		)
		(layer "In6.Cu")
	)
	(gr_line
		(start 7.689088 -372.065804)
		(end 8.587486 -372.107206)
		(stroke
			(width 0.2)
			(type default)
		)
		(layer "In6.Cu")
	)
	(gr_line
		(start 7.725156 -398.716754)
		(end 6.862318 -398.756378)
		(stroke
			(width 0.2)
			(type default)
		)
		(layer "In6.Cu")
	)
	(gr_arc
		(start 7.74319 -370.89334)
		(mid 7.13004 -371.452521)
		(end 7.689088 -372.065804)
		(stroke
			(width 0.2)
			(type default)
		)
		(layer "In6.Cu")
	)
	(gr_line
		(start 7.746746 -380.96444)
		(end 8.660892 -380.96444)
		(stroke
			(width 0.2)
			(type default)
		)
		(layer "In6.Cu")
	)
	(gr_arc
		(start 7.746746 -379.79096)
		(mid 7.160006 -380.3777)
		(end 7.746746 -380.96444)
		(stroke
			(width 0.2)
			(type default)
		)
		(layer "In6.Cu")
	)
	(gr_line
		(start 7.778242 -414.516062)
		(end 8.581898 -414.041336)
		(stroke
			(width 0.2)
			(type default)
		)
		(layer "In6.Cu")
	)
	(gr_arc
		(start 7.77875 -399.884138)
		(mid 8.335766 -399.273649)
		(end 7.725156 -398.716754)
		(stroke
			(width 0.2)
			(type default)
		)
		(layer "In6.Cu")
	)
	(gr_line
		(start 7.817104 -375.905268)
		(end 7.817358 -375.907808)
		(stroke
			(width 0.2)
			(type default)
		)
		(layer "In6.Cu")
	)
	(gr_arc
		(start 7.817358 -375.907808)
		(mid 7.340854 -376.497088)
		(end 7.930134 -376.973592)
		(stroke
			(width 0.2)
			(type default)
		)
		(layer "In6.Cu")
	)
	(gr_line
		(start 7.930134 -376.973592)
		(end 7.930388 -376.976132)
		(stroke
			(width 0.2)
			(type default)
		)
		(layer "In6.Cu")
	)
	(gr_line
		(start 7.930388 -376.976132)
		(end 8.810498 -376.882914)
		(stroke
			(width 0.2)
			(type default)
		)
		(layer "In6.Cu")
	)
	(gr_line
		(start 7.977632 -352.36277)
		(end 7.00405 -352.786188)
		(stroke
			(width 0.2)
			(type default)
		)
		(layer "In6.Cu")
	)
	(gr_line
		(start 7.978648 -352.365056)
		(end 7.977632 -352.36277)
		(stroke
			(width 0.2)
			(type default)
		)
		(layer "In6.Cu")
	)
	(gr_line
		(start 8.010906 -413.074612)
		(end 7.215886 -413.544512)
		(stroke
			(width 0.2)
			(type default)
		)
		(layer "In6.Cu")
	)
	(gr_line
		(start 8.062976 -363.359954)
		(end 7.375398 -363.918246)
		(stroke
			(width 0.2)
			(type default)
		)
		(layer "In6.Cu")
	)
	(gr_line
		(start 8.0645 -363.361986)
		(end 8.062976 -363.359954)
		(stroke
			(width 0.2)
			(type default)
		)
		(layer "In6.Cu")
	)
	(gr_line
		(start 8.113014 -422.489884)
		(end 8.113268 -422.48963)
		(stroke
			(width 0.2)
			(type default)
		)
		(layer "In6.Cu")
	)
	(gr_line
		(start 8.113268 -422.48963)
		(end 8.113268 -422.487344)
		(stroke
			(width 0.2)
			(type default)
		)
		(layer "In6.Cu")
	)
	(gr_arc
		(start 8.113268 -422.487344)
		(mid 8.688832 -421.940736)
		(end 8.142224 -421.365172)
		(stroke
			(width 0.2)
			(type default)
		)
		(layer "In6.Cu")
	)
	(gr_line
		(start 8.11657 -364.831122)
		(end 8.118094 -364.833154)
		(stroke
			(width 0.2)
			(type default)
		)
		(layer "In6.Cu")
	)
	(gr_line
		(start 8.118094 -364.833154)
		(end 8.805672 -364.275116)
		(stroke
			(width 0.2)
			(type default)
		)
		(layer "In6.Cu")
	)
	(gr_arc
		(start 8.127746 -368.441224)
		(mid 8.687314 -367.929795)
		(end 8.175752 -367.37036)
		(stroke
			(width 0.2)
			(type default)
		)
		(layer "In6.Cu")
	)
	(gr_line
		(start 8.142224 -421.365172)
		(end 8.142224 -421.362632)
		(stroke
			(width 0.2)
			(type default)
		)
		(layer "In6.Cu")
	)
	(gr_line
		(start 8.142224 -421.362632)
		(end 7.278878 -421.34028)
		(stroke
			(width 0.2)
			(type default)
		)
		(layer "In6.Cu")
	)
	(gr_line
		(start 8.175752 -367.37036)
		(end 7.312914 -367.331752)
		(stroke
			(width 0.2)
			(type default)
		)
		(layer "In6.Cu")
	)
	(gr_arc
		(start 8.203946 -410.396436)
		(mid 8.765286 -409.835096)
		(end 8.203946 -409.273756)
		(stroke
			(width 0.2)
			(type default)
		)
		(layer "In6.Cu")
	)
	(gr_line
		(start 8.203946 -409.273756)
		(end 7.3406 -409.273756)
		(stroke
			(width 0.2)
			(type default)
		)
		(layer "In6.Cu")
	)
	(gr_line
		(start 8.22071 -424.642788)
		(end 8.220964 -424.642534)
		(stroke
			(width 0.2)
			(type default)
		)
		(layer "In6.Cu")
	)
	(gr_line
		(start 8.220964 -424.642534)
		(end 8.221218 -424.640248)
		(stroke
			(width 0.2)
			(type default)
		)
		(layer "In6.Cu")
	)
	(gr_arc
		(start 8.221218 -424.640248)
		(mid 8.7884 -424.137582)
		(end 8.285734 -423.5704)
		(stroke
			(width 0.2)
			(type default)
		)
		(layer "In6.Cu")
	)
	(gr_line
		(start 8.228584 -357.928926)
		(end 8.228584 -357.926386)
		(stroke
			(width 0.2)
			(type default)
		)
		(layer "In6.Cu")
	)
	(gr_line
		(start 8.228584 -357.926386)
		(end 7.351776 -357.947214)
		(stroke
			(width 0.2)
			(type default)
		)
		(layer "In6.Cu")
	)
	(gr_line
		(start 8.25627 -359.099358)
		(end 8.256524 -359.099104)
		(stroke
			(width 0.2)
			(type default)
		)
		(layer "In6.Cu")
	)
	(gr_line
		(start 8.256524 -359.099104)
		(end 8.256524 -359.096818)
		(stroke
			(width 0.2)
			(type default)
		)
		(layer "In6.Cu")
	)
	(gr_arc
		(start 8.256524 -359.096818)
		(mid 8.8265 -358.498902)
		(end 8.228584 -357.928926)
		(stroke
			(width 0.2)
			(type default)
		)
		(layer "In6.Cu")
	)
	(gr_line
		(start 8.285734 -423.5704)
		(end 8.285988 -423.56786)
		(stroke
			(width 0.2)
			(type default)
		)
		(layer "In6.Cu")
	)
	(gr_line
		(start 8.285988 -423.56786)
		(end 7.423912 -423.515536)
		(stroke
			(width 0.2)
			(type default)
		)
		(layer "In6.Cu")
	)
	(gr_arc
		(start 8.380222 -418.429694)
		(mid 8.975344 -417.851336)
		(end 8.396986 -417.256214)
		(stroke
			(width 0.2)
			(type default)
		)
		(layer "In6.Cu")
	)
	(gr_line
		(start 8.396986 -417.256214)
		(end 7.53364 -417.243768)
		(stroke
			(width 0.2)
			(type default)
		)
		(layer "In6.Cu")
	)
	(gr_arc
		(start 8.446516 -353.441508)
		(mid 8.750808 -352.669348)
		(end 7.978648 -352.365056)
		(stroke
			(width 0.2)
			(type default)
		)
		(layer "In6.Cu")
	)
	(gr_line
		(start 8.447532 -353.443794)
		(end 8.446516 -353.441508)
		(stroke
			(width 0.2)
			(type default)
		)
		(layer "In6.Cu")
	)
	(gr_arc
		(start 8.485886 -384.647186)
		(mid 9.09828 -384.087116)
		(end 8.53821 -383.474722)
		(stroke
			(width 0.2)
			(type default)
		)
		(layer "In6.Cu")
	)
	(gr_line
		(start 8.53821 -383.474722)
		(end 7.675626 -383.436368)
		(stroke
			(width 0.2)
			(type default)
		)
		(layer "In6.Cu")
	)
	(gr_arc
		(start 8.581898 -414.041336)
		(mid 8.779764 -413.272478)
		(end 8.010906 -413.074612)
		(stroke
			(width 0.2)
			(type default)
		)
		(layer "In6.Cu")
	)
	(gr_arc
		(start 8.587486 -372.107206)
		(mid 9.200642 -371.547898)
		(end 8.641334 -370.934742)
		(stroke
			(width 0.2)
			(type default)
		)
		(layer "In6.Cu")
	)
	(gr_line
		(start 8.641334 -370.934742)
		(end 7.74319 -370.89334)
		(stroke
			(width 0.2)
			(type default)
		)
		(layer "In6.Cu")
	)
	(gr_line
		(start 8.660892 -380.96444)
		(end 8.661146 -380.96444)
		(stroke
			(width 0.2)
			(type default)
		)
		(layer "In6.Cu")
	)
	(gr_arc
		(start 8.661146 -380.96444)
		(mid 9.247886 -380.3777)
		(end 8.661146 -379.79096)
		(stroke
			(width 0.2)
			(type default)
		)
		(layer "In6.Cu")
	)
	(gr_line
		(start 8.661146 -379.79096)
		(end 7.746746 -379.79096)
		(stroke
			(width 0.2)
			(type default)
		)
		(layer "In6.Cu")
	)
	(gr_arc
		(start 8.684006 -132.4737)
		(mid 9.270746 -133.06044)
		(end 9.857486 -132.4737)
		(stroke
			(width 0.2)
			(type default)
		)
		(layer "In6.Cu")
	)
	(gr_line
		(start 8.684006 -131.51485)
		(end 8.684006 -132.4737)
		(stroke
			(width 0.2)
			(type default)
		)
		(layer "In6.Cu")
	)
	(gr_line
		(start 8.689086 -386.461)
		(end 8.689086 -385.533138)
		(stroke
			(width 0.2)
			(type default)
		)
		(layer "In6.Cu")
	)
	(gr_arc
		(start 8.689086 -385.533138)
		(mid 8.127873 -384.971544)
		(end 7.566406 -385.532884)
		(stroke
			(width 0.2)
			(type default)
		)
		(layer "In6.Cu")
	)
	(gr_line
		(start 8.697468 -375.81205)
		(end 7.817104 -375.905268)
		(stroke
			(width 0.2)
			(type default)
		)
		(layer "In6.Cu")
	)
	(gr_line
		(start 8.697722 -375.81459)
		(end 8.697468 -375.81205)
		(stroke
			(width 0.2)
			(type default)
		)
		(layer "In6.Cu")
	)
	(gr_arc
		(start 8.804148 -364.27283)
		(mid 8.889746 -363.447584)
		(end 8.0645 -363.361986)
		(stroke
			(width 0.2)
			(type default)
		)
		(layer "In6.Cu")
	)
	(gr_line
		(start 8.805672 -364.275116)
		(end 8.805672 -364.274608)
		(stroke
			(width 0.2)
			(type default)
		)
		(layer "In6.Cu")
	)
	(gr_line
		(start 8.805672 -364.274608)
		(end 8.804148 -364.27283)
		(stroke
			(width 0.2)
			(type default)
		)
		(layer "In6.Cu")
	)
	(gr_line
		(start 8.810498 -376.882914)
		(end 8.810752 -376.88266)
		(stroke
			(width 0.2)
			(type default)
		)
		(layer "In6.Cu")
	)
	(gr_arc
		(start 8.810498 -376.880374)
		(mid 9.287002 -376.291094)
		(end 8.697722 -375.81459)
		(stroke
			(width 0.2)
			(type default)
		)
		(layer "In6.Cu")
	)
	(gr_line
		(start 8.810752 -376.88266)
		(end 8.810498 -376.880374)
		(stroke
			(width 0.2)
			(type default)
		)
		(layer "In6.Cu")
	)
	(gr_line
		(start 9.857486 -132.4737)
		(end 9.857486 -131.515104)
		(stroke
			(width 0.2)
			(type default)
		)
		(layer "In6.Cu")
	)
	(gr_arc
		(start 9.857486 -131.515104)
		(mid 9.270873 -130.92811)
		(end 8.684006 -131.51485)
		(stroke
			(width 0.2)
			(type default)
		)
		(layer "In6.Cu")
	)
	(gr_arc
		(start 11.066018 -439.032904)
		(mid 11.652631 -439.619898)
		(end 12.239498 -439.033158)
		(stroke
			(width 0.2)
			(type default)
		)
		(layer "In6.Cu")
	)
	(gr_line
		(start 11.066018 -438.105042)
		(end 11.066018 -439.032904)
		(stroke
			(width 0.2)
			(type default)
		)
		(layer "In6.Cu")
	)
	(gr_line
		(start 11.0744 -441.81014)
		(end 11.937746 -441.81014)
		(stroke
			(width 0.2)
			(type default)
		)
		(layer "In6.Cu")
	)
	(gr_arc
		(start 11.0744 -440.63666)
		(mid 10.48766 -441.2234)
		(end 11.0744 -441.81014)
		(stroke
			(width 0.2)
			(type default)
		)
		(layer "In6.Cu")
	)
	(gr_line
		(start 11.937746 -441.81014)
		(end 11.938 -441.81014)
		(stroke
			(width 0.2)
			(type default)
		)
		(layer "In6.Cu")
	)
	(gr_arc
		(start 11.938 -441.81014)
		(mid 12.52474 -441.2234)
		(end 11.938 -440.63666)
		(stroke
			(width 0.2)
			(type default)
		)
		(layer "In6.Cu")
	)
	(gr_line
		(start 11.938 -440.63666)
		(end 11.0744 -440.63666)
		(stroke
			(width 0.2)
			(type default)
		)
		(layer "In6.Cu")
	)
	(gr_arc
		(start 12.192254 -177.578004)
		(mid 12.757404 -178.180746)
		(end 13.360146 -177.615596)
		(stroke
			(width 0.2)
			(type default)
		)
		(layer "In6.Cu")
	)
	(gr_line
		(start 12.220194 -176.714658)
		(end 12.192254 -177.578004)
		(stroke
			(width 0.2)
			(type default)
		)
		(layer "In6.Cu")
	)
	(gr_line
		(start 12.239498 -439.033158)
		(end 12.239498 -438.105042)
		(stroke
			(width 0.2)
			(type default)
		)
		(layer "In6.Cu")
	)
	(gr_arc
		(start 12.239498 -438.105042)
		(mid 11.652758 -437.518302)
		(end 11.066018 -438.105042)
		(stroke
			(width 0.2)
			(type default)
		)
		(layer "In6.Cu")
	)
	(gr_line
		(start 13.360146 -177.615596)
		(end 13.388086 -176.752504)
		(stroke
			(width 0.2)
			(type default)
		)
		(layer "In6.Cu")
	)
	(gr_arc
		(start 13.388086 -176.752504)
		(mid 12.823063 -176.149766)
		(end 12.220194 -176.714658)
		(stroke
			(width 0.2)
			(type default)
		)
		(layer "In6.Cu")
	)
	(gr_arc
		(start 14.653006 -136.536938)
		(mid 15.238984 -137.12444)
		(end 15.826486 -136.538462)
		(stroke
			(width 0.2)
			(type default)
		)
		(layer "In6.Cu")
	)
	(gr_line
		(start 14.654022 -135.673338)
		(end 14.653006 -136.536938)
		(stroke
			(width 0.2)
			(type default)
		)
		(layer "In6.Cu")
	)
	(gr_arc
		(start 15.770098 -120.508268)
		(mid 16.355822 -121.096024)
		(end 16.943578 -120.5103)
		(stroke
			(width 0.2)
			(type default)
		)
		(layer "In6.Cu")
	)
	(gr_line
		(start 15.771622 -119.644668)
		(end 15.770098 -120.508268)
		(stroke
			(width 0.2)
			(type default)
		)
		(layer "In6.Cu")
	)
	(gr_line
		(start 15.826486 -136.538462)
		(end 15.827502 -135.675116)
		(stroke
			(width 0.2)
			(type default)
		)
		(layer "In6.Cu")
	)
	(gr_arc
		(start 15.827502 -135.675116)
		(mid 15.241651 -135.087614)
		(end 14.654022 -135.673338)
		(stroke
			(width 0.2)
			(type default)
		)
		(layer "In6.Cu")
	)
	(gr_line
		(start 16.943578 -120.5103)
		(end 16.945102 -119.646954)
		(stroke
			(width 0.2)
			(type default)
		)
		(layer "In6.Cu")
	)
	(gr_arc
		(start 16.945102 -119.646954)
		(mid 16.359505 -119.059198)
		(end 15.771622 -119.644668)
		(stroke
			(width 0.2)
			(type default)
		)
		(layer "In6.Cu")
	)
	(gr_line
		(start 21.053044 -444.232792)
		(end 21.090382 -445.095376)
		(stroke
			(width 0.2)
			(type default)
		)
		(layer "In6.Cu")
	)
	(gr_arc
		(start 21.090382 -445.095376)
		(mid 21.701887 -445.656457)
		(end 22.262846 -445.04483)
		(stroke
			(width 0.2)
			(type default)
		)
		(layer "In6.Cu")
	)
	(gr_arc
		(start 21.26107 -238.799624)
		(mid 21.774529 -239.451657)
		(end 22.426422 -238.938054)
		(stroke
			(width 0.2)
			(type default)
		)
		(layer "In6.Cu")
	)
	(gr_arc
		(start 21.307806 -136.15035)
		(mid 21.894546 -136.73709)
		(end 22.481286 -136.15035)
		(stroke
			(width 0.2)
			(type default)
		)
		(layer "In6.Cu")
	)
	(gr_line
		(start 21.307806 -135.1915)
		(end 21.307806 -136.15035)
		(stroke
			(width 0.2)
			(type default)
		)
		(layer "In6.Cu")
	)
	(gr_line
		(start 21.36267 -237.941612)
		(end 21.26107 -238.799624)
		(stroke
			(width 0.2)
			(type default)
		)
		(layer "In6.Cu")
	)
	(gr_line
		(start 21.411184 -32.240474)
		(end 21.487384 -33.209738)
		(stroke
			(width 0.2)
			(type default)
		)
		(layer "In6.Cu")
	)
	(gr_arc
		(start 21.48586 -342.045036)
		(mid 22.069933 -342.62949)
		(end 22.65426 -342.04529)
		(stroke
			(width 0.2)
			(type default)
		)
		(layer "In6.Cu")
	)
	(gr_line
		(start 21.48586 -341.08644)
		(end 21.48586 -342.045036)
		(stroke
			(width 0.2)
			(type default)
		)
		(layer "In6.Cu")
	)
	(gr_arc
		(start 21.487384 -33.209738)
		(mid 22.118192 -33.74897)
		(end 22.657308 -33.118044)
		(stroke
			(width 0.2)
			(type default)
		)
		(layer "In6.Cu")
	)
	(gr_arc
		(start 22.225508 -444.181992)
		(mid 21.613876 -443.62116)
		(end 21.053044 -444.232792)
		(stroke
			(width 0.2)
			(type default)
		)
		(layer "In6.Cu")
	)
	(gr_line
		(start 22.262846 -445.04483)
		(end 22.225508 -444.181992)
		(stroke
			(width 0.2)
			(type default)
		)
		(layer "In6.Cu")
	)
	(gr_line
		(start 22.426422 -238.938054)
		(end 22.528022 -238.079788)
		(stroke
			(width 0.2)
			(type default)
		)
		(layer "In6.Cu")
	)
	(gr_line
		(start 22.481286 -136.15035)
		(end 22.481286 -135.191754)
		(stroke
			(width 0.2)
			(type default)
		)
		(layer "In6.Cu")
	)
	(gr_arc
		(start 22.481286 -135.191754)
		(mid 21.894673 -134.60476)
		(end 21.307806 -135.1915)
		(stroke
			(width 0.2)
			(type default)
		)
		(layer "In6.Cu")
	)
	(gr_arc
		(start 22.528022 -238.079788)
		(mid 22.014434 -237.428024)
		(end 21.36267 -237.941612)
		(stroke
			(width 0.2)
			(type default)
		)
		(layer "In6.Cu")
	)
	(gr_arc
		(start 22.581108 -32.148526)
		(mid 21.950172 -31.609538)
		(end 21.411184 -32.240474)
		(stroke
			(width 0.2)
			(type default)
		)
		(layer "In6.Cu")
	)
	(gr_line
		(start 22.65426 -342.04529)
		(end 22.65426 -341.08644)
		(stroke
			(width 0.2)
			(type default)
		)
		(layer "In6.Cu")
	)
	(gr_arc
		(start 22.65426 -341.08644)
		(mid 22.07006 -340.50224)
		(end 21.48586 -341.08644)
		(stroke
			(width 0.2)
			(type default)
		)
		(layer "In6.Cu")
	)
	(gr_line
		(start 22.657308 -33.118044)
		(end 22.581108 -32.148526)
		(stroke
			(width 0.2)
			(type default)
		)
		(layer "In6.Cu")
	)
	(gr_arc
		(start 24.052022 -349.878904)
		(mid 24.606504 -350.496378)
		(end 25.223978 -349.941896)
		(stroke
			(width 0.2)
			(type default)
		)
		(layer "In6.Cu")
	)
	(gr_line
		(start 24.110188 -348.796102)
		(end 24.052022 -349.878904)
		(stroke
			(width 0.2)
			(type default)
		)
		(layer "In6.Cu")
	)
	(gr_line
		(start 24.257 -130.99034)
		(end 25.1206 -130.99034)
		(stroke
			(width 0.2)
			(type default)
		)
		(layer "In6.Cu")
	)
	(gr_arc
		(start 24.257 -129.81686)
		(mid 23.67026 -130.4036)
		(end 24.257 -130.99034)
		(stroke
			(width 0.2)
			(type default)
		)
		(layer "In6.Cu")
	)
	(gr_arc
		(start 25.1206 -130.99034)
		(mid 25.70734 -130.4036)
		(end 25.1206 -129.81686)
		(stroke
			(width 0.2)
			(type default)
		)
		(layer "In6.Cu")
	)
	(gr_line
		(start 25.1206 -129.81686)
		(end 24.257 -129.81686)
		(stroke
			(width 0.2)
			(type default)
		)
		(layer "In6.Cu")
	)
	(gr_line
		(start 25.223978 -349.941896)
		(end 25.282144 -348.859348)
		(stroke
			(width 0.2)
			(type default)
		)
		(layer "In6.Cu")
	)
	(gr_arc
		(start 25.282144 -348.859348)
		(mid 24.727789 -348.241881)
		(end 24.110188 -348.796102)
		(stroke
			(width 0.2)
			(type default)
		)
		(layer "In6.Cu")
	)
	(gr_arc
		(start 25.41016 -342.431116)
		(mid 25.9969 -343.017856)
		(end 26.58364 -342.431116)
		(stroke
			(width 0.2)
			(type default)
		)
		(layer "In6.Cu")
	)
	(gr_line
		(start 25.41016 -341.503)
		(end 25.41016 -342.431116)
		(stroke
			(width 0.2)
			(type default)
		)
		(layer "In6.Cu")
	)
	(gr_line
		(start 26.06675 -365.929672)
		(end 26.083006 -367.02365)
		(stroke
			(width 0.2)
			(type default)
		)
		(layer "In6.Cu")
	)
	(gr_arc
		(start 26.083006 -367.02365)
		(mid 26.678382 -367.601754)
		(end 27.256486 -367.006378)
		(stroke
			(width 0.2)
			(type default)
		)
		(layer "In6.Cu")
	)
	(gr_line
		(start 26.58364 -342.431116)
		(end 26.58364 -341.503254)
		(stroke
			(width 0.2)
			(type default)
		)
		(layer "In6.Cu")
	)
	(gr_arc
		(start 26.58364 -341.503254)
		(mid 25.997027 -340.91626)
		(end 25.41016 -341.503)
		(stroke
			(width 0.2)
			(type default)
		)
		(layer "In6.Cu")
	)
	(gr_arc
		(start 27.061414 -236.59719)
		(mid 27.602942 -237.226094)
		(end 28.231846 -236.684566)
		(stroke
			(width 0.2)
			(type default)
		)
		(layer "In6.Cu")
	)
	(gr_line
		(start 27.12593 -235.731812)
		(end 27.061414 -236.59719)
		(stroke
			(width 0.2)
			(type default)
		)
		(layer "In6.Cu")
	)
	(gr_arc
		(start 27.157172 -339.620606)
		(mid 27.743785 -340.2076)
		(end 28.330652 -339.62086)
		(stroke
			(width 0.2)
			(type default)
		)
		(layer "In6.Cu")
	)
	(gr_line
		(start 27.157172 -338.66201)
		(end 27.157172 -339.620606)
		(stroke
			(width 0.2)
			(type default)
		)
		(layer "In6.Cu")
	)
	(gr_line
		(start 27.19832 -441.860432)
		(end 27.22372 -442.876178)
		(stroke
			(width 0.2)
			(type default)
		)
		(layer "In6.Cu")
	)
	(gr_line
		(start 27.20086 -441.860432)
		(end 27.19832 -441.860432)
		(stroke
			(width 0.2)
			(type default)
		)
		(layer "In6.Cu")
	)
	(gr_line
		(start 27.22372 -442.876178)
		(end 27.223974 -442.876432)
		(stroke
			(width 0.2)
			(type default)
		)
		(layer "In6.Cu")
	)
	(gr_line
		(start 27.223974 -442.876432)
		(end 27.22626 -442.876432)
		(stroke
			(width 0.2)
			(type default)
		)
		(layer "In6.Cu")
	)
	(gr_arc
		(start 27.22626 -442.876432)
		(mid 27.827478 -443.448186)
		(end 28.399232 -442.846968)
		(stroke
			(width 0.2)
			(type default)
		)
		(layer "In6.Cu")
	)
	(gr_arc
		(start 27.24023 -365.912654)
		(mid 26.644981 -365.334548)
		(end 26.06675 -365.929672)
		(stroke
			(width 0.2)
			(type default)
		)
		(layer "In6.Cu")
	)
	(gr_line
		(start 27.256486 -367.006378)
		(end 27.24023 -365.912654)
		(stroke
			(width 0.2)
			(type default)
		)
		(layer "In6.Cu")
	)
	(gr_line
		(start 27.980894 -345.078304)
		(end 28.12288 -345.93022)
		(stroke
			(width 0.2)
			(type default)
		)
		(layer "In6.Cu")
	)
	(gr_arc
		(start 28.12288 -345.93022)
		(mid 28.798266 -346.412566)
		(end 29.280612 -345.73718)
		(stroke
			(width 0.2)
			(type default)
		)
		(layer "In6.Cu")
	)
	(gr_line
		(start 28.231846 -236.684566)
		(end 28.296362 -235.819442)
		(stroke
			(width 0.2)
			(type default)
		)
		(layer "In6.Cu")
	)
	(gr_arc
		(start 28.24226 -342.431116)
		(mid 28.829 -343.017856)
		(end 29.41574 -342.431116)
		(stroke
			(width 0.2)
			(type default)
		)
		(layer "In6.Cu")
	)
	(gr_line
		(start 28.24226 -341.503)
		(end 28.24226 -342.431116)
		(stroke
			(width 0.2)
			(type default)
		)
		(layer "In6.Cu")
	)
	(gr_arc
		(start 28.296362 -235.819442)
		(mid 27.75496 -235.190547)
		(end 27.12593 -235.731812)
		(stroke
			(width 0.2)
			(type default)
		)
		(layer "In6.Cu")
	)
	(gr_line
		(start 28.330652 -339.62086)
		(end 28.330652 -338.66201)
		(stroke
			(width 0.2)
			(type default)
		)
		(layer "In6.Cu")
	)
	(gr_arc
		(start 28.330652 -338.66201)
		(mid 27.743912 -338.07527)
		(end 27.157172 -338.66201)
		(stroke
			(width 0.2)
			(type default)
		)
		(layer "In6.Cu")
	)
	(gr_arc
		(start 28.373832 -441.830968)
		(mid 27.772614 -441.259214)
		(end 27.20086 -441.860432)
		(stroke
			(width 0.2)
			(type default)
		)
		(layer "In6.Cu")
	)
	(gr_line
		(start 28.376372 -441.830968)
		(end 28.373832 -441.830968)
		(stroke
			(width 0.2)
			(type default)
		)
		(layer "In6.Cu")
	)
	(gr_line
		(start 28.399232 -442.846968)
		(end 28.401772 -442.846968)
		(stroke
			(width 0.2)
			(type default)
		)
		(layer "In6.Cu")
	)
	(gr_line
		(start 28.401772 -442.846968)
		(end 28.376372 -441.830968)
		(stroke
			(width 0.2)
			(type default)
		)
		(layer "In6.Cu")
	)
	(gr_arc
		(start 28.896564 -33.0327)
		(mid 29.432504 -33.56864)
		(end 29.968444 -33.0327)
		(stroke
			(width 0.2)
			(type default)
		)
		(layer "In6.Cu")
	)
	(gr_line
		(start 28.896564 -31.997142)
		(end 28.896564 -33.0327)
		(stroke
			(width 0.2)
			(type default)
		)
		(layer "In6.Cu")
	)
	(gr_arc
		(start 29.138626 -344.885518)
		(mid 28.463364 -344.403151)
		(end 27.980894 -345.078304)
		(stroke
			(width 0.2)
			(type default)
		)
		(layer "In6.Cu")
	)
	(gr_arc
		(start 29.23032 -363.213904)
		(mid 29.81706 -363.800644)
		(end 30.4038 -363.213904)
		(stroke
			(width 0.2)
			(type default)
		)
		(layer "In6.Cu")
	)
	(gr_line
		(start 29.23032 -362.255054)
		(end 29.23032 -363.213904)
		(stroke
			(width 0.2)
			(type default)
		)
		(layer "In6.Cu")
	)
	(gr_line
		(start 29.280612 -345.73718)
		(end 29.138626 -344.885518)
		(stroke
			(width 0.2)
			(type default)
		)
		(layer "In6.Cu")
	)
	(gr_line
		(start 29.41574 -342.431116)
		(end 29.41574 -341.503254)
		(stroke
			(width 0.2)
			(type default)
		)
		(layer "In6.Cu")
	)
	(gr_arc
		(start 29.41574 -341.503254)
		(mid 28.829127 -340.91626)
		(end 28.24226 -341.503)
		(stroke
			(width 0.2)
			(type default)
		)
		(layer "In6.Cu")
	)
	(gr_line
		(start 29.968444 -33.0327)
		(end 29.968444 -31.997396)
		(stroke
			(width 0.2)
			(type default)
		)
		(layer "In6.Cu")
	)
	(gr_arc
		(start 29.968444 -31.997396)
		(mid 29.432631 -31.461202)
		(end 28.896564 -31.997142)
		(stroke
			(width 0.2)
			(type default)
		)
		(layer "In6.Cu")
	)
	(gr_line
		(start 30.4038 -363.213904)
		(end 30.4038 -362.255308)
		(stroke
			(width 0.2)
			(type default)
		)
		(layer "In6.Cu")
	)
	(gr_arc
		(start 30.4038 -362.255308)
		(mid 29.817187 -361.668314)
		(end 29.23032 -362.255054)
		(stroke
			(width 0.2)
			(type default)
		)
		(layer "In6.Cu")
	)
	(gr_line
		(start 30.503368 -64.11595)
		(end 30.503622 -64.116204)
		(stroke
			(width 0.2)
			(type default)
		)
		(layer "In6.Cu")
	)
	(gr_line
		(start 30.503622 -64.116204)
		(end 30.505908 -64.116458)
		(stroke
			(width 0.2)
			(type default)
		)
		(layer "In6.Cu")
	)
	(gr_arc
		(start 30.505908 -64.116458)
		(mid 31.022544 -64.765682)
		(end 31.671768 -64.249046)
		(stroke
			(width 0.2)
			(type default)
		)
		(layer "In6.Cu")
	)
	(gr_line
		(start 30.605476 -63.217552)
		(end 30.503368 -64.11595)
		(stroke
			(width 0.2)
			(type default)
		)
		(layer "In6.Cu")
	)
	(gr_line
		(start 30.608016 -63.217806)
		(end 30.605476 -63.217552)
		(stroke
			(width 0.2)
			(type default)
		)
		(layer "In6.Cu")
	)
	(gr_line
		(start 30.753558 -475.23273)
		(end 30.804104 -476.09506)
		(stroke
			(width 0.2)
			(type default)
		)
		(layer "In6.Cu")
	)
	(gr_line
		(start 30.756098 -475.232476)
		(end 30.753558 -475.23273)
		(stroke
			(width 0.2)
			(type default)
		)
		(layer "In6.Cu")
	)
	(gr_line
		(start 30.804104 -476.09506)
		(end 30.806644 -476.094806)
		(stroke
			(width 0.2)
			(type default)
		)
		(layer "In6.Cu")
	)
	(gr_arc
		(start 30.806644 -476.094806)
		(mid 31.426658 -476.64624)
		(end 31.978092 -476.026226)
		(stroke
			(width 0.2)
			(type default)
		)
		(layer "In6.Cu")
	)
	(gr_arc
		(start 30.909006 -267.728446)
		(mid 31.495619 -268.31544)
		(end 32.082486 -267.7287)
		(stroke
			(width 0.2)
			(type default)
		)
		(layer "In6.Cu")
	)
	(gr_line
		(start 30.909006 -266.8651)
		(end 30.909006 -267.728446)
		(stroke
			(width 0.2)
			(type default)
		)
		(layer "In6.Cu")
	)
	(gr_line
		(start 30.912308 -372.184168)
		(end 31.034736 -373.248428)
		(stroke
			(width 0.2)
			(type default)
		)
		(layer "In6.Cu")
	)
	(gr_line
		(start 30.914848 -372.183914)
		(end 30.912308 -372.184168)
		(stroke
			(width 0.2)
			(type default)
		)
		(layer "In6.Cu")
	)
	(gr_arc
		(start 31.016702 -274.618958)
		(mid 31.603442 -275.205698)
		(end 32.190182 -274.618958)
		(stroke
			(width 0.2)
			(type default)
		)
		(layer "In6.Cu")
	)
	(gr_line
		(start 31.016702 -273.690842)
		(end 31.016702 -274.618958)
		(stroke
			(width 0.2)
			(type default)
		)
		(layer "In6.Cu")
	)
	(gr_line
		(start 31.034736 -373.248428)
		(end 31.03499 -373.248682)
		(stroke
			(width 0.2)
			(type default)
		)
		(layer "In6.Cu")
	)
	(gr_line
		(start 31.03499 -373.248682)
		(end 31.037276 -373.248428)
		(stroke
			(width 0.2)
			(type default)
		)
		(layer "In6.Cu")
	)
	(gr_arc
		(start 31.037276 -373.248428)
		(mid 31.630874 -373.719598)
		(end 32.102044 -373.126)
		(stroke
			(width 0.2)
			(type default)
		)
		(layer "In6.Cu")
	)
	(gr_arc
		(start 31.290006 -162.2933)
		(mid 31.876746 -162.88004)
		(end 32.463486 -162.2933)
		(stroke
			(width 0.2)
			(type default)
		)
		(layer "In6.Cu")
	)
	(gr_line
		(start 31.290006 -161.4297)
		(end 31.290006 -162.2933)
		(stroke
			(width 0.2)
			(type default)
		)
		(layer "In6.Cu")
	)
	(gr_line
		(start 31.671768 -64.249046)
		(end 31.674308 -64.2493)
		(stroke
			(width 0.2)
			(type default)
		)
		(layer "In6.Cu")
	)
	(gr_line
		(start 31.674308 -64.2493)
		(end 31.776416 -63.350648)
		(stroke
			(width 0.2)
			(type default)
		)
		(layer "In6.Cu")
	)
	(gr_arc
		(start 31.773876 -63.350394)
		(mid 31.25724 -62.70117)
		(end 30.608016 -63.217806)
		(stroke
			(width 0.2)
			(type default)
		)
		(layer "In6.Cu")
	)
	(gr_line
		(start 31.776416 -63.350648)
		(end 31.773876 -63.350394)
		(stroke
			(width 0.2)
			(type default)
		)
		(layer "In6.Cu")
	)
	(gr_arc
		(start 31.927546 -475.163896)
		(mid 31.307532 -474.612462)
		(end 30.756098 -475.232476)
		(stroke
			(width 0.2)
			(type default)
		)
		(layer "In6.Cu")
	)
	(gr_line
		(start 31.929832 -475.163642)
		(end 31.927546 -475.163896)
		(stroke
			(width 0.2)
			(type default)
		)
		(layer "In6.Cu")
	)
	(gr_line
		(start 31.930086 -475.163896)
		(end 31.929832 -475.163642)
		(stroke
			(width 0.2)
			(type default)
		)
		(layer "In6.Cu")
	)
	(gr_line
		(start 31.978092 -476.026226)
		(end 31.980632 -476.025972)
		(stroke
			(width 0.2)
			(type default)
		)
		(layer "In6.Cu")
	)
	(gr_arc
		(start 31.979616 -372.061486)
		(mid 31.386018 -371.590316)
		(end 30.914848 -372.183914)
		(stroke
			(width 0.2)
			(type default)
		)
		(layer "In6.Cu")
	)
	(gr_line
		(start 31.980632 -476.025972)
		(end 31.930086 -475.163896)
		(stroke
			(width 0.2)
			(type default)
		)
		(layer "In6.Cu")
	)
	(gr_line
		(start 31.982156 -372.061232)
		(end 31.979616 -372.061486)
		(stroke
			(width 0.2)
			(type default)
		)
		(layer "In6.Cu")
	)
	(gr_line
		(start 32.082486 -267.7287)
		(end 32.082486 -266.8651)
		(stroke
			(width 0.2)
			(type default)
		)
		(layer "In6.Cu")
	)
	(gr_arc
		(start 32.082486 -266.8651)
		(mid 31.495746 -266.27836)
		(end 30.909006 -266.8651)
		(stroke
			(width 0.2)
			(type default)
		)
		(layer "In6.Cu")
	)
	(gr_line
		(start 32.102044 -373.126)
		(end 32.104584 -373.125746)
		(stroke
			(width 0.2)
			(type default)
		)
		(layer "In6.Cu")
	)
	(gr_line
		(start 32.104584 -373.125746)
		(end 31.982156 -372.061232)
		(stroke
			(width 0.2)
			(type default)
		)
		(layer "In6.Cu")
	)
	(gr_line
		(start 32.190182 -274.618958)
		(end 32.190182 -273.691096)
		(stroke
			(width 0.2)
			(type default)
		)
		(layer "In6.Cu")
	)
	(gr_arc
		(start 32.190182 -273.691096)
		(mid 31.603569 -273.104102)
		(end 31.016702 -273.690842)
		(stroke
			(width 0.2)
			(type default)
		)
		(layer "In6.Cu")
	)
	(gr_arc
		(start 32.361886 -163.402518)
		(mid 31.945616 -164.123487)
		(end 32.66948 -164.53485)
		(stroke
			(width 0.2)
			(type default)
		)
		(layer "In6.Cu")
	)
	(gr_line
		(start 32.463486 -162.2933)
		(end 32.463486 -161.429954)
		(stroke
			(width 0.2)
			(type default)
		)
		(layer "In6.Cu")
	)
	(gr_arc
		(start 32.463486 -161.429954)
		(mid 31.876873 -160.84296)
		(end 31.290006 -161.4297)
		(stroke
			(width 0.2)
			(type default)
		)
		(layer "In6.Cu")
	)
	(gr_line
		(start 32.66948 -164.53485)
		(end 33.533334 -164.29355)
		(stroke
			(width 0.2)
			(type default)
		)
		(layer "In6.Cu")
	)
	(gr_line
		(start 33.217866 -163.16325)
		(end 32.361886 -163.402518)
		(stroke
			(width 0.2)
			(type default)
		)
		(layer "In6.Cu")
	)
	(gr_arc
		(start 33.533334 -164.29355)
		(mid 33.94075 -163.570666)
		(end 33.217866 -163.16325)
		(stroke
			(width 0.2)
			(type default)
		)
		(layer "In6.Cu")
	)
	(gr_arc
		(start 34.332418 -274.618196)
		(mid 34.918396 -275.205698)
		(end 35.505898 -274.61972)
		(stroke
			(width 0.2)
			(type default)
		)
		(layer "In6.Cu")
	)
	(gr_line
		(start 34.333434 -273.698716)
		(end 34.332418 -274.618196)
		(stroke
			(width 0.2)
			(type default)
		)
		(layer "In6.Cu")
	)
	(gr_arc
		(start 34.465006 -473.748354)
		(mid 35.051746 -474.335094)
		(end 35.638486 -473.748354)
		(stroke
			(width 0.2)
			(type default)
		)
		(layer "In6.Cu")
	)
	(gr_line
		(start 34.465006 -472.820238)
		(end 34.465006 -473.748354)
		(stroke
			(width 0.2)
			(type default)
		)
		(layer "In6.Cu")
	)
	(gr_line
		(start 35.505898 -274.61972)
		(end 35.506914 -273.700494)
		(stroke
			(width 0.2)
			(type default)
		)
		(layer "In6.Cu")
	)
	(gr_arc
		(start 35.506914 -273.700494)
		(mid 34.921063 -273.112992)
		(end 34.333434 -273.698716)
		(stroke
			(width 0.2)
			(type default)
		)
		(layer "In6.Cu")
	)
	(gr_line
		(start 35.638486 -473.748354)
		(end 35.638486 -472.820492)
		(stroke
			(width 0.2)
			(type default)
		)
		(layer "In6.Cu")
	)
	(gr_arc
		(start 35.638486 -472.820492)
		(mid 35.051873 -472.233498)
		(end 34.465006 -472.820238)
		(stroke
			(width 0.2)
			(type default)
		)
		(layer "In6.Cu")
	)
	(gr_line
		(start 35.707574 -370.823998)
		(end 35.710114 -370.823998)
		(stroke
			(width 0.2)
			(type default)
		)
		(layer "In6.Cu")
	)
	(gr_arc
		(start 35.710114 -370.823998)
		(mid 36.280598 -371.426486)
		(end 36.883086 -370.856002)
		(stroke
			(width 0.2)
			(type default)
		)
		(layer "In6.Cu")
	)
	(gr_line
		(start 35.73272 -369.90274)
		(end 35.707574 -370.823998)
		(stroke
			(width 0.2)
			(type default)
		)
		(layer "In6.Cu")
	)
	(gr_line
		(start 35.73526 -369.90274)
		(end 35.73272 -369.90274)
		(stroke
			(width 0.2)
			(type default)
		)
		(layer "In6.Cu")
	)
	(gr_arc
		(start 36.049712 -164.879274)
		(mid 36.636452 -165.466014)
		(end 37.223192 -164.879274)
		(stroke
			(width 0.2)
			(type default)
		)
		(layer "In6.Cu")
	)
	(gr_line
		(start 36.049712 -163.920424)
		(end 36.049712 -164.879274)
		(stroke
			(width 0.2)
			(type default)
		)
		(layer "In6.Cu")
	)
	(gr_line
		(start 36.883086 -370.856002)
		(end 36.885626 -370.856002)
		(stroke
			(width 0.2)
			(type default)
		)
		(layer "In6.Cu")
	)
	(gr_line
		(start 36.885626 -370.856002)
		(end 36.910772 -369.934998)
		(stroke
			(width 0.2)
			(type default)
		)
		(layer "In6.Cu")
	)
	(gr_arc
		(start 36.908232 -369.934744)
		(mid 36.337748 -369.332256)
		(end 35.73526 -369.90274)
		(stroke
			(width 0.2)
			(type default)
		)
		(layer "In6.Cu")
	)
	(gr_line
		(start 36.910518 -369.934744)
		(end 36.908232 -369.934744)
		(stroke
			(width 0.2)
			(type default)
		)
		(layer "In6.Cu")
	)
	(gr_line
		(start 36.910772 -369.934998)
		(end 36.910518 -369.934744)
		(stroke
			(width 0.2)
			(type default)
		)
		(layer "In6.Cu")
	)
	(gr_line
		(start 37.223192 -164.879274)
		(end 37.223192 -163.920678)
		(stroke
			(width 0.2)
			(type default)
		)
		(layer "In6.Cu")
	)
	(gr_arc
		(start 37.223192 -163.920678)
		(mid 36.636579 -163.333684)
		(end 36.049712 -163.920424)
		(stroke
			(width 0.2)
			(type default)
		)
		(layer "In6.Cu")
	)
	(gr_arc
		(start 37.513006 -61.850016)
		(mid 38.099746 -62.436756)
		(end 38.686486 -61.850016)
		(stroke
			(width 0.2)
			(type default)
		)
		(layer "In6.Cu")
	)
	(gr_line
		(start 37.513006 -60.891166)
		(end 37.513006 -61.850016)
		(stroke
			(width 0.2)
			(type default)
		)
		(layer "In6.Cu")
	)
	(gr_line
		(start 38.686486 -61.850016)
		(end 38.686486 -60.89142)
		(stroke
			(width 0.2)
			(type default)
		)
		(layer "In6.Cu")
	)
	(gr_arc
		(start 38.686486 -60.89142)
		(mid 38.099873 -60.304426)
		(end 37.513006 -60.891166)
		(stroke
			(width 0.2)
			(type default)
		)
		(layer "In6.Cu")
	)
	(gr_arc
		(start 215.1888 -269.032228)
		(mid 214.610442 -269.62735)
		(end 215.205564 -270.205708)
		(stroke
			(width 0.2)
			(type default)
		)
		(layer "In6.Cu")
	)
	(gr_line
		(start 215.205564 -270.205708)
		(end 216.11971 -270.192754)
		(stroke
			(width 0.2)
			(type default)
		)
		(layer "In6.Cu")
	)
	(gr_line
		(start 215.32342 -167.05072)
		(end 216.186766 -167.066468)
		(stroke
			(width 0.2)
			(type default)
		)
		(layer "In6.Cu")
	)
	(gr_arc
		(start 215.344756 -165.87724)
		(mid 214.747348 -166.453312)
		(end 215.32342 -167.05072)
		(stroke
			(width 0.2)
			(type default)
		)
		(layer "In6.Cu")
	)
	(gr_arc
		(start 215.349836 -62.92342)
		(mid 214.774524 -63.521463)
		(end 215.372442 -64.0969)
		(stroke
			(width 0.2)
			(type default)
		)
		(layer "In6.Cu")
	)
	(gr_line
		(start 215.372442 -64.0969)
		(end 216.236042 -64.080136)
		(stroke
			(width 0.2)
			(type default)
		)
		(layer "In6.Cu")
	)
	(gr_arc
		(start 215.608154 -371.879368)
		(mid 215.031064 -372.475633)
		(end 215.627204 -373.052848)
		(stroke
			(width 0.2)
			(type default)
		)
		(layer "In6.Cu")
	)
	(gr_line
		(start 215.627204 -373.052848)
		(end 216.490804 -373.038624)
		(stroke
			(width 0.2)
			(type default)
		)
		(layer "In6.Cu")
	)
	(gr_arc
		(start 215.92159 -474.661484)
		(mid 215.338406 -475.25178)
		(end 215.928702 -475.834964)
		(stroke
			(width 0.2)
			(type default)
		)
		(layer "In6.Cu")
	)
	(gr_line
		(start 215.928702 -475.834964)
		(end 216.792048 -475.829884)
		(stroke
			(width 0.2)
			(type default)
		)
		(layer "In6.Cu")
	)
	(gr_line
		(start 216.1032 -269.019274)
		(end 215.1888 -269.032228)
		(stroke
			(width 0.2)
			(type default)
		)
		(layer "In6.Cu")
	)
	(gr_arc
		(start 216.11971 -270.192754)
		(mid 216.69832 -269.597759)
		(end 216.1032 -269.019274)
		(stroke
			(width 0.2)
			(type default)
		)
		(layer "In6.Cu")
	)
	(gr_arc
		(start 216.186766 -167.066468)
		(mid 216.78443 -166.490523)
		(end 216.208356 -165.892988)
		(stroke
			(width 0.2)
			(type default)
		)
		(layer "In6.Cu")
	)
	(gr_line
		(start 216.208356 -165.892988)
		(end 215.344756 -165.87724)
		(stroke
			(width 0.2)
			(type default)
		)
		(layer "In6.Cu")
	)
	(gr_line
		(start 216.213182 -62.906656)
		(end 215.349836 -62.92342)
		(stroke
			(width 0.2)
			(type default)
		)
		(layer "In6.Cu")
	)
	(gr_arc
		(start 216.236042 -64.080136)
		(mid 216.811352 -63.481966)
		(end 216.213182 -62.906656)
		(stroke
			(width 0.2)
			(type default)
		)
		(layer "In6.Cu")
	)
	(gr_line
		(start 216.4715 -371.865144)
		(end 215.608154 -371.879368)
		(stroke
			(width 0.2)
			(type default)
		)
		(layer "In6.Cu")
	)
	(gr_arc
		(start 216.490804 -373.038624)
		(mid 217.067892 -372.442232)
		(end 216.4715 -371.865144)
		(stroke
			(width 0.2)
			(type default)
		)
		(layer "In6.Cu")
	)
	(gr_line
		(start 216.78519 -474.656404)
		(end 215.92159 -474.661484)
		(stroke
			(width 0.2)
			(type default)
		)
		(layer "In6.Cu")
	)
	(gr_arc
		(start 216.792048 -475.829884)
		(mid 217.375485 -475.239715)
		(end 216.78519 -474.656404)
		(stroke
			(width 0.2)
			(type default)
		)
		(layer "In6.Cu")
	)
	(gr_arc
		(start 219.609416 -473.86621)
		(mid 220.196156 -474.45295)
		(end 220.782896 -473.86621)
		(stroke
			(width 0.2)
			(type default)
		)
		(layer "In6.Cu")
	)
	(gr_line
		(start 219.609416 -472.90736)
		(end 219.609416 -473.86621)
		(stroke
			(width 0.2)
			(type default)
		)
		(layer "In6.Cu")
	)
	(gr_line
		(start 220.782896 -473.86621)
		(end 220.782896 -472.907614)
		(stroke
			(width 0.2)
			(type default)
		)
		(layer "In6.Cu")
	)
	(gr_arc
		(start 220.782896 -472.907614)
		(mid 220.196283 -472.32062)
		(end 219.609416 -472.90736)
		(stroke
			(width 0.2)
			(type default)
		)
		(layer "In6.Cu")
	)
	(gr_line
		(start 222.386398 -370.80444)
		(end 222.388938 -370.804694)
		(stroke
			(width 0.2)
			(type default)
		)
		(layer "In6.Cu")
	)
	(gr_arc
		(start 222.388938 -370.804694)
		(mid 222.941642 -371.423438)
		(end 223.560386 -370.870734)
		(stroke
			(width 0.2)
			(type default)
		)
		(layer "In6.Cu")
	)
	(gr_arc
		(start 222.417894 -267.792708)
		(mid 222.956374 -268.424152)
		(end 223.587818 -267.885672)
		(stroke
			(width 0.2)
			(type default)
		)
		(layer "In6.Cu")
	)
	(gr_line
		(start 222.437452 -369.905026)
		(end 222.386398 -370.80444)
		(stroke
			(width 0.2)
			(type default)
		)
		(layer "In6.Cu")
	)
	(gr_line
		(start 222.439992 -369.90528)
		(end 222.437452 -369.905026)
		(stroke
			(width 0.2)
			(type default)
		)
		(layer "In6.Cu")
	)
	(gr_arc
		(start 222.445072 -61.945012)
		(mid 223.031812 -62.531752)
		(end 223.618552 -61.945012)
		(stroke
			(width 0.2)
			(type default)
		)
		(layer "In6.Cu")
	)
	(gr_line
		(start 222.445072 -60.986162)
		(end 222.445072 -61.945012)
		(stroke
			(width 0.2)
			(type default)
		)
		(layer "In6.Cu")
	)
	(gr_line
		(start 222.48622 -266.931648)
		(end 222.417894 -267.792708)
		(stroke
			(width 0.2)
			(type default)
		)
		(layer "In6.Cu")
	)
	(gr_arc
		(start 222.576644 -164.934392)
		(mid 223.163384 -165.521132)
		(end 223.750124 -164.934392)
		(stroke
			(width 0.2)
			(type default)
		)
		(layer "In6.Cu")
	)
	(gr_line
		(start 222.576644 -163.975542)
		(end 222.576644 -164.934392)
		(stroke
			(width 0.2)
			(type default)
		)
		(layer "In6.Cu")
	)
	(gr_line
		(start 223.560386 -370.870734)
		(end 223.562926 -370.870988)
		(stroke
			(width 0.2)
			(type default)
		)
		(layer "In6.Cu")
	)
	(gr_line
		(start 223.562926 -370.870988)
		(end 223.61398 -369.971828)
		(stroke
			(width 0.2)
			(type default)
		)
		(layer "In6.Cu")
	)
	(gr_line
		(start 223.587818 -267.885672)
		(end 223.656144 -267.024866)
		(stroke
			(width 0.2)
			(type default)
		)
		(layer "In6.Cu")
	)
	(gr_arc
		(start 223.61144 -369.971574)
		(mid 223.058863 -369.352569)
		(end 222.439992 -369.90528)
		(stroke
			(width 0.2)
			(type default)
		)
		(layer "In6.Cu")
	)
	(gr_line
		(start 223.613726 -369.971574)
		(end 223.61144 -369.971574)
		(stroke
			(width 0.2)
			(type default)
		)
		(layer "In6.Cu")
	)
	(gr_line
		(start 223.61398 -369.971828)
		(end 223.613726 -369.971574)
		(stroke
			(width 0.2)
			(type default)
		)
		(layer "In6.Cu")
	)
	(gr_line
		(start 223.618552 -61.945012)
		(end 223.618552 -60.986416)
		(stroke
			(width 0.2)
			(type default)
		)
		(layer "In6.Cu")
	)
	(gr_arc
		(start 223.618552 -60.986416)
		(mid 223.031939 -60.399422)
		(end 222.445072 -60.986162)
		(stroke
			(width 0.2)
			(type default)
		)
		(layer "In6.Cu")
	)
	(gr_arc
		(start 223.656144 -267.024866)
		(mid 223.11779 -266.393432)
		(end 222.48622 -266.931648)
		(stroke
			(width 0.2)
			(type default)
		)
		(layer "In6.Cu")
	)
	(gr_line
		(start 223.750124 -164.934392)
		(end 223.750124 -163.975796)
		(stroke
			(width 0.2)
			(type default)
		)
		(layer "In6.Cu")
	)
	(gr_arc
		(start 223.750124 -163.975796)
		(mid 223.163511 -163.388802)
		(end 222.576644 -163.975542)
		(stroke
			(width 0.2)
			(type default)
		)
		(layer "In6.Cu")
	)
	(gr_line
		(start 0 -505.000006)
		(end 0 -461.449928)
		(stroke
			(width 0.05)
			(type default)
		)
		(layer "Edge.Cuts")
	)
	(gr_arc
		(start 0 -505.000006)
		(mid 0.292895 -505.707108)
		(end 0.999998 -506.000004)
		(stroke
			(width 0.05)
			(type default)
		)
		(layer "Edge.Cuts")
	)
	(gr_line
		(start 0 -461.449928)
		(end 0.500126 -460.950056)
		(stroke
			(width 0.05)
			(type default)
		)
		(layer "Edge.Cuts")
	)
	(gr_line
		(start 0 -458.55001)
		(end 0 -357.449882)
		(stroke
			(width 0.05)
			(type default)
		)
		(layer "Edge.Cuts")
	)
	(gr_line
		(start 0 -357.449882)
		(end 0.500126 -356.95001)
		(stroke
			(width 0.05)
			(type default)
		)
		(layer "Edge.Cuts")
	)
	(gr_line
		(start 0 -354.549964)
		(end 0 -306.649882)
		(stroke
			(width 0.05)
			(type default)
		)
		(layer "Edge.Cuts")
	)
	(gr_line
		(start 0 -306.649882)
		(end 0.500126 -306.15001)
		(stroke
			(width 0.05)
			(type default)
		)
		(layer "Edge.Cuts")
	)
	(gr_line
		(start 0 -303.749964)
		(end 0 -211.44992)
		(stroke
			(width 0.05)
			(type default)
		)
		(layer "Edge.Cuts")
	)
	(gr_line
		(start 0 -211.44992)
		(end 0.500126 -210.950048)
		(stroke
			(width 0.05)
			(type default)
		)
		(layer "Edge.Cuts")
	)
	(gr_line
		(start 0 -208.550002)
		(end 0 -107.449874)
		(stroke
			(width 0.05)
			(type default)
		)
		(layer "Edge.Cuts")
	)
	(gr_line
		(start 0 -107.449874)
		(end 0.500126 -106.950002)
		(stroke
			(width 0.05)
			(type default)
		)
		(layer "Edge.Cuts")
	)
	(gr_line
		(start 0 -104.549956)
		(end 0 -56.649874)
		(stroke
			(width 0.05)
			(type default)
		)
		(layer "Edge.Cuts")
	)
	(gr_line
		(start 0 -56.649874)
		(end 0.500126 -56.150002)
		(stroke
			(width 0.05)
			(type default)
		)
		(layer "Edge.Cuts")
	)
	(gr_line
		(start 0 -53.749956)
		(end 0 -0.999998)
		(stroke
			(width 0.05)
			(type default)
		)
		(layer "Edge.Cuts")
	)
	(gr_line
		(start 0.500126 -460.950056)
		(end 5.050028 -460.950056)
		(stroke
			(width 0.05)
			(type default)
		)
		(layer "Edge.Cuts")
	)
	(gr_line
		(start 0.500126 -459.049882)
		(end 0 -458.55001)
		(stroke
			(width 0.05)
			(type default)
		)
		(layer "Edge.Cuts")
	)
	(gr_line
		(start 0.500126 -356.95001)
		(end 5.050028 -356.95001)
		(stroke
			(width 0.05)
			(type default)
		)
		(layer "Edge.Cuts")
	)
	(gr_line
		(start 0.500126 -355.05009)
		(end 0 -354.549964)
		(stroke
			(width 0.05)
			(type default)
		)
		(layer "Edge.Cuts")
	)
	(gr_line
		(start 0.500126 -306.15001)
		(end 5.050028 -306.15001)
		(stroke
			(width 0.05)
			(type default)
		)
		(layer "Edge.Cuts")
	)
	(gr_line
		(start 0.500126 -304.25009)
		(end 0 -303.749964)
		(stroke
			(width 0.05)
			(type default)
		)
		(layer "Edge.Cuts")
	)
	(gr_line
		(start 0.500126 -210.950048)
		(end 5.050028 -210.950048)
		(stroke
			(width 0.05)
			(type default)
		)
		(layer "Edge.Cuts")
	)
	(gr_line
		(start 0.500126 -209.049874)
		(end 0 -208.550002)
		(stroke
			(width 0.05)
			(type default)
		)
		(layer "Edge.Cuts")
	)
	(gr_line
		(start 0.500126 -106.950002)
		(end 5.050028 -106.950002)
		(stroke
			(width 0.05)
			(type default)
		)
		(layer "Edge.Cuts")
	)
	(gr_line
		(start 0.500126 -105.050082)
		(end 0 -104.549956)
		(stroke
			(width 0.05)
			(type default)
		)
		(layer "Edge.Cuts")
	)
	(gr_line
		(start 0.500126 -56.150002)
		(end 5.050028 -56.150002)
		(stroke
			(width 0.05)
			(type default)
		)
		(layer "Edge.Cuts")
	)
	(gr_line
		(start 0.500126 -54.250082)
		(end 0 -53.749956)
		(stroke
			(width 0.05)
			(type default)
		)
		(layer "Edge.Cuts")
	)
	(gr_arc
		(start 0.999998 0)
		(mid 0.292893 -0.292893)
		(end 0 -0.999998)
		(stroke
			(width 0.05)
			(type default)
		)
		(layer "Edge.Cuts")
	)
	(gr_line
		(start 0.999998 0)
		(end 261.500112 0)
		(stroke
			(width 0.05)
			(type default)
		)
		(layer "Edge.Cuts")
	)
	(gr_arc
		(start 5.050028 -460.950056)
		(mid 5.999988 -460.000096)
		(end 5.050028 -459.049882)
		(stroke
			(width 0.05)
			(type default)
		)
		(layer "Edge.Cuts")
	)
	(gr_line
		(start 5.050028 -459.049882)
		(end 0.500126 -459.049882)
		(stroke
			(width 0.05)
			(type default)
		)
		(layer "Edge.Cuts")
	)
	(gr_arc
		(start 5.050028 -356.95001)
		(mid 5.999988 -356.00005)
		(end 5.050028 -355.05009)
		(stroke
			(width 0.05)
			(type default)
		)
		(layer "Edge.Cuts")
	)
	(gr_line
		(start 5.050028 -355.05009)
		(end 0.500126 -355.05009)
		(stroke
			(width 0.05)
			(type default)
		)
		(layer "Edge.Cuts")
	)
	(gr_arc
		(start 5.050028 -306.15001)
		(mid 5.999988 -305.20005)
		(end 5.050028 -304.25009)
		(stroke
			(width 0.05)
			(type default)
		)
		(layer "Edge.Cuts")
	)
	(gr_line
		(start 5.050028 -304.25009)
		(end 0.500126 -304.25009)
		(stroke
			(width 0.05)
			(type default)
		)
		(layer "Edge.Cuts")
	)
	(gr_arc
		(start 5.050028 -210.950048)
		(mid 5.999988 -210.000088)
		(end 5.050028 -209.049874)
		(stroke
			(width 0.05)
			(type default)
		)
		(layer "Edge.Cuts")
	)
	(gr_line
		(start 5.050028 -209.049874)
		(end 0.500126 -209.049874)
		(stroke
			(width 0.05)
			(type default)
		)
		(layer "Edge.Cuts")
	)
	(gr_arc
		(start 5.050028 -106.950002)
		(mid 5.999988 -106.000042)
		(end 5.050028 -105.050082)
		(stroke
			(width 0.05)
			(type default)
		)
		(layer "Edge.Cuts")
	)
	(gr_line
		(start 5.050028 -105.050082)
		(end 0.500126 -105.050082)
		(stroke
			(width 0.05)
			(type default)
		)
		(layer "Edge.Cuts")
	)
	(gr_arc
		(start 5.050028 -56.150002)
		(mid 5.999988 -55.200042)
		(end 5.050028 -54.250082)
		(stroke
			(width 0.05)
			(type default)
		)
		(layer "Edge.Cuts")
	)
	(gr_line
		(start 5.050028 -54.250082)
		(end 0.500126 -54.250082)
		(stroke
			(width 0.05)
			(type default)
		)
		(layer "Edge.Cuts")
	)
	(gr_line
		(start 251.394976 -410.485082)
		(end 257.899916 -410.485082)
		(stroke
			(width 0.05)
			(type default)
		)
		(layer "Edge.Cuts")
	)
	(gr_arc
		(start 251.394976 -409.41498)
		(mid 250.859798 -409.950158)
		(end 251.394976 -410.485082)
		(stroke
			(width 0.05)
			(type default)
		)
		(layer "Edge.Cuts")
	)
	(gr_line
		(start 257.899916 -410.485082)
		(end 258.899914 -411.48508)
		(stroke
			(width 0.05)
			(type default)
		)
		(layer "Edge.Cuts")
	)
	(gr_line
		(start 257.899916 -409.41498)
		(end 251.394976 -409.41498)
		(stroke
			(width 0.05)
			(type default)
		)
		(layer "Edge.Cuts")
	)
	(gr_arc
		(start 258.899914 -425.829984)
		(mid 259.266101 -426.713911)
		(end 260.150102 -427.079918)
		(stroke
			(width 0.05)
			(type default)
		)
		(layer "Edge.Cuts")
	)
	(gr_line
		(start 258.899914 -411.48508)
		(end 258.899914 -425.829984)
		(stroke
			(width 0.05)
			(type default)
		)
		(layer "Edge.Cuts")
	)
	(gr_line
		(start 258.899914 -408.414982)
		(end 257.899916 -409.41498)
		(stroke
			(width 0.05)
			(type default)
		)
		(layer "Edge.Cuts")
	)
	(gr_line
		(start 258.899914 -364.16996)
		(end 258.899914 -408.414982)
		(stroke
			(width 0.05)
			(type default)
		)
		(layer "Edge.Cuts")
	)
	(gr_line
		(start 260.150102 -427.079918)
		(end 261.500112 -427.079918)
		(stroke
			(width 0.05)
			(type default)
		)
		(layer "Edge.Cuts")
	)
	(gr_arc
		(start 260.150102 -362.920026)
		(mid 259.266101 -363.286033)
		(end 258.899914 -364.16996)
		(stroke
			(width 0.05)
			(type default)
		)
		(layer "Edge.Cuts")
	)
	(gr_line
		(start 261.500112 -506.000004)
		(end 0.999998 -506.000004)
		(stroke
			(width 0.05)
			(type default)
		)
		(layer "Edge.Cuts")
	)
	(gr_arc
		(start 261.500112 -506.000004)
		(mid 262.207212 -505.707107)
		(end 262.50011 -505.000006)
		(stroke
			(width 0.05)
			(type default)
		)
		(layer "Edge.Cuts")
	)
	(gr_line
		(start 261.500112 -427.079918)
		(end 262.50011 -428.079916)
		(stroke
			(width 0.05)
			(type default)
		)
		(layer "Edge.Cuts")
	)
	(gr_line
		(start 261.500112 -362.920026)
		(end 260.150102 -362.920026)
		(stroke
			(width 0.05)
			(type default)
		)
		(layer "Edge.Cuts")
	)
	(gr_line
		(start 262.50011 -428.079916)
		(end 262.50011 -505.000006)
		(stroke
			(width 0.05)
			(type default)
		)
		(layer "Edge.Cuts")
	)
	(gr_line
		(start 262.50011 -361.920028)
		(end 261.500112 -362.920026)
		(stroke
			(width 0.05)
			(type default)
		)
		(layer "Edge.Cuts")
	)
	(gr_arc
		(start 262.50011 -0.999998)
		(mid 262.207217 -0.29289)
		(end 261.500112 0)
		(stroke
			(width 0.05)
			(type default)
		)
		(layer "Edge.Cuts")
	)
	(gr_line
		(start 262.50011 -0.999998)
		(end 262.50011 -361.920028)
		(stroke
			(width 0.05)
			(type default)
		)
		(layer "Edge.Cuts")
	)
	(segment
		(start 3.19024 -216.504774)
		(end 5.811774 -216.504774)
		(width 0.508)
		(layer "F.Cu")
		(net "PCIE_MATED#_B")
	)
	(segment
		(start 6.985 -229.2985)
		(end 6.985 -228.092)
		(width 0.508)
		(layer "F.Cu")
		(net "PCIE_MATED#_B")
	)
	(segment
		(start 5.811774 -216.504774)
		(end 6.096 -216.789)
		(width 0.508)
		(layer "F.Cu")
		(net "PCIE_MATED#_B")
	)
	(segment
		(start 6.985 -228.092)
		(end 7.366 -227.711)
		(width 0.508)
		(layer "F.Cu")
		(net "PCIE_MATED#_B")
	)
	(via
		(at 11.0744 -224.4598)
		(size 0.7112)
		(drill 0.3556)
		(layers "F.Cu" "B.Cu")
		(net "PCIE_MATED#_B")
	)
	(via
		(at 6.096 -216.789)
		(size 0.5588)
		(drill 0.3048)
		(layers "F.Cu" "B.Cu")
		(net "PCIE_MATED#_B")
	)
	(via
		(at 7.366 -227.711)
		(size 0.5588)
		(drill 0.3048)
		(layers "F.Cu" "B.Cu")
		(net "PCIE_MATED#_B")
	)
	(segment
		(start 11.0744 -221.6404)
		(end 11.0744 -224.4598)
		(width 0.508)
		(layer "B.Cu")
		(net "PCIE_MATED#_B")
	)
	(segment
		(start 11.0744 -224.4598)
		(end 11.0744 -225.171)
		(width 0.508)
		(layer "B.Cu")
		(net "PCIE_MATED#_B")
	)
	(segment
		(start 6.223 -216.789)
		(end 11.0744 -221.6404)
		(width 0.508)
		(layer "B.Cu")
		(net "PCIE_MATED#_B")
	)
	(segment
		(start 11.0744 -225.171)
		(end 8.5344 -227.711)
		(width 0.508)
		(layer "B.Cu")
		(net "PCIE_MATED#_B")
	)
	(segment
		(start 6.096 -216.789)
		(end 6.223 -216.789)
		(width 0.508)
		(layer "B.Cu")
		(net "PCIE_MATED#_B")
	)
	(segment
		(start 8.5344 -227.711)
		(end 7.366 -227.711)
		(width 0.508)
		(layer "B.Cu")
		(net "PCIE_MATED#_B")
	)
	(segment
		(start 10.8204 -473.7354)
		(end 10.287 -473.202)
		(width 0.508)
		(layer "F.Cu")
		(net "PCIE_MATED#_A")
	)
	(segment
		(start 10.8204 -474.3577)
		(end 10.8204 -473.7354)
		(width 0.508)
		(layer "F.Cu")
		(net "PCIE_MATED#_A")
	)
	(segment
		(start 3.19024 -466.504782)
		(end 5.681218 -466.504782)
		(width 0.508)
		(layer "F.Cu")
		(net "PCIE_MATED#_A")
	)
	(via
		(at 11.6586 -473.1766)
		(size 0.7112)
		(drill 0.3556)
		(layers "F.Cu" "B.Cu")
		(net "PCIE_MATED#_A")
	)
	(via
		(at 10.287 -473.202)
		(size 0.5588)
		(drill 0.3048)
		(layers "F.Cu" "B.Cu")
		(net "PCIE_MATED#_A")
	)
	(via
		(at 5.681218 -466.504782)
		(size 0.5588)
		(drill 0.3048)
		(layers "F.Cu" "B.Cu")
		(net "PCIE_MATED#_A")
	)
	(segment
		(start 10.541 -473.202)
		(end 11.6586 -473.1766)
		(width 0.508)
		(layer "B.Cu")
		(net "PCIE_MATED#_A")
	)
	(segment
		(start 10.287 -473.202)
		(end 10.541 -473.202)
		(width 0.508)
		(layer "B.Cu")
		(net "PCIE_MATED#_A")
	)
	(segment
		(start 5.681218 -469.19642)
		(end 5.681218 -466.504782)
		(width 0.508)
		(layer "In5.Cu")
		(net "PCIE_MATED#_A")
	)
	(segment
		(start 9.686798 -473.202)
		(end 5.681218 -469.19642)
		(width 0.508)
		(layer "In5.Cu")
		(net "PCIE_MATED#_A")
	)
	(segment
		(start 10.287 -473.202)
		(end 9.686798 -473.202)
		(width 0.508)
		(layer "In5.Cu")
		(net "PCIE_MATED#_A")
	)
	(segment
		(start 9.80313 -489.2167)
		(end 10.15746 -489.57103)
		(width 0.254)
		(layer "F.Cu")
		(net "P5VC_ROVP")
	)
	(segment
		(start 10.743946 -491.583472)
		(end 10.743946 -490.157516)
		(width 0.254)
		(layer "F.Cu")
		(net "P5VC_ROVP")
	)
	(segment
		(start 5.84962 -489.886752)
		(end 6.86562 -489.886752)
		(width 0.508)
		(layer "F.Cu")
		(net "P5VC_ROVP")
	)
	(segment
		(start 10.743946 -490.157516)
		(end 10.15746 -489.57103)
		(width 0.254)
		(layer "F.Cu")
		(net "P5VC_ROVP")
	)
	(segment
		(start 7.1501 -489.683552)
		(end 7.616952 -489.2167)
		(width 0.254)
		(layer "F.Cu")
		(net "P5VC_ROVP")
	)
	(segment
		(start 10.769346 -491.608872)
		(end 10.743946 -491.583472)
		(width 0.254)
		(layer "F.Cu")
		(net "P5VC_ROVP")
	)
	(segment
		(start 10.769346 -492.015526)
		(end 10.769346 -491.608872)
		(width 0.254)
		(layer "F.Cu")
		(net "P5VC_ROVP")
	)
	(segment
		(start 7.06882 -489.683552)
		(end 7.1501 -489.683552)
		(width 0.254)
		(layer "F.Cu")
		(net "P5VC_ROVP")
	)
	(segment
		(start 7.616952 -489.2167)
		(end 9.80313 -489.2167)
		(width 0.254)
		(layer "F.Cu")
		(net "P5VC_ROVP")
	)
	(segment
		(start 6.86562 -489.886752)
		(end 7.06882 -489.683552)
		(width 0.254)
		(layer "F.Cu")
		(net "P5VC_ROVP")
	)
	(via
		(at 10.15746 -489.57103)
		(size 0.7112)
		(drill 0.3556)
		(layers "F.Cu" "B.Cu")
		(net "P5VC_ROVP")
	)
	(segment
		(start 51.062382 -18.922238)
		(end 48.640746 -18.922238)
		(width 0.254)
		(layer "F.Cu")
		(net "P5VB_ROVP")
	)
	(segment
		(start 48.640746 -19.3167)
		(end 48.640746 -18.922238)
		(width 0.254)
		(layer "F.Cu")
		(net "P5VB_ROVP")
	)
	(segment
		(start 46.462188 -21.989288)
		(end 47.751746 -20.69973)
		(width 0.254)
		(layer "F.Cu")
		(net "P5VB_ROVP")
	)
	(segment
		(start 46.462188 -23.005288)
		(end 46.462188 -21.989288)
		(width 0.508)
		(layer "F.Cu")
		(net "P5VB_ROVP")
	)
	(segment
		(start 47.751746 -20.2057)
		(end 48.640746 -19.3167)
		(width 0.254)
		(layer "F.Cu")
		(net "P5VB_ROVP")
	)
	(segment
		(start 47.751746 -20.69973)
		(end 47.751746 -20.2057)
		(width 0.254)
		(layer "F.Cu")
		(net "P5VB_ROVP")
	)
	(via
		(at 48.640746 -18.922238)
		(size 0.7112)
		(drill 0.3556)
		(layers "F.Cu" "B.Cu")
		(net "P5VB_ROVP")
	)
	(segment
		(start 230.631746 -23.5077)
		(end 231.749346 -22.3901)
		(width 0.254)
		(layer "F.Cu")
		(net "P5VA_ROVP")
	)
	(segment
		(start 230.060246 -26.1747)
		(end 230.631746 -25.6032)
		(width 0.254)
		(layer "F.Cu")
		(net "P5VA_ROVP")
	)
	(segment
		(start 230.631746 -25.6032)
		(end 230.631746 -23.5077)
		(width 0.254)
		(layer "F.Cu")
		(net "P5VA_ROVP")
	)
	(segment
		(start 230.060246 -27.1907)
		(end 230.060246 -26.1747)
		(width 0.508)
		(layer "F.Cu")
		(net "P5VA_ROVP")
	)
	(segment
		(start 231.90962 -22.229826)
		(end 231.749346 -22.3901)
		(width 0.254)
		(layer "F.Cu")
		(net "P5VA_ROVP")
	)
	(segment
		(start 233.389424 -22.229826)
		(end 231.90962 -22.229826)
		(width 0.254)
		(layer "F.Cu")
		(net "P5VA_ROVP")
	)
	(via
		(at 231.749346 -22.3901)
		(size 0.7112)
		(drill 0.3556)
		(layers "F.Cu" "B.Cu")
		(net "P5VA_ROVP")
	)
	(segment
		(start 7.112 -25.9715)
		(end 4.0005 -25.9715)
		(width 0.508)
		(layer "F.Cu")
		(net "PRSNT_B")
	)
	(via
		(at 6.096 -29.591)
		(size 0.7112)
		(drill 0.3556)
		(layers "F.Cu" "B.Cu")
		(net "PRSNT_B")
	)
	(via
		(at 4.0005 -25.9715)
		(size 0.5588)
		(drill 0.3048)
		(layers "F.Cu" "B.Cu")
		(net "PRSNT_B")
	)
	(segment
		(start 5.31749 -43.70451)
		(end 2.80924 -43.70451)
		(width 0.508)
		(layer "B.Cu")
		(net "PRSNT_B")
	)
	(segment
		(start 6.096 -28.067)
		(end 6.096 -29.591)
		(width 0.508)
		(layer "B.Cu")
		(net "PRSNT_B")
	)
	(segment
		(start 4.0005 -25.9715)
		(end 6.096 -28.067)
		(width 0.508)
		(layer "B.Cu")
		(net "PRSNT_B")
	)
	(segment
		(start 6.096 -29.591)
		(end 6.096 -42.926)
		(width 0.508)
		(layer "B.Cu")
		(net "PRSNT_B")
	)
	(segment
		(start 6.096 -42.926)
		(end 5.31749 -43.70451)
		(width 0.508)
		(layer "B.Cu")
		(net "PRSNT_B")
	)
	(segment
		(start 4.699 -275.9075)
		(end 2.2225 -275.9075)
		(width 0.508)
		(layer "F.Cu")
		(net "PRSNT_A")
	)
	(via
		(at 3.7846 -275.8694)
		(size 0.7112)
		(drill 0.3556)
		(layers "F.Cu" "B.Cu")
		(net "PRSNT_A")
	)
	(via
		(at 5.541518 -293.704518)
		(size 0.5588)
		(drill 0.3048)
		(layers "F.Cu" "B.Cu")
		(net "PRSNT_A")
	)
	(via
		(at 2.2225 -275.9075)
		(size 0.5588)
		(drill 0.3048)
		(layers "F.Cu" "B.Cu")
		(net "PRSNT_A")
	)
	(segment
		(start 2.80924 -293.704518)
		(end 5.541518 -293.704518)
		(width 0.508)
		(layer "B.Cu")
		(net "PRSNT_A")
	)
	(segment
		(start 2.2606 -275.8694)
		(end 2.2225 -275.9075)
		(width 0.508)
		(layer "B.Cu")
		(net "PRSNT_A")
	)
	(segment
		(start 3.7846 -275.8694)
		(end 2.2606 -275.8694)
		(width 0.508)
		(layer "B.Cu")
		(net "PRSNT_A")
	)
	(segment
		(start 5.541518 -288.082482)
		(end 5.541518 -293.704518)
		(width 0.508)
		(layer "In5.Cu")
		(net "PRSNT_A")
	)
	(segment
		(start 2.2225 -275.9075)
		(end 6.0325 -275.9075)
		(width 0.508)
		(layer "In5.Cu")
		(net "PRSNT_A")
	)
	(segment
		(start 6.731 -276.606)
		(end 6.731 -286.893)
		(width 0.508)
		(layer "In5.Cu")
		(net "PRSNT_A")
	)
	(segment
		(start 6.0325 -275.9075)
		(end 6.731 -276.606)
		(width 0.508)
		(layer "In5.Cu")
		(net "PRSNT_A")
	)
	(segment
		(start 6.731 -286.893)
		(end 5.541518 -288.082482)
		(width 0.508)
		(layer "In5.Cu")
		(net "PRSNT_A")
	)
	(segment
		(start 193.060828 -497.381276)
		(end 193.539364 -496.902994)
		(width 0.111252)
		(layer "F.Cu")
		(net "SW_HDD0_R")
	)
	(segment
		(start 194.186556 -496.512342)
		(end 195.053458 -496.512342)
		(width 0.111252)
		(layer "F.Cu")
		(net "SW_HDD0_R")
	)
	(segment
		(start 192.3415 -500.5705)
		(end 192.3415 -499.11)
		(width 0.111252)
		(layer "F.Cu")
		(net "SW_HDD0_R")
	)
	(segment
		(start 192.3415 -498.094)
		(end 192.628774 -497.806726)
		(width 0.111252)
		(layer "F.Cu")
		(net "SW_HDD0_R")
	)
	(segment
		(start 196.1515 -495.427)
		(end 196.723 -495.427)
		(width 0.111252)
		(layer "F.Cu")
		(net "SW_HDD0_R")
	)
	(segment
		(start 192.3415 -499.11)
		(end 192.3415 -498.094)
		(width 0.111252)
		(layer "F.Cu")
		(net "SW_HDD0_R")
	)
	(segment
		(start 195.58 -495.9985)
		(end 196.1515 -495.427)
		(width 0.111252)
		(layer "F.Cu")
		(net "SW_HDD0_R")
	)
	(segment
		(start 195.053458 -496.512342)
		(end 195.5673 -495.9985)
		(width 0.111252)
		(layer "F.Cu")
		(net "SW_HDD0_R")
	)
	(segment
		(start 193.923158 -496.512342)
		(end 194.186556 -496.512342)
		(width 0.111252)
		(layer "F.Cu")
		(net "SW_HDD0_R")
	)
	(segment
		(start 195.5673 -495.9985)
		(end 195.58 -495.9985)
		(width 0.111252)
		(layer "F.Cu")
		(net "SW_HDD0_R")
	)
	(segment
		(start 193.539364 -496.896136)
		(end 193.923158 -496.512342)
		(width 0.111252)
		(layer "F.Cu")
		(net "SW_HDD0_R")
	)
	(segment
		(start 196.723 -495.427)
		(end 197.104 -495.046)
		(width 0.111252)
		(layer "F.Cu")
		(net "SW_HDD0_R")
	)
	(segment
		(start 192.628774 -497.806726)
		(end 192.635378 -497.806726)
		(width 0.111252)
		(layer "F.Cu")
		(net "SW_HDD0_R")
	)
	(segment
		(start 193.539364 -496.902994)
		(end 193.539364 -496.896136)
		(width 0.111252)
		(layer "F.Cu")
		(net "SW_HDD0_R")
	)
	(segment
		(start 192.635378 -497.806726)
		(end 193.060828 -497.381276)
		(width 0.111252)
		(layer "F.Cu")
		(net "SW_HDD0_R")
	)
	(segment
		(start 192.024 -500.888)
		(end 192.3415 -500.5705)
		(width 0.111252)
		(layer "F.Cu")
		(net "SW_HDD0_R")
	)
	(via
		(at 197.104 -495.046)
		(size 0.7112)
		(drill 0.3556)
		(layers "F.Cu" "B.Cu")
		(net "SW_HDD0_R")
	)
	(segment
		(start 95.3389 -10.7442)
		(end 95.9485 -10.1346)
		(width 0.111252)
		(layer "F.Cu")
		(net "SW_HDD14_R")
	)
	(segment
		(start 95.885 -12.446)
		(end 95.6945 -12.446)
		(width 0.111252)
		(layer "F.Cu")
		(net "SW_HDD14_R")
	)
	(segment
		(start 95.0595 -11.0236)
		(end 95.0595 -11.811)
		(width 0.111252)
		(layer "F.Cu")
		(net "SW_HDD14_R")
	)
	(segment
		(start 98.246946 -7.7724)
		(end 98.246946 -9.26846)
		(width 0.111252)
		(layer "F.Cu")
		(net "SW_HDD14_R")
	)
	(segment
		(start 95.0595 -12.1285)
		(end 93.726 -13.462)
		(width 0.111252)
		(layer "F.Cu")
		(net "SW_HDD14_R")
	)
	(segment
		(start 96.6724 -10.1346)
		(end 97.53854 -9.26846)
		(width 0.111252)
		(layer "F.Cu")
		(net "SW_HDD14_R")
	)
	(segment
		(start 97.53854 -9.26846)
		(end 98.246946 -9.26846)
		(width 0.111252)
		(layer "F.Cu")
		(net "SW_HDD14_R")
	)
	(segment
		(start 95.0595 -11.811)
		(end 95.0595 -12.1285)
		(width 0.111252)
		(layer "F.Cu")
		(net "SW_HDD14_R")
	)
	(segment
		(start 95.3389 -10.7442)
		(end 95.0595 -11.0236)
		(width 0.111252)
		(layer "F.Cu")
		(net "SW_HDD14_R")
	)
	(segment
		(start 95.6945 -12.446)
		(end 95.0595 -11.811)
		(width 0.111252)
		(layer "F.Cu")
		(net "SW_HDD14_R")
	)
	(segment
		(start 98.234246 -7.7597)
		(end 98.246946 -7.7724)
		(width 0.111252)
		(layer "F.Cu")
		(net "SW_HDD14_R")
	)
	(segment
		(start 95.9485 -10.1346)
		(end 96.6724 -10.1346)
		(width 0.111252)
		(layer "F.Cu")
		(net "SW_HDD14_R")
	)
	(via
		(at 95.885 -12.446)
		(size 0.7112)
		(drill 0.3556)
		(layers "F.Cu" "B.Cu")
		(net "SW_HDD14_R")
	)
	(segment
		(start 43.3197 -106.807)
		(end 43.2689 -106.7562)
		(width 0.111252)
		(layer "F.Cu")
		(net "SW_HDD13_R")
	)
	(segment
		(start 42.8498 -110.965488)
		(end 42.8498 -108.2167)
		(width 0.111252)
		(layer "F.Cu")
		(net "SW_HDD13_R")
	)
	(segment
		(start 43.2689 -107.7976)
		(end 43.2689 -107.7722)
		(width 0.111252)
		(layer "F.Cu")
		(net "SW_HDD13_R")
	)
	(segment
		(start 42.8498 -108.2167)
		(end 43.2689 -107.7976)
		(width 0.111252)
		(layer "F.Cu")
		(net "SW_HDD13_R")
	)
	(segment
		(start 44.831 -106.7435)
		(end 44.7675 -106.807)
		(width 0.111252)
		(layer "F.Cu")
		(net "SW_HDD13_R")
	)
	(segment
		(start 43.2689 -106.7562)
		(end 43.2689 -107.7722)
		(width 0.111252)
		(layer "F.Cu")
		(net "SW_HDD13_R")
	)
	(segment
		(start 42.519346 -111.295942)
		(end 42.8498 -110.965488)
		(width 0.111252)
		(layer "F.Cu")
		(net "SW_HDD13_R")
	)
	(segment
		(start 43.434 -105.283)
		(end 44.831 -105.283)
		(width 0.111252)
		(layer "F.Cu")
		(net "SW_HDD13_R")
	)
	(segment
		(start 44.7675 -106.807)
		(end 43.3197 -106.807)
		(width 0.111252)
		(layer "F.Cu")
		(net "SW_HDD13_R")
	)
	(segment
		(start 42.087546 -111.295942)
		(end 42.519346 -111.295942)
		(width 0.111252)
		(layer "F.Cu")
		(net "SW_HDD13_R")
	)
	(segment
		(start 44.831 -105.283)
		(end 44.831 -106.7435)
		(width 0.111252)
		(layer "F.Cu")
		(net "SW_HDD13_R")
	)
	(via
		(at 43.434 -105.283)
		(size 0.7112)
		(drill 0.3556)
		(layers "F.Cu" "B.Cu")
		(net "SW_HDD13_R")
	)
	(segment
		(start 48.878998 -212.514942)
		(end 48.056546 -212.514942)
		(width 0.111252)
		(layer "F.Cu")
		(net "SW_HDD12_R")
	)
	(segment
		(start 50.673 -208.059528)
		(end 50.5079 -208.224628)
		(width 0.111252)
		(layer "F.Cu")
		(net "SW_HDD12_R")
	)
	(segment
		(start 51.689 -208.0895)
		(end 51.638962 -208.039462)
		(width 0.111252)
		(layer "F.Cu")
		(net "SW_HDD12_R")
	)
	(segment
		(start 50.693066 -208.039462)
		(end 50.673 -208.059528)
		(width 0.111252)
		(layer "F.Cu")
		(net "SW_HDD12_R")
	)
	(segment
		(start 49.276 -212.11794)
		(end 48.878998 -212.514942)
		(width 0.111252)
		(layer "F.Cu")
		(net "SW_HDD12_R")
	)
	(segment
		(start 50.5079 -208.224628)
		(end 50.5079 -209.042)
		(width 0.111252)
		(layer "F.Cu")
		(net "SW_HDD12_R")
	)
	(segment
		(start 51.638962 -208.039462)
		(end 50.693066 -208.039462)
		(width 0.111252)
		(layer "F.Cu")
		(net "SW_HDD12_R")
	)
	(segment
		(start 50.5079 -209.042)
		(end 50.419 -209.042)
		(width 0.111252)
		(layer "F.Cu")
		(net "SW_HDD12_R")
	)
	(segment
		(start 50.419 -209.042)
		(end 49.276 -210.185)
		(width 0.111252)
		(layer "F.Cu")
		(net "SW_HDD12_R")
	)
	(segment
		(start 48.386746 -213.960202)
		(end 48.056546 -213.630002)
		(width 0.111252)
		(layer "F.Cu")
		(net "SW_HDD12_R")
	)
	(segment
		(start 48.056546 -213.630002)
		(end 48.056546 -212.514942)
		(width 0.111252)
		(layer "F.Cu")
		(net "SW_HDD12_R")
	)
	(segment
		(start 51.689 -206.375)
		(end 51.689 -208.0895)
		(width 0.111252)
		(layer "F.Cu")
		(net "SW_HDD12_R")
	)
	(segment
		(start 49.276 -210.185)
		(end 49.276 -212.11794)
		(width 0.111252)
		(layer "F.Cu")
		(net "SW_HDD12_R")
	)
	(via
		(at 50.673 -208.059528)
		(size 0.7112)
		(drill 0.3556)
		(layers "F.Cu" "B.Cu")
		(net "SW_HDD12_R")
	)
	(segment
		(start 34.2265 -304.2285)
		(end 34.2265 -305.308)
		(width 0.111252)
		(layer "F.Cu")
		(net "SW_HDD11_R")
	)
	(segment
		(start 34.2265 -305.308)
		(end 34.2265 -306.324)
		(width 0.111252)
		(layer "F.Cu")
		(net "SW_HDD11_R")
	)
	(segment
		(start 33.782 -303.784)
		(end 34.2265 -304.2285)
		(width 0.111252)
		(layer "F.Cu")
		(net "SW_HDD11_R")
	)
	(segment
		(start 34.2265 -306.324)
		(end 34.2265 -306.959)
		(width 0.111252)
		(layer "F.Cu")
		(net "SW_HDD11_R")
	)
	(segment
		(start 34.2265 -306.959)
		(end 34.6075 -307.34)
		(width 0.111252)
		(layer "F.Cu")
		(net "SW_HDD11_R")
	)
	(segment
		(start 34.163 -308.483)
		(end 34.163 -309.245)
		(width 0.111252)
		(layer "F.Cu")
		(net "SW_HDD11_R")
	)
	(segment
		(start 34.6075 -308.0385)
		(end 34.163 -308.483)
		(width 0.111252)
		(layer "F.Cu")
		(net "SW_HDD11_R")
	)
	(segment
		(start 32.258 -303.784)
		(end 33.782 -303.784)
		(width 0.111252)
		(layer "F.Cu")
		(net "SW_HDD11_R")
	)
	(segment
		(start 34.163 -309.245)
		(end 33.865058 -309.542942)
		(width 0.111252)
		(layer "F.Cu")
		(net "SW_HDD11_R")
	)
	(segment
		(start 33.865058 -309.542942)
		(end 33.197546 -309.542942)
		(width 0.111252)
		(layer "F.Cu")
		(net "SW_HDD11_R")
	)
	(segment
		(start 34.6075 -307.34)
		(end 34.6075 -308.0385)
		(width 0.111252)
		(layer "F.Cu")
		(net "SW_HDD11_R")
	)
	(via
		(at 32.258 -303.784)
		(size 0.7112)
		(drill 0.3556)
		(layers "F.Cu" "B.Cu")
		(net "SW_HDD11_R")
	)
	(segment
		(start 48.574198 -419.858698)
		(end 47.599346 -419.858698)
		(width 0.111252)
		(layer "F.Cu")
		(net "SW_HDD10_R")
	)
	(segment
		(start 49.2125 -420.497)
		(end 51.054 -420.497)
		(width 0.111252)
		(layer "F.Cu")
		(net "SW_HDD10_R")
	)
	(segment
		(start 48.9712 -420.2557)
		(end 48.574198 -419.858698)
		(width 0.111252)
		(layer "F.Cu")
		(net "SW_HDD10_R")
	)
	(segment
		(start 51.6255 -418.211)
		(end 51.3715 -417.957)
		(width 0.111252)
		(layer "F.Cu")
		(net "SW_HDD10_R")
	)
	(segment
		(start 51.054 -420.497)
		(end 51.6255 -419.9255)
		(width 0.111252)
		(layer "F.Cu")
		(net "SW_HDD10_R")
	)
	(segment
		(start 51.6255 -419.9255)
		(end 51.6255 -418.973)
		(width 0.111252)
		(layer "F.Cu")
		(net "SW_HDD10_R")
	)
	(segment
		(start 48.9712 -420.2557)
		(end 49.2125 -420.497)
		(width 0.111252)
		(layer "F.Cu")
		(net "SW_HDD10_R")
	)
	(segment
		(start 48.9712 -421.3352)
		(end 48.9712 -420.2557)
		(width 0.111252)
		(layer "F.Cu")
		(net "SW_HDD10_R")
	)
	(segment
		(start 51.6255 -418.973)
		(end 51.6255 -418.211)
		(width 0.111252)
		(layer "F.Cu")
		(net "SW_HDD10_R")
	)
	(via
		(at 48.9712 -421.3352)
		(size 0.7112)
		(drill 0.3556)
		(layers "F.Cu" "B.Cu")
		(net "SW_HDD10_R")
	)
	(segment
		(start 78.879446 -91.3765)
		(end 80.248506 -91.3765)
		(width 0.111252)
		(layer "F.Cu")
		(net "SW_HDD9_R")
	)
	(segment
		(start 80.248506 -91.3765)
		(end 80.248506 -92.509594)
		(width 0.111252)
		(layer "F.Cu")
		(net "SW_HDD9_R")
	)
	(segment
		(start 80.7085 -94.0435)
		(end 81.407 -94.742)
		(width 0.111252)
		(layer "F.Cu")
		(net "SW_HDD9_R")
	)
	(segment
		(start 78.803246 -91.4527)
		(end 78.879446 -91.3765)
		(width 0.111252)
		(layer "F.Cu")
		(net "SW_HDD9_R")
	)
	(segment
		(start 79.9973 -92.7608)
		(end 79.9973 -94.0308)
		(width 0.111252)
		(layer "F.Cu")
		(net "SW_HDD9_R")
	)
	(segment
		(start 82.804 -96.52)
		(end 82.804 -96.139)
		(width 0.111252)
		(layer "F.Cu")
		(net "SW_HDD9_R")
	)
	(segment
		(start 82.804 -96.139)
		(end 81.407 -94.742)
		(width 0.111252)
		(layer "F.Cu")
		(net "SW_HDD9_R")
	)
	(segment
		(start 79.9973 -94.0308)
		(end 80.01 -94.0435)
		(width 0.111252)
		(layer "F.Cu")
		(net "SW_HDD9_R")
	)
	(segment
		(start 80.248506 -92.509594)
		(end 79.9973 -92.7608)
		(width 0.111252)
		(layer "F.Cu")
		(net "SW_HDD9_R")
	)
	(segment
		(start 80.01 -94.0435)
		(end 80.7085 -94.0435)
		(width 0.111252)
		(layer "F.Cu")
		(net "SW_HDD9_R")
	)
	(via
		(at 81.407 -94.742)
		(size 0.7112)
		(drill 0.3556)
		(layers "F.Cu" "B.Cu")
		(net "SW_HDD9_R")
	)
	(segment
		(start 82.55 -199.517)
		(end 81.153 -199.517)
		(width 0.111252)
		(layer "F.Cu")
		(net "SW_HDD8_R")
	)
	(segment
		(start 81.153 -199.517)
		(end 80.2005 -198.5645)
		(width 0.111252)
		(layer "F.Cu")
		(net "SW_HDD8_R")
	)
	(segment
		(start 80.2005 -198.5645)
		(end 80.2005 -197.866)
		(width 0.111252)
		(layer "F.Cu")
		(net "SW_HDD8_R")
	)
	(segment
		(start 80.2005 -197.866)
		(end 80.2005 -196.1896)
		(width 0.111252)
		(layer "F.Cu")
		(net "SW_HDD8_R")
	)
	(segment
		(start 79.133446 -194.7545)
		(end 80.502506 -194.7545)
		(width 0.111252)
		(layer "F.Cu")
		(net "SW_HDD8_R")
	)
	(segment
		(start 79.057246 -194.8307)
		(end 79.133446 -194.7545)
		(width 0.111252)
		(layer "F.Cu")
		(net "SW_HDD8_R")
	)
	(segment
		(start 80.2513 -196.1388)
		(end 80.502506 -195.887594)
		(width 0.111252)
		(layer "F.Cu")
		(net "SW_HDD8_R")
	)
	(segment
		(start 80.502506 -195.887594)
		(end 80.502506 -194.7545)
		(width 0.111252)
		(layer "F.Cu")
		(net "SW_HDD8_R")
	)
	(segment
		(start 80.2005 -196.1896)
		(end 80.2513 -196.1388)
		(width 0.111252)
		(layer "F.Cu")
		(net "SW_HDD8_R")
	)
	(via
		(at 82.55 -199.517)
		(size 0.7112)
		(drill 0.3556)
		(layers "F.Cu" "B.Cu")
		(net "SW_HDD8_R")
	)
	(segment
		(start 29.9085 -288.163)
		(end 28.829 -288.163)
		(width 0.111252)
		(layer "F.Cu")
		(net "SW_HDD7_R")
	)
	(segment
		(start 30.226 -287.8455)
		(end 29.9085 -288.163)
		(width 0.111252)
		(layer "F.Cu")
		(net "SW_HDD7_R")
	)
	(segment
		(start 25.527 -282.3845)
		(end 25.527 -281.2415)
		(width 0.111252)
		(layer "F.Cu")
		(net "SW_HDD7_R")
	)
	(segment
		(start 25.407366 -287.909)
		(end 28.575 -287.909)
		(width 0.111252)
		(layer "F.Cu")
		(net "SW_HDD7_R")
	)
	(segment
		(start 25.68194 -281.08656)
		(end 26.949146 -281.08656)
		(width 0.111252)
		(layer "F.Cu")
		(net "SW_HDD7_R")
	)
	(segment
		(start 24.13 -283.464)
		(end 24.8412 -284.1752)
		(width 0.111252)
		(layer "F.Cu")
		(net "SW_HDD7_R")
	)
	(segment
		(start 25.2095 -282.702)
		(end 24.13 -282.702)
		(width 0.111252)
		(layer "F.Cu")
		(net "SW_HDD7_R")
	)
	(segment
		(start 25.527 -282.3845)
		(end 25.2095 -282.702)
		(width 0.111252)
		(layer "F.Cu")
		(net "SW_HDD7_R")
	)
	(segment
		(start 24.8412 -284.1752)
		(end 24.8412 -287.342834)
		(width 0.111252)
		(layer "F.Cu")
		(net "SW_HDD7_R")
	)
	(segment
		(start 24.13 -282.702)
		(end 24.13 -283.464)
		(width 0.111252)
		(layer "F.Cu")
		(net "SW_HDD7_R")
	)
	(segment
		(start 24.8412 -287.342834)
		(end 25.407366 -287.909)
		(width 0.111252)
		(layer "F.Cu")
		(net "SW_HDD7_R")
	)
	(segment
		(start 28.575 -287.909)
		(end 28.829 -288.163)
		(width 0.111252)
		(layer "F.Cu")
		(net "SW_HDD7_R")
	)
	(segment
		(start 25.527 -281.2415)
		(end 25.68194 -281.08656)
		(width 0.111252)
		(layer "F.Cu")
		(net "SW_HDD7_R")
	)
	(via
		(at 28.829 -288.163)
		(size 0.7112)
		(drill 0.3556)
		(layers "F.Cu" "B.Cu")
		(net "SW_HDD7_R")
	)
	(segment
		(start 80.248506 -401.729194)
		(end 79.9973 -401.9804)
		(width 0.111252)
		(layer "F.Cu")
		(net "SW_HDD6_R")
	)
	(segment
		(start 80.3275 -404.8125)
		(end 81.153 -405.638)
		(width 0.111252)
		(layer "F.Cu")
		(net "SW_HDD6_R")
	)
	(segment
		(start 82.423 -405.638)
		(end 81.153 -405.638)
		(width 0.111252)
		(layer "F.Cu")
		(net "SW_HDD6_R")
	)
	(segment
		(start 80.3275 -404.114)
		(end 80.3275 -404.8125)
		(width 0.111252)
		(layer "F.Cu")
		(net "SW_HDD6_R")
	)
	(segment
		(start 80.248506 -400.6215)
		(end 80.248506 -401.729194)
		(width 0.111252)
		(layer "F.Cu")
		(net "SW_HDD6_R")
	)
	(segment
		(start 79.9465 -403.733)
		(end 80.3275 -404.114)
		(width 0.111252)
		(layer "F.Cu")
		(net "SW_HDD6_R")
	)
	(segment
		(start 79.9465 -402.0312)
		(end 79.9465 -403.098)
		(width 0.111252)
		(layer "F.Cu")
		(net "SW_HDD6_R")
	)
	(segment
		(start 79.9973 -401.9804)
		(end 79.9465 -402.0312)
		(width 0.111252)
		(layer "F.Cu")
		(net "SW_HDD6_R")
	)
	(segment
		(start 79.9465 -403.098)
		(end 79.9465 -403.733)
		(width 0.111252)
		(layer "F.Cu")
		(net "SW_HDD6_R")
	)
	(via
		(at 82.423 -405.638)
		(size 0.7112)
		(drill 0.3556)
		(layers "F.Cu" "B.Cu")
		(net "SW_HDD6_R")
	)
	(segment
		(start 81.376774 -498.759226)
		(end 81.04632 -499.08968)
		(width 0.111252)
		(layer "F.Cu")
		(net "SW_HDD5_R")
	)
	(segment
		(start 81.04632 -500.62638)
		(end 81.04632 -499.483888)
		(width 0.111252)
		(layer "F.Cu")
		(net "SW_HDD5_R")
	)
	(segment
		(start 80.0481 -500.8626)
		(end 80.8101 -500.8626)
		(width 0.111252)
		(layer "F.Cu")
		(net "SW_HDD5_R")
	)
	(segment
		(start 81.04632 -499.08968)
		(end 81.04632 -499.483888)
		(width 0.111252)
		(layer "F.Cu")
		(net "SW_HDD5_R")
	)
	(segment
		(start 79.629 -499.419372)
		(end 79.629 -500.4435)
		(width 0.111252)
		(layer "F.Cu")
		(net "SW_HDD5_R")
	)
	(segment
		(start 83.5406 -498.7544)
		(end 82.26552 -498.7544)
		(width 0.111252)
		(layer "F.Cu")
		(net "SW_HDD5_R")
	)
	(segment
		(start 79.635858 -499.412514)
		(end 79.629 -499.419372)
		(width 0.111252)
		(layer "F.Cu")
		(net "SW_HDD5_R")
	)
	(segment
		(start 83.82 -498.475)
		(end 85.344 -498.475)
		(width 0.111252)
		(layer "F.Cu")
		(net "SW_HDD5_R")
	)
	(segment
		(start 82.26552 -498.7544)
		(end 82.260694 -498.759226)
		(width 0.111252)
		(layer "F.Cu")
		(net "SW_HDD5_R")
	)
	(segment
		(start 83.82 -498.475)
		(end 83.5406 -498.7544)
		(width 0.111252)
		(layer "F.Cu")
		(net "SW_HDD5_R")
	)
	(segment
		(start 80.8101 -500.8626)
		(end 81.04632 -500.62638)
		(width 0.111252)
		(layer "F.Cu")
		(net "SW_HDD5_R")
	)
	(segment
		(start 82.260694 -498.759226)
		(end 81.376774 -498.759226)
		(width 0.111252)
		(layer "F.Cu")
		(net "SW_HDD5_R")
	)
	(segment
		(start 79.629 -500.4435)
		(end 80.0481 -500.8626)
		(width 0.111252)
		(layer "F.Cu")
		(net "SW_HDD5_R")
	)
	(via
		(at 83.82 -498.475)
		(size 0.7112)
		(drill 0.3556)
		(layers "F.Cu" "B.Cu")
		(net "SW_HDD5_R")
	)
	(segment
		(start 192.659 -89.281)
		(end 193.421 -88.519)
		(width 0.111252)
		(layer "F.Cu")
		(net "SW_HDD4_R")
	)
	(segment
		(start 195.961 -86.6775)
		(end 195.774564 -86.863936)
		(width 0.111252)
		(layer "F.Cu")
		(net "SW_HDD4_R")
	)
	(segment
		(start 194.609212 -86.863936)
		(end 194.609212 -87.330788)
		(width 0.111252)
		(layer "F.Cu")
		(net "SW_HDD4_R")
	)
	(segment
		(start 192.3415 -90.297)
		(end 192.3415 -89.281)
		(width 0.111252)
		(layer "F.Cu")
		(net "SW_HDD4_R")
	)
	(segment
		(start 191.262 -92.075)
		(end 192.3415 -90.9955)
		(width 0.111252)
		(layer "F.Cu")
		(net "SW_HDD4_R")
	)
	(segment
		(start 192.3415 -90.9955)
		(end 192.3415 -90.297)
		(width 0.111252)
		(layer "F.Cu")
		(net "SW_HDD4_R")
	)
	(segment
		(start 194.609212 -87.330788)
		(end 193.421 -88.519)
		(width 0.111252)
		(layer "F.Cu")
		(net "SW_HDD4_R")
	)
	(segment
		(start 195.774564 -86.863936)
		(end 194.609212 -86.863936)
		(width 0.111252)
		(layer "F.Cu")
		(net "SW_HDD4_R")
	)
	(segment
		(start 192.3415 -89.281)
		(end 192.659 -89.281)
		(width 0.111252)
		(layer "F.Cu")
		(net "SW_HDD4_R")
	)
	(via
		(at 193.421 -88.519)
		(size 0.7112)
		(drill 0.3556)
		(layers "F.Cu" "B.Cu")
		(net "SW_HDD4_R")
	)
	(segment
		(start 195.531232 -188.580268)
		(end 194.156584 -188.580268)
		(width 0.111252)
		(layer "F.Cu")
		(net "SW_HDD3_R")
	)
	(segment
		(start 195.58 -188.5315)
		(end 195.531232 -188.580268)
		(width 0.111252)
		(layer "F.Cu")
		(net "SW_HDD3_R")
	)
	(segment
		(start 192.5955 -191.77)
		(end 192.5955 -190.754)
		(width 0.111252)
		(layer "F.Cu")
		(net "SW_HDD3_R")
	)
	(segment
		(start 192.5955 -192.8495)
		(end 192.5955 -191.77)
		(width 0.111252)
		(layer "F.Cu")
		(net "SW_HDD3_R")
	)
	(segment
		(start 194.156584 -189.129416)
		(end 193.421 -189.865)
		(width 0.111252)
		(layer "F.Cu")
		(net "SW_HDD3_R")
	)
	(segment
		(start 192.5955 -190.754)
		(end 192.5955 -190.6905)
		(width 0.111252)
		(layer "F.Cu")
		(net "SW_HDD3_R")
	)
	(segment
		(start 192.024 -193.421)
		(end 192.5955 -192.8495)
		(width 0.111252)
		(layer "F.Cu")
		(net "SW_HDD3_R")
	)
	(segment
		(start 194.156584 -188.580268)
		(end 194.156584 -189.129416)
		(width 0.111252)
		(layer "F.Cu")
		(net "SW_HDD3_R")
	)
	(segment
		(start 192.5955 -190.6905)
		(end 193.421 -189.865)
		(width 0.111252)
		(layer "F.Cu")
		(net "SW_HDD3_R")
	)
	(via
		(at 193.421 -189.865)
		(size 0.7112)
		(drill 0.3556)
		(layers "F.Cu" "B.Cu")
		(net "SW_HDD3_R")
	)
	(segment
		(start 195.453 -290.8935)
		(end 195.10756 -291.23894)
		(width 0.111252)
		(layer "F.Cu")
		(net "SW_HDD2_R")
	)
	(segment
		(start 191.2366 -295.8592)
		(end 191.8335 -295.2623)
		(width 0.111252)
		(layer "F.Cu")
		(net "SW_HDD2_R")
	)
	(segment
		(start 191.8335 -294.259)
		(end 191.8335 -293.243)
		(width 0.111252)
		(layer "F.Cu")
		(net "SW_HDD2_R")
	)
	(segment
		(start 195.10756 -291.23894)
		(end 194.106546 -291.23894)
		(width 0.111252)
		(layer "F.Cu")
		(net "SW_HDD2_R")
	)
	(segment
		(start 191.8335 -293.243)
		(end 192.760092 -293.243)
		(width 0.111252)
		(layer "F.Cu")
		(net "SW_HDD2_R")
	)
	(segment
		(start 191.8335 -295.2623)
		(end 191.8335 -294.259)
		(width 0.111252)
		(layer "F.Cu")
		(net "SW_HDD2_R")
	)
	(segment
		(start 192.760092 -293.243)
		(end 193.547492 -292.4556)
		(width 0.111252)
		(layer "F.Cu")
		(net "SW_HDD2_R")
	)
	(segment
		(start 194.106546 -291.23894)
		(end 194.106546 -291.896546)
		(width 0.111252)
		(layer "F.Cu")
		(net "SW_HDD2_R")
	)
	(segment
		(start 194.106546 -291.896546)
		(end 193.547492 -292.4556)
		(width 0.111252)
		(layer "F.Cu")
		(net "SW_HDD2_R")
	)
	(via
		(at 193.547492 -292.4556)
		(size 0.7112)
		(drill 0.3556)
		(layers "F.Cu" "B.Cu")
		(net "SW_HDD2_R")
	)
	(segment
		(start 193.802 -394.432282)
		(end 194.697858 -393.536424)
		(width 0.111252)
		(layer "F.Cu")
		(net "SW_HDD1_R")
	)
	(segment
		(start 194.724782 -393.5095)
		(end 194.697858 -393.536424)
		(width 0.111252)
		(layer "F.Cu")
		(net "SW_HDD1_R")
	)
	(segment
		(start 192.7225 -396.494)
		(end 192.7225 -395.351)
		(width 0.111252)
		(layer "F.Cu")
		(net "SW_HDD1_R")
	)
	(segment
		(start 192.7225 -397.4465)
		(end 192.7225 -396.494)
		(width 0.111252)
		(layer "F.Cu")
		(net "SW_HDD1_R")
	)
	(segment
		(start 193.4464 -395.351)
		(end 193.802 -394.9954)
		(width 0.111252)
		(layer "F.Cu")
		(net "SW_HDD1_R")
	)
	(segment
		(start 192.7225 -395.351)
		(end 193.4464 -395.351)
		(width 0.111252)
		(layer "F.Cu")
		(net "SW_HDD1_R")
	)
	(segment
		(start 196.088 -393.5095)
		(end 194.724782 -393.5095)
		(width 0.111252)
		(layer "F.Cu")
		(net "SW_HDD1_R")
	)
	(segment
		(start 193.802 -394.9954)
		(end 193.802 -394.97)
		(width 0.111252)
		(layer "F.Cu")
		(net "SW_HDD1_R")
	)
	(segment
		(start 193.802 -394.97)
		(end 193.802 -394.432282)
		(width 0.111252)
		(layer "F.Cu")
		(net "SW_HDD1_R")
	)
	(segment
		(start 191.897 -398.272)
		(end 192.7225 -397.4465)
		(width 0.111252)
		(layer "F.Cu")
		(net "SW_HDD1_R")
	)
	(via
		(at 193.802 -394.97)
		(size 0.7112)
		(drill 0.3556)
		(layers "F.Cu" "B.Cu")
		(net "SW_HDD1_R")
	)
	(segment
		(start 22.1615 -396.113)
		(end 17.145 -396.113)
		(width 0.111252)
		(layer "F.Cu")
		(net "I2C_B_SDA_DAMP_A")
	)
	(segment
		(start 6.812788 -402.49602)
		(end 10.76198 -402.49602)
		(width 0.111252)
		(layer "F.Cu")
		(net "I2C_B_SDA_DAMP_A")
	)
	(segment
		(start 22.6695 -395.605)
		(end 22.1615 -396.113)
		(width 0.111252)
		(layer "F.Cu")
		(net "I2C_B_SDA_DAMP_A")
	)
	(segment
		(start 6.80847 -402.500338)
		(end 6.812788 -402.49602)
		(width 0.111252)
		(layer "F.Cu")
		(net "I2C_B_SDA_DAMP_A")
	)
	(segment
		(start 10.76198 -402.49602)
		(end 15.283688 -397.974312)
		(width 0.111252)
		(layer "F.Cu")
		(net "I2C_B_SDA_DAMP_A")
	)
	(segment
		(start 3.192526 -402.498814)
		(end 3.19405 -402.500338)
		(width 0.111252)
		(layer "F.Cu")
		(net "I2C_B_SDA_DAMP_A")
	)
	(segment
		(start 3.19405 -402.500338)
		(end 6.80847 -402.500338)
		(width 0.111252)
		(layer "F.Cu")
		(net "I2C_B_SDA_DAMP_A")
	)
	(segment
		(start 17.145 -396.113)
		(end 15.283688 -397.974312)
		(width 0.111252)
		(layer "F.Cu")
		(net "I2C_B_SDA_DAMP_A")
	)
	(via
		(at 15.283688 -397.974312)
		(size 0.7112)
		(drill 0.3556)
		(layers "F.Cu" "B.Cu")
		(net "I2C_B_SDA_DAMP_A")
	)
	(segment
		(start 22.6695 -394.589)
		(end 21.6281 -395.6304)
		(width 0.111252)
		(layer "F.Cu")
		(net "I2C_B_SCL_DAMP_A")
	)
	(segment
		(start 3.192526 -401.498816)
		(end 3.19405 -401.50034)
		(width 0.111252)
		(layer "F.Cu")
		(net "I2C_B_SCL_DAMP_A")
	)
	(segment
		(start 10.99566 -401.50034)
		(end 16.005556 -396.490444)
		(width 0.111252)
		(layer "F.Cu")
		(net "I2C_B_SCL_DAMP_A")
	)
	(segment
		(start 21.6281 -395.6304)
		(end 16.8656 -395.6304)
		(width 0.111252)
		(layer "F.Cu")
		(net "I2C_B_SCL_DAMP_A")
	)
	(segment
		(start 3.19405 -401.50034)
		(end 10.99566 -401.50034)
		(width 0.111252)
		(layer "F.Cu")
		(net "I2C_B_SCL_DAMP_A")
	)
	(segment
		(start 16.8656 -395.6304)
		(end 16.005556 -396.490444)
		(width 0.111252)
		(layer "F.Cu")
		(net "I2C_B_SCL_DAMP_A")
	)
	(via
		(at 16.005556 -396.490444)
		(size 0.7112)
		(drill 0.3556)
		(layers "F.Cu" "B.Cu")
		(net "I2C_B_SCL_DAMP_A")
	)
	(segment
		(start 21.082 -394.1445)
		(end 21.082 -394.951966)
		(width 0.111252)
		(layer "F.Cu")
		(net "I2C_D_SDA_DAMP_A")
	)
	(segment
		(start 21.082 -394.951966)
		(end 20.936966 -395.097)
		(width 0.111252)
		(layer "F.Cu")
		(net "I2C_D_SDA_DAMP_A")
	)
	(via
		(at 20.936966 -395.097)
		(size 0.5588)
		(drill 0.3048)
		(layers "F.Cu" "B.Cu")
		(net "I2C_D_SDA_DAMP_A")
	)
	(via
		(at 10.2108 -403.0472)
		(size 0.7112)
		(drill 0.3556)
		(layers "F.Cu" "B.Cu")
		(net "I2C_D_SDA_DAMP_A")
	)
	(segment
		(start 9.757664 -403.500336)
		(end 10.2108 -403.0472)
		(width 0.111252)
		(layer "B.Cu")
		(net "I2C_D_SDA_DAMP_A")
	)
	(segment
		(start 20.936966 -396.961614)
		(end 20.936966 -395.097)
		(width 0.111252)
		(layer "B.Cu")
		(net "I2C_D_SDA_DAMP_A")
	)
	(segment
		(start 20.209256 -402.021548)
		(end 21.876766 -400.354038)
		(width 0.111252)
		(layer "B.Cu")
		(net "I2C_D_SDA_DAMP_A")
	)
	(segment
		(start 21.876766 -400.354038)
		(end 21.876766 -397.901414)
		(width 0.111252)
		(layer "B.Cu")
		(net "I2C_D_SDA_DAMP_A")
	)
	(segment
		(start 11.185652 -402.072348)
		(end 18.5166 -402.072348)
		(width 0.111252)
		(layer "B.Cu")
		(net "I2C_D_SDA_DAMP_A")
	)
	(segment
		(start 10.2108 -403.0472)
		(end 11.185652 -402.072348)
		(width 0.111252)
		(layer "B.Cu")
		(net "I2C_D_SDA_DAMP_A")
	)
	(segment
		(start 2.811526 -403.498812)
		(end 2.81305 -403.500336)
		(width 0.111252)
		(layer "B.Cu")
		(net "I2C_D_SDA_DAMP_A")
	)
	(segment
		(start 2.81305 -403.500336)
		(end 9.757664 -403.500336)
		(width 0.111252)
		(layer "B.Cu")
		(net "I2C_D_SDA_DAMP_A")
	)
	(segment
		(start 18.5166 -402.072348)
		(end 18.5674 -402.021548)
		(width 0.111252)
		(layer "B.Cu")
		(net "I2C_D_SDA_DAMP_A")
	)
	(segment
		(start 18.5674 -402.021548)
		(end 20.209256 -402.021548)
		(width 0.111252)
		(layer "B.Cu")
		(net "I2C_D_SDA_DAMP_A")
	)
	(segment
		(start 21.876766 -397.901414)
		(end 20.936966 -396.961614)
		(width 0.111252)
		(layer "B.Cu")
		(net "I2C_D_SDA_DAMP_A")
	)
	(segment
		(start 20.066 -394.1445)
		(end 20.066 -395.097)
		(width 0.111252)
		(layer "F.Cu")
		(net "I2C_D_SCL_DAMP_A")
	)
	(via
		(at 9.441942 -402.100796)
		(size 0.7112)
		(drill 0.3556)
		(layers "F.Cu" "B.Cu")
		(net "I2C_D_SCL_DAMP_A")
	)
	(via
		(at 20.066 -395.097)
		(size 0.5588)
		(drill 0.3048)
		(layers "F.Cu" "B.Cu")
		(net "I2C_D_SCL_DAMP_A")
	)
	(segment
		(start 9.816338 -401.7264)
		(end 10.943082 -401.7264)
		(width 0.111252)
		(layer "B.Cu")
		(net "I2C_D_SCL_DAMP_A")
	)
	(segment
		(start 21.394166 -400.153886)
		(end 21.394166 -398.101566)
		(width 0.111252)
		(layer "B.Cu")
		(net "I2C_D_SCL_DAMP_A")
	)
	(segment
		(start 20.066 -395.24432)
		(end 20.066 -395.097)
		(width 0.111252)
		(layer "B.Cu")
		(net "I2C_D_SCL_DAMP_A")
	)
	(segment
		(start 18.221452 -401.656296)
		(end 18.3388 -401.538948)
		(width 0.111252)
		(layer "B.Cu")
		(net "I2C_D_SCL_DAMP_A")
	)
	(segment
		(start 20.454366 -395.632686)
		(end 20.066 -395.24432)
		(width 0.111252)
		(layer "B.Cu")
		(net "I2C_D_SCL_DAMP_A")
	)
	(segment
		(start 9.0424 -402.500338)
		(end 9.441942 -402.100796)
		(width 0.111252)
		(layer "B.Cu")
		(net "I2C_D_SCL_DAMP_A")
	)
	(segment
		(start 11.013186 -401.656296)
		(end 18.221452 -401.656296)
		(width 0.111252)
		(layer "B.Cu")
		(net "I2C_D_SCL_DAMP_A")
	)
	(segment
		(start 20.009104 -401.538948)
		(end 21.394166 -400.153886)
		(width 0.111252)
		(layer "B.Cu")
		(net "I2C_D_SCL_DAMP_A")
	)
	(segment
		(start 9.441942 -402.100796)
		(end 9.816338 -401.7264)
		(width 0.111252)
		(layer "B.Cu")
		(net "I2C_D_SCL_DAMP_A")
	)
	(segment
		(start 2.811526 -402.498814)
		(end 2.81305 -402.500338)
		(width 0.111252)
		(layer "B.Cu")
		(net "I2C_D_SCL_DAMP_A")
	)
	(segment
		(start 20.454366 -397.161766)
		(end 20.454366 -395.632686)
		(width 0.111252)
		(layer "B.Cu")
		(net "I2C_D_SCL_DAMP_A")
	)
	(segment
		(start 18.3388 -401.538948)
		(end 20.009104 -401.538948)
		(width 0.111252)
		(layer "B.Cu")
		(net "I2C_D_SCL_DAMP_A")
	)
	(segment
		(start 10.943082 -401.7264)
		(end 11.013186 -401.656296)
		(width 0.111252)
		(layer "B.Cu")
		(net "I2C_D_SCL_DAMP_A")
	)
	(segment
		(start 2.81305 -402.500338)
		(end 9.0424 -402.500338)
		(width 0.111252)
		(layer "B.Cu")
		(net "I2C_D_SCL_DAMP_A")
	)
	(segment
		(start 21.394166 -398.101566)
		(end 20.454366 -397.161766)
		(width 0.111252)
		(layer "B.Cu")
		(net "I2C_D_SCL_DAMP_A")
	)
	(segment
		(start 20.066 -398.4371)
		(end 20.776184 -398.4371)
		(width 0.111252)
		(layer "F.Cu")
		(net "I2C_C_SDA_DAMP_A")
	)
	(segment
		(start 20.776184 -398.4371)
		(end 20.911566 -398.301718)
		(width 0.111252)
		(layer "F.Cu")
		(net "I2C_C_SDA_DAMP_A")
	)
	(via
		(at 20.911566 -398.301718)
		(size 0.5588)
		(drill 0.3048)
		(layers "F.Cu" "B.Cu")
		(net "I2C_C_SDA_DAMP_A")
	)
	(via
		(at 15.4178 -401.056348)
		(size 0.7112)
		(drill 0.3556)
		(layers "F.Cu" "B.Cu")
		(net "I2C_C_SDA_DAMP_A")
	)
	(segment
		(start 19.808952 -401.056348)
		(end 15.4178 -401.056348)
		(width 0.111252)
		(layer "B.Cu")
		(net "I2C_C_SDA_DAMP_A")
	)
	(segment
		(start 20.911566 -399.953734)
		(end 19.808952 -401.056348)
		(width 0.111252)
		(layer "B.Cu")
		(net "I2C_C_SDA_DAMP_A")
	)
	(segment
		(start 5.28066 -401.50034)
		(end 5.724652 -401.056348)
		(width 0.111252)
		(layer "B.Cu")
		(net "I2C_C_SDA_DAMP_A")
	)
	(segment
		(start 20.911566 -398.301718)
		(end 20.911566 -399.953734)
		(width 0.111252)
		(layer "B.Cu")
		(net "I2C_C_SDA_DAMP_A")
	)
	(segment
		(start 2.81305 -401.50034)
		(end 5.28066 -401.50034)
		(width 0.111252)
		(layer "B.Cu")
		(net "I2C_C_SDA_DAMP_A")
	)
	(segment
		(start 5.724652 -401.056348)
		(end 15.4178 -401.056348)
		(width 0.111252)
		(layer "B.Cu")
		(net "I2C_C_SDA_DAMP_A")
	)
	(segment
		(start 2.811526 -401.498816)
		(end 2.81305 -401.50034)
		(width 0.111252)
		(layer "B.Cu")
		(net "I2C_C_SDA_DAMP_A")
	)
	(segment
		(start 19.05 -398.4371)
		(end 19.05 -398.59204)
		(width 0.111252)
		(layer "F.Cu")
		(net "I2C_C_SCL_DAMP_A")
	)
	(segment
		(start 19.05 -398.59204)
		(end 19.686524 -399.228564)
		(width 0.111252)
		(layer "F.Cu")
		(net "I2C_C_SCL_DAMP_A")
	)
	(segment
		(start 19.686524 -399.228564)
		(end 20.4216 -399.228564)
		(width 0.111252)
		(layer "F.Cu")
		(net "I2C_C_SCL_DAMP_A")
	)
	(via
		(at 20.4216 -399.228564)
		(size 0.5588)
		(drill 0.3048)
		(layers "F.Cu" "B.Cu")
		(net "I2C_C_SCL_DAMP_A")
	)
	(via
		(at 19.929348 -400.029172)
		(size 0.7112)
		(drill 0.3556)
		(layers "F.Cu" "B.Cu")
		(net "I2C_C_SCL_DAMP_A")
	)
	(segment
		(start 20.416266 -399.233898)
		(end 20.416266 -399.542254)
		(width 0.111252)
		(layer "B.Cu")
		(net "I2C_C_SCL_DAMP_A")
	)
	(segment
		(start 20.4216 -399.228564)
		(end 20.416266 -399.233898)
		(width 0.111252)
		(layer "B.Cu")
		(net "I2C_C_SCL_DAMP_A")
	)
	(segment
		(start 15.640812 -400.518122)
		(end 15.75689 -400.6342)
		(width 0.111252)
		(layer "B.Cu")
		(net "I2C_C_SCL_DAMP_A")
	)
	(segment
		(start 15.75689 -400.6342)
		(end 19.32432 -400.6342)
		(width 0.111252)
		(layer "B.Cu")
		(net "I2C_C_SCL_DAMP_A")
	)
	(segment
		(start 2.946908 -400.6342)
		(end 15.07871 -400.6342)
		(width 0.111252)
		(layer "B.Cu")
		(net "I2C_C_SCL_DAMP_A")
	)
	(segment
		(start 15.07871 -400.6342)
		(end 15.194788 -400.518122)
		(width 0.111252)
		(layer "B.Cu")
		(net "I2C_C_SCL_DAMP_A")
	)
	(segment
		(start 2.811526 -400.498818)
		(end 2.946908 -400.6342)
		(width 0.111252)
		(layer "B.Cu")
		(net "I2C_C_SCL_DAMP_A")
	)
	(segment
		(start 19.32432 -400.6342)
		(end 19.929348 -400.029172)
		(width 0.111252)
		(layer "B.Cu")
		(net "I2C_C_SCL_DAMP_A")
	)
	(segment
		(start 15.194788 -400.518122)
		(end 15.640812 -400.518122)
		(width 0.111252)
		(layer "B.Cu")
		(net "I2C_C_SCL_DAMP_A")
	)
	(segment
		(start 20.416266 -399.542254)
		(end 19.929348 -400.029172)
		(width 0.111252)
		(layer "B.Cu")
		(net "I2C_C_SCL_DAMP_A")
	)
	(segment
		(start 8.922004 -154.203908)
		(end 8.025892 -154.203908)
		(width 0.111252)
		(layer "F.Cu")
		(net "I2C_D_SDA_DAMP_B")
	)
	(segment
		(start 8.9789 -154.260804)
		(end 8.922004 -154.203908)
		(width 0.111252)
		(layer "F.Cu")
		(net "I2C_D_SDA_DAMP_B")
	)
	(via
		(at 8.025892 -154.203908)
		(size 0.5588)
		(drill 0.3048)
		(layers "F.Cu" "B.Cu")
		(net "I2C_D_SDA_DAMP_B")
	)
	(via
		(at 8.929878 -154.461718)
		(size 0.7112)
		(drill 0.3556)
		(layers "F.Cu" "B.Cu")
		(net "I2C_D_SDA_DAMP_B")
	)
	(segment
		(start 7.874508 -154.203908)
		(end 7.170928 -153.500328)
		(width 0.111252)
		(layer "B.Cu")
		(net "I2C_D_SDA_DAMP_B")
	)
	(segment
		(start 8.641588 -154.183588)
		(end 8.046212 -154.183588)
		(width 0.111252)
		(layer "B.Cu")
		(net "I2C_D_SDA_DAMP_B")
	)
	(segment
		(start 8.025892 -154.203908)
		(end 7.874508 -154.203908)
		(width 0.111252)
		(layer "B.Cu")
		(net "I2C_D_SDA_DAMP_B")
	)
	(segment
		(start 7.170928 -153.500328)
		(end 2.81305 -153.500328)
		(width 0.111252)
		(layer "B.Cu")
		(net "I2C_D_SDA_DAMP_B")
	)
	(segment
		(start 2.81305 -153.500328)
		(end 2.811526 -153.498804)
		(width 0.111252)
		(layer "B.Cu")
		(net "I2C_D_SDA_DAMP_B")
	)
	(segment
		(start 8.929878 -154.461718)
		(end 8.919718 -154.461718)
		(width 0.111252)
		(layer "B.Cu")
		(net "I2C_D_SDA_DAMP_B")
	)
	(segment
		(start 8.046212 -154.183588)
		(end 8.025892 -154.203908)
		(width 0.111252)
		(layer "B.Cu")
		(net "I2C_D_SDA_DAMP_B")
	)
	(segment
		(start 8.919718 -154.461718)
		(end 8.641588 -154.183588)
		(width 0.111252)
		(layer "B.Cu")
		(net "I2C_D_SDA_DAMP_B")
	)
	(segment
		(start 8.84936 -153.34234)
		(end 8.1788 -153.34234)
		(width 0.111252)
		(layer "F.Cu")
		(net "I2C_D_SCL_DAMP_B")
	)
	(segment
		(start 8.9789 -153.2128)
		(end 8.84936 -153.34234)
		(width 0.111252)
		(layer "F.Cu")
		(net "I2C_D_SCL_DAMP_B")
	)
	(via
		(at 9.084564 -153.091134)
		(size 0.7112)
		(drill 0.3556)
		(layers "F.Cu" "B.Cu")
		(net "I2C_D_SCL_DAMP_B")
	)
	(via
		(at 8.1788 -153.34234)
		(size 0.5588)
		(drill 0.3048)
		(layers "F.Cu" "B.Cu")
		(net "I2C_D_SCL_DAMP_B")
	)
	(segment
		(start 7.82574 -153.34234)
		(end 6.98373 -152.50033)
		(width 0.111252)
		(layer "B.Cu")
		(net "I2C_D_SCL_DAMP_B")
	)
	(segment
		(start 2.81305 -152.50033)
		(end 2.811526 -152.498806)
		(width 0.111252)
		(layer "B.Cu")
		(net "I2C_D_SCL_DAMP_B")
	)
	(segment
		(start 8.1788 -153.34234)
		(end 7.82574 -153.34234)
		(width 0.111252)
		(layer "B.Cu")
		(net "I2C_D_SCL_DAMP_B")
	)
	(segment
		(start 6.98373 -152.50033)
		(end 2.81305 -152.50033)
		(width 0.111252)
		(layer "B.Cu")
		(net "I2C_D_SCL_DAMP_B")
	)
	(segment
		(start 9.084564 -153.091134)
		(end 8.430006 -153.091134)
		(width 0.111252)
		(layer "B.Cu")
		(net "I2C_D_SCL_DAMP_B")
	)
	(segment
		(start 8.430006 -153.091134)
		(end 8.1788 -153.34234)
		(width 0.111252)
		(layer "B.Cu")
		(net "I2C_D_SCL_DAMP_B")
	)
	(segment
		(start 7.505954 -151.7396)
		(end 7.2898 -151.523446)
		(width 0.111252)
		(layer "F.Cu")
		(net "I2C_C_SDA_DAMP_B")
	)
	(segment
		(start 8.1407 -151.7396)
		(end 7.505954 -151.7396)
		(width 0.111252)
		(layer "F.Cu")
		(net "I2C_C_SDA_DAMP_B")
	)
	(via
		(at 8.2042 -151.8412)
		(size 0.7112)
		(drill 0.3556)
		(layers "F.Cu" "B.Cu")
		(net "I2C_C_SDA_DAMP_B")
	)
	(via
		(at 7.2898 -151.523446)
		(size 0.5588)
		(drill 0.3048)
		(layers "F.Cu" "B.Cu")
		(net "I2C_C_SDA_DAMP_B")
	)
	(segment
		(start 7.607554 -151.8412)
		(end 7.2898 -151.523446)
		(width 0.111252)
		(layer "B.Cu")
		(net "I2C_C_SDA_DAMP_B")
	)
	(segment
		(start 8.2042 -151.8412)
		(end 7.607554 -151.8412)
		(width 0.111252)
		(layer "B.Cu")
		(net "I2C_C_SDA_DAMP_B")
	)
	(segment
		(start 7.2898 -151.523446)
		(end 7.266686 -151.500332)
		(width 0.111252)
		(layer "B.Cu")
		(net "I2C_C_SDA_DAMP_B")
	)
	(segment
		(start 2.81305 -151.500332)
		(end 2.811526 -151.498808)
		(width 0.111252)
		(layer "B.Cu")
		(net "I2C_C_SDA_DAMP_B")
	)
	(segment
		(start 7.266686 -151.500332)
		(end 2.81305 -151.500332)
		(width 0.111252)
		(layer "B.Cu")
		(net "I2C_C_SDA_DAMP_B")
	)
	(segment
		(start 8.1407 -150.6982)
		(end 7.355332 -150.6982)
		(width 0.111252)
		(layer "F.Cu")
		(net "I2C_C_SCL_DAMP_B")
	)
	(segment
		(start 7.355332 -150.6982)
		(end 7.317232 -150.6601)
		(width 0.111252)
		(layer "F.Cu")
		(net "I2C_C_SCL_DAMP_B")
	)
	(via
		(at 8.25627 -150.618444)
		(size 0.7112)
		(drill 0.3556)
		(layers "F.Cu" "B.Cu")
		(net "I2C_C_SCL_DAMP_B")
	)
	(via
		(at 7.317232 -150.6601)
		(size 0.5588)
		(drill 0.3048)
		(layers "F.Cu" "B.Cu")
		(net "I2C_C_SCL_DAMP_B")
	)
	(segment
		(start 2.81305 -150.500334)
		(end 7.157466 -150.500334)
		(width 0.111252)
		(layer "B.Cu")
		(net "I2C_C_SCL_DAMP_B")
	)
	(segment
		(start 8.214614 -150.6601)
		(end 8.25627 -150.618444)
		(width 0.111252)
		(layer "B.Cu")
		(net "I2C_C_SCL_DAMP_B")
	)
	(segment
		(start 7.317232 -150.6601)
		(end 8.214614 -150.6601)
		(width 0.111252)
		(layer "B.Cu")
		(net "I2C_C_SCL_DAMP_B")
	)
	(segment
		(start 2.811526 -150.49881)
		(end 2.81305 -150.500334)
		(width 0.111252)
		(layer "B.Cu")
		(net "I2C_C_SCL_DAMP_B")
	)
	(segment
		(start 7.157466 -150.500334)
		(end 7.317232 -150.6601)
		(width 0.111252)
		(layer "B.Cu")
		(net "I2C_C_SCL_DAMP_B")
	)
	(segment
		(start 3.192526 -152.498806)
		(end 3.19405 -152.50033)
		(width 0.111252)
		(layer "F.Cu")
		(net "I2C_B_SDA_DAMP_B")
	)
	(segment
		(start 7.07263 -153.682192)
		(end 7.243826 -153.682192)
		(width 0.111252)
		(layer "F.Cu")
		(net "I2C_B_SDA_DAMP_B")
	)
	(segment
		(start 10.8966 -152.7429)
		(end 10.8839 -152.7302)
		(width 0.111252)
		(layer "F.Cu")
		(net "I2C_B_SDA_DAMP_B")
	)
	(segment
		(start 10.8839 -152.7302)
		(end 8.108188 -152.7302)
		(width 0.111252)
		(layer "F.Cu")
		(net "I2C_B_SDA_DAMP_B")
	)
	(segment
		(start 7.6962 -153.142188)
		(end 7.6962 -153.229818)
		(width 0.111252)
		(layer "F.Cu")
		(net "I2C_B_SDA_DAMP_B")
	)
	(segment
		(start 7.6962 -153.229818)
		(end 7.243826 -153.682192)
		(width 0.111252)
		(layer "F.Cu")
		(net "I2C_B_SDA_DAMP_B")
	)
	(segment
		(start 5.890768 -152.50033)
		(end 7.07263 -153.682192)
		(width 0.111252)
		(layer "F.Cu")
		(net "I2C_B_SDA_DAMP_B")
	)
	(segment
		(start 3.19405 -152.50033)
		(end 5.890768 -152.50033)
		(width 0.111252)
		(layer "F.Cu")
		(net "I2C_B_SDA_DAMP_B")
	)
	(segment
		(start 8.108188 -152.7302)
		(end 7.6962 -153.142188)
		(width 0.111252)
		(layer "F.Cu")
		(net "I2C_B_SDA_DAMP_B")
	)
	(via
		(at 7.243826 -153.682192)
		(size 0.7112)
		(drill 0.3556)
		(layers "F.Cu" "B.Cu")
		(net "I2C_B_SDA_DAMP_B")
	)
	(segment
		(start 10.0711 -151.7396)
		(end 9.5631 -152.2476)
		(width 0.111252)
		(layer "F.Cu")
		(net "I2C_B_SCL_DAMP_B")
	)
	(segment
		(start 7.908036 -152.2476)
		(end 7.692644 -152.462992)
		(width 0.111252)
		(layer "F.Cu")
		(net "I2C_B_SCL_DAMP_B")
	)
	(segment
		(start 3.19405 -151.500332)
		(end 6.298184 -151.500332)
		(width 0.111252)
		(layer "F.Cu")
		(net "I2C_B_SCL_DAMP_B")
	)
	(segment
		(start 7.692644 -152.462992)
		(end 7.260844 -152.462992)
		(width 0.111252)
		(layer "F.Cu")
		(net "I2C_B_SCL_DAMP_B")
	)
	(segment
		(start 6.298184 -151.500332)
		(end 7.260844 -152.462992)
		(width 0.111252)
		(layer "F.Cu")
		(net "I2C_B_SCL_DAMP_B")
	)
	(segment
		(start 9.5631 -152.2476)
		(end 7.908036 -152.2476)
		(width 0.111252)
		(layer "F.Cu")
		(net "I2C_B_SCL_DAMP_B")
	)
	(segment
		(start 3.192526 -151.498808)
		(end 3.19405 -151.500332)
		(width 0.111252)
		(layer "F.Cu")
		(net "I2C_B_SCL_DAMP_B")
	)
	(via
		(at 7.260844 -152.462992)
		(size 0.7112)
		(drill 0.3556)
		(layers "F.Cu" "B.Cu")
		(net "I2C_B_SCL_DAMP_B")
	)
	(segment
		(start 206.9338 -69.1642)
		(end 206.9338 -68.59524)
		(width 0.4064)
		(layer "F.Cu")
		(net "P3V3_HDD4_LED")
	)
	(segment
		(start 207.4418 -69.6722)
		(end 206.9338 -69.1642)
		(width 0.4064)
		(layer "F.Cu")
		(net "P3V3_HDD4_LED")
	)
	(segment
		(start 221.355412 -40.620696)
		(end 220.364304 -40.620696)
		(width 0.508)
		(layer "F.Cu")
		(net "P3V3_HDD4_LED")
	)
	(via
		(at 220.364304 -40.620696)
		(size 0.5588)
		(drill 0.3048)
		(layers "F.Cu" "B.Cu")
		(net "P3V3_HDD4_LED")
	)
	(via
		(at 207.4418 -69.6722)
		(size 0.5588)
		(drill 0.3048)
		(layers "F.Cu" "B.Cu")
		(net "P3V3_HDD4_LED")
	)
	(via
		(at 207.391 -68.7324)
		(size 0.7112)
		(drill 0.3556)
		(layers "F.Cu" "B.Cu")
		(net "P3V3_HDD4_LED")
	)
	(segment
		(start 207.391 -69.6214)
		(end 207.391 -68.7324)
		(width 0.508)
		(layer "B.Cu")
		(net "P3V3_HDD4_LED")
	)
	(segment
		(start 207.4418 -69.6722)
		(end 207.391 -69.6214)
		(width 0.508)
		(layer "B.Cu")
		(net "P3V3_HDD4_LED")
	)
	(segment
		(start 220.211396 -40.620696)
		(end 220.364304 -40.620696)
		(width 0.508)
		(layer "In2.Cu")
		(net "P3V3_HDD4_LED")
	)
	(segment
		(start 208.0006 -69.1134)
		(end 208.0006 -62.782196)
		(width 0.508)
		(layer "In2.Cu")
		(net "P3V3_HDD4_LED")
	)
	(segment
		(start 207.4418 -69.6722)
		(end 208.0006 -69.1134)
		(width 0.508)
		(layer "In2.Cu")
		(net "P3V3_HDD4_LED")
	)
	(segment
		(start 217.297 -43.535092)
		(end 220.211396 -40.620696)
		(width 0.508)
		(layer "In2.Cu")
		(net "P3V3_HDD4_LED")
	)
	(segment
		(start 208.0006 -62.782196)
		(end 217.297 -53.485796)
		(width 0.508)
		(layer "In2.Cu")
		(net "P3V3_HDD4_LED")
	)
	(segment
		(start 217.297 -53.485796)
		(end 217.297 -43.535092)
		(width 0.508)
		(layer "In2.Cu")
		(net "P3V3_HDD4_LED")
	)
	(segment
		(start 224.345246 -143.5227)
		(end 223.5073 -143.5227)
		(width 0.508)
		(layer "F.Cu")
		(net "P3V3_HDD3_LED")
	)
	(segment
		(start 206.5528 -170.85564)
		(end 206.5528 -171.6786)
		(width 0.4064)
		(layer "F.Cu")
		(net "P3V3_HDD3_LED")
	)
	(via
		(at 223.5073 -143.5227)
		(size 0.5588)
		(drill 0.3048)
		(layers "F.Cu" "B.Cu")
		(net "P3V3_HDD3_LED")
	)
	(via
		(at 206.5528 -171.6786)
		(size 0.5588)
		(drill 0.3048)
		(layers "F.Cu" "B.Cu")
		(net "P3V3_HDD3_LED")
	)
	(via
		(at 206.4512 -172.6946)
		(size 0.7112)
		(drill 0.3556)
		(layers "F.Cu" "B.Cu")
		(net "P3V3_HDD3_LED")
	)
	(segment
		(start 206.4512 -171.7548)
		(end 206.4512 -172.6946)
		(width 0.508)
		(layer "B.Cu")
		(net "P3V3_HDD3_LED")
	)
	(segment
		(start 206.5528 -171.6786)
		(end 206.4512 -171.7548)
		(width 0.508)
		(layer "B.Cu")
		(net "P3V3_HDD3_LED")
	)
	(segment
		(start 222.653606 -144.1069)
		(end 222.9231 -144.1069)
		(width 0.508)
		(layer "In2.Cu")
		(net "P3V3_HDD3_LED")
	)
	(segment
		(start 206.5528 -171.6786)
		(end 207.6196 -170.6118)
		(width 0.508)
		(layer "In2.Cu")
		(net "P3V3_HDD3_LED")
	)
	(segment
		(start 207.6196 -159.140906)
		(end 222.653606 -144.1069)
		(width 0.508)
		(layer "In2.Cu")
		(net "P3V3_HDD3_LED")
	)
	(segment
		(start 222.9231 -144.1069)
		(end 223.5073 -143.5227)
		(width 0.508)
		(layer "In2.Cu")
		(net "P3V3_HDD3_LED")
	)
	(segment
		(start 207.6196 -170.6118)
		(end 207.6196 -159.140906)
		(width 0.508)
		(layer "In2.Cu")
		(net "P3V3_HDD3_LED")
	)
	(segment
		(start 207.1116 -274.0152)
		(end 207.1116 -273.9136)
		(width 0.508)
		(layer "F.Cu")
		(net "P3V3_HDD2_LED")
	)
	(segment
		(start 207.1116 -273.9136)
		(end 206.4766 -273.2786)
		(width 0.508)
		(layer "F.Cu")
		(net "P3V3_HDD2_LED")
	)
	(segment
		(start 224.303082 -246.860568)
		(end 223.445832 -246.860568)
		(width 0.508)
		(layer "F.Cu")
		(net "P3V3_HDD2_LED")
	)
	(segment
		(start 206.4766 -273.2786)
		(end 206.4766 -273.16684)
		(width 0.508)
		(layer "F.Cu")
		(net "P3V3_HDD2_LED")
	)
	(via
		(at 207.1116 -274.955)
		(size 0.7112)
		(drill 0.3556)
		(layers "F.Cu" "B.Cu")
		(net "P3V3_HDD2_LED")
	)
	(via
		(at 207.1116 -274.0152)
		(size 0.5588)
		(drill 0.3048)
		(layers "F.Cu" "B.Cu")
		(net "P3V3_HDD2_LED")
	)
	(via
		(at 223.445832 -246.860568)
		(size 0.5588)
		(drill 0.3048)
		(layers "F.Cu" "B.Cu")
		(net "P3V3_HDD2_LED")
	)
	(segment
		(start 207.1116 -274.955)
		(end 207.1116 -274.0152)
		(width 0.508)
		(layer "B.Cu")
		(net "P3V3_HDD2_LED")
	)
	(segment
		(start 207.1878 -274.0152)
		(end 207.1116 -274.0152)
		(width 0.508)
		(layer "In2.Cu")
		(net "P3V3_HDD2_LED")
	)
	(segment
		(start 222.137224 -247.899682)
		(end 208.9404 -261.096506)
		(width 0.508)
		(layer "In2.Cu")
		(net "P3V3_HDD2_LED")
	)
	(segment
		(start 208.9404 -272.2626)
		(end 207.1878 -274.0152)
		(width 0.508)
		(layer "In2.Cu")
		(net "P3V3_HDD2_LED")
	)
	(segment
		(start 222.406718 -247.899682)
		(end 222.137224 -247.899682)
		(width 0.508)
		(layer "In2.Cu")
		(net "P3V3_HDD2_LED")
	)
	(segment
		(start 208.9404 -261.096506)
		(end 208.9404 -272.2626)
		(width 0.508)
		(layer "In2.Cu")
		(net "P3V3_HDD2_LED")
	)
	(segment
		(start 223.445832 -246.860568)
		(end 222.406718 -247.899682)
		(width 0.508)
		(layer "In2.Cu")
		(net "P3V3_HDD2_LED")
	)
	(segment
		(start 220.999558 -349.452184)
		(end 220.115384 -349.452184)
		(width 0.508)
		(layer "F.Cu")
		(net "P3V3_HDD1_LED")
	)
	(segment
		(start 206.9338 -376.72264)
		(end 206.9338 -377.5202)
		(width 0.4064)
		(layer "F.Cu")
		(net "P3V3_HDD1_LED")
	)
	(via
		(at 206.9338 -377.5202)
		(size 0.5588)
		(drill 0.3048)
		(layers "F.Cu" "B.Cu")
		(net "P3V3_HDD1_LED")
	)
	(via
		(at 221.054676 -349.417386)
		(size 0.7112)
		(drill 0.3556)
		(layers "F.Cu" "B.Cu")
		(net "P3V3_HDD1_LED")
	)
	(via
		(at 220.115384 -349.452184)
		(size 0.5588)
		(drill 0.3048)
		(layers "F.Cu" "B.Cu")
		(net "P3V3_HDD1_LED")
	)
	(segment
		(start 220.115384 -349.452184)
		(end 220.209872 -349.417386)
		(width 0.508)
		(layer "B.Cu")
		(net "P3V3_HDD1_LED")
	)
	(segment
		(start 220.209872 -349.417386)
		(end 221.054676 -349.417386)
		(width 0.508)
		(layer "B.Cu")
		(net "P3V3_HDD1_LED")
	)
	(segment
		(start 220.008196 -349.452184)
		(end 220.115384 -349.452184)
		(width 0.508)
		(layer "In2.Cu")
		(net "P3V3_HDD1_LED")
	)
	(segment
		(start 208.000346 -361.460034)
		(end 220.008196 -349.452184)
		(width 0.508)
		(layer "In2.Cu")
		(net "P3V3_HDD1_LED")
	)
	(segment
		(start 208.000346 -376.453654)
		(end 208.000346 -361.460034)
		(width 0.508)
		(layer "In2.Cu")
		(net "P3V3_HDD1_LED")
	)
	(segment
		(start 206.9338 -377.5202)
		(end 208.000346 -376.453654)
		(width 0.508)
		(layer "In2.Cu")
		(net "P3V3_HDD1_LED")
	)
	(segment
		(start 205.6384 -479.44024)
		(end 204.6986 -479.44024)
		(width 0.4064)
		(layer "F.Cu")
		(net "P3V3_HDD0_LED")
	)
	(segment
		(start 207.0862 -479.44024)
		(end 205.6384 -479.44024)
		(width 0.4064)
		(layer "F.Cu")
		(net "P3V3_HDD0_LED")
	)
	(segment
		(start 224.234756 -452.682102)
		(end 223.434656 -452.682102)
		(width 0.508)
		(layer "F.Cu")
		(net "P3V3_HDD0_LED")
	)
	(via
		(at 204.6986 -479.44024)
		(size 0.5588)
		(drill 0.3048)
		(layers "F.Cu" "B.Cu")
		(net "P3V3_HDD0_LED")
	)
	(via
		(at 223.434656 -452.682102)
		(size 0.5588)
		(drill 0.3048)
		(layers "F.Cu" "B.Cu")
		(net "P3V3_HDD0_LED")
	)
	(via
		(at 205.6384 -479.44024)
		(size 0.7112)
		(drill 0.3556)
		(layers "F.Cu" "B.Cu")
		(net "P3V3_HDD0_LED")
	)
	(segment
		(start 205.90764 -479.44024)
		(end 207.137 -478.21088)
		(width 0.508)
		(layer "In2.Cu")
		(net "P3V3_HDD0_LED")
	)
	(segment
		(start 223.332294 -452.682102)
		(end 223.434656 -452.682102)
		(width 0.508)
		(layer "In2.Cu")
		(net "P3V3_HDD0_LED")
	)
	(segment
		(start 204.6986 -479.44024)
		(end 205.90764 -479.44024)
		(width 0.508)
		(layer "In2.Cu")
		(net "P3V3_HDD0_LED")
	)
	(segment
		(start 207.137 -478.21088)
		(end 207.137 -468.877396)
		(width 0.508)
		(layer "In2.Cu")
		(net "P3V3_HDD0_LED")
	)
	(segment
		(start 207.137 -468.877396)
		(end 223.332294 -452.682102)
		(width 0.508)
		(layer "In2.Cu")
		(net "P3V3_HDD0_LED")
	)
	(segment
		(start 38.4683 -40.9067)
		(end 37.9476 -41.4274)
		(width 0.508)
		(layer "F.Cu")
		(net "P3V3_HDD9_LED")
	)
	(segment
		(start 39.306246 -40.9067)
		(end 38.4683 -40.9067)
		(width 0.508)
		(layer "F.Cu")
		(net "P3V3_HDD9_LED")
	)
	(segment
		(start 61.47816 -70.14464)
		(end 61.47816 -69.8754)
		(width 0.4064)
		(layer "F.Cu")
		(net "P3V3_HDD9_LED")
	)
	(segment
		(start 60.8584 -70.7644)
		(end 61.47816 -70.14464)
		(width 0.4064)
		(layer "F.Cu")
		(net "P3V3_HDD9_LED")
	)
	(segment
		(start 37.9476 -41.4274)
		(end 37.9476 -42.2656)
		(width 0.508)
		(layer "F.Cu")
		(net "P3V3_HDD9_LED")
	)
	(via
		(at 37.9476 -42.2656)
		(size 0.5588)
		(drill 0.3048)
		(layers "F.Cu" "B.Cu")
		(net "P3V3_HDD9_LED")
	)
	(via
		(at 37.9476 -41.275)
		(size 0.7112)
		(drill 0.3556)
		(layers "F.Cu" "B.Cu")
		(net "P3V3_HDD9_LED")
	)
	(via
		(at 60.8584 -70.7644)
		(size 0.5588)
		(drill 0.3048)
		(layers "F.Cu" "B.Cu")
		(net "P3V3_HDD9_LED")
	)
	(segment
		(start 37.9476 -42.2656)
		(end 37.9476 -41.275)
		(width 0.508)
		(layer "B.Cu")
		(net "P3V3_HDD9_LED")
	)
	(segment
		(start 60.6679 -60.099194)
		(end 60.6679 -69.996304)
		(width 0.508)
		(layer "In2.Cu")
		(net "P3V3_HDD9_LED")
	)
	(segment
		(start 38.735 -43.6372)
		(end 42.825162 -43.6372)
		(width 0.508)
		(layer "In2.Cu")
		(net "P3V3_HDD9_LED")
	)
	(segment
		(start 60.6679 -69.996304)
		(end 60.8584 -70.186804)
		(width 0.508)
		(layer "In2.Cu")
		(net "P3V3_HDD9_LED")
	)
	(segment
		(start 60.8584 -70.186804)
		(end 60.8584 -70.7644)
		(width 0.508)
		(layer "In2.Cu")
		(net "P3V3_HDD9_LED")
	)
	(segment
		(start 44.612306 -44.0436)
		(end 60.6679 -60.099194)
		(width 0.508)
		(layer "In2.Cu")
		(net "P3V3_HDD9_LED")
	)
	(segment
		(start 37.9476 -42.2656)
		(end 37.9476 -42.8498)
		(width 0.508)
		(layer "In2.Cu")
		(net "P3V3_HDD9_LED")
	)
	(segment
		(start 42.825162 -43.6372)
		(end 43.231562 -44.0436)
		(width 0.508)
		(layer "In2.Cu")
		(net "P3V3_HDD9_LED")
	)
	(segment
		(start 43.231562 -44.0436)
		(end 44.612306 -44.0436)
		(width 0.508)
		(layer "In2.Cu")
		(net "P3V3_HDD9_LED")
	)
	(segment
		(start 37.9476 -42.8498)
		(end 38.735 -43.6372)
		(width 0.508)
		(layer "In2.Cu")
		(net "P3V3_HDD9_LED")
	)
	(segment
		(start 82.4992 -23.45436)
		(end 82.4992 -22.7076)
		(width 0.4064)
		(layer "F.Cu")
		(net "P3V3_HDD14_LED")
	)
	(segment
		(start 20.637246 -52.9717)
		(end 22.8092 -52.9717)
		(width 0.508)
		(layer "F.Cu")
		(net "P3V3_HDD14_LED")
	)
	(via
		(at 22.8092 -52.9717)
		(size 0.5588)
		(drill 0.3048)
		(layers "F.Cu" "B.Cu")
		(net "P3V3_HDD14_LED")
	)
	(via
		(at 82.4992 -23.6474)
		(size 0.7112)
		(drill 0.3556)
		(layers "F.Cu" "B.Cu")
		(net "P3V3_HDD14_LED")
	)
	(via
		(at 82.4992 -22.7076)
		(size 0.5588)
		(drill 0.3048)
		(layers "F.Cu" "B.Cu")
		(net "P3V3_HDD14_LED")
	)
	(segment
		(start 82.4992 -22.7076)
		(end 82.4992 -23.6474)
		(width 0.508)
		(layer "B.Cu")
		(net "P3V3_HDD14_LED")
	)
	(segment
		(start 22.8092 -52.9717)
		(end 24.924004 -52.9717)
		(width 0.508)
		(layer "In2.Cu")
		(net "P3V3_HDD14_LED")
	)
	(segment
		(start 37.766498 -40.129206)
		(end 66.760598 -40.129206)
		(width 0.508)
		(layer "In2.Cu")
		(net "P3V3_HDD14_LED")
	)
	(segment
		(start 66.760598 -40.129206)
		(end 81.6102 -25.279604)
		(width 0.508)
		(layer "In2.Cu")
		(net "P3V3_HDD14_LED")
	)
	(segment
		(start 81.6102 -25.279604)
		(end 81.6102 -23.4696)
		(width 0.508)
		(layer "In2.Cu")
		(net "P3V3_HDD14_LED")
	)
	(segment
		(start 82.3722 -22.7076)
		(end 82.4992 -22.7076)
		(width 0.508)
		(layer "In2.Cu")
		(net "P3V3_HDD14_LED")
	)
	(segment
		(start 24.924004 -52.9717)
		(end 37.766498 -40.129206)
		(width 0.508)
		(layer "In2.Cu")
		(net "P3V3_HDD14_LED")
	)
	(segment
		(start 81.6102 -23.4696)
		(end 82.3722 -22.7076)
		(width 0.508)
		(layer "In2.Cu")
		(net "P3V3_HDD14_LED")
	)
	(segment
		(start 35.157664 -140.589)
		(end 35.79876 -139.947904)
		(width 0.4064)
		(layer "F.Cu")
		(net "P3V3_HDD13_LED")
	)
	(segment
		(start 35.79876 -139.947904)
		(end 35.79876 -139.7762)
		(width 0.4064)
		(layer "F.Cu")
		(net "P3V3_HDD13_LED")
	)
	(segment
		(start 20.637754 -156.3243)
		(end 20.637754 -157.289754)
		(width 0.508)
		(layer "F.Cu")
		(net "P3V3_HDD13_LED")
	)
	(via
		(at 34.2138 -140.6652)
		(size 0.7112)
		(drill 0.3556)
		(layers "F.Cu" "B.Cu")
		(net "P3V3_HDD13_LED")
	)
	(via
		(at 35.157664 -140.589)
		(size 0.5588)
		(drill 0.3048)
		(layers "F.Cu" "B.Cu")
		(net "P3V3_HDD13_LED")
	)
	(via
		(at 20.637754 -157.289754)
		(size 0.5588)
		(drill 0.3048)
		(layers "F.Cu" "B.Cu")
		(net "P3V3_HDD13_LED")
	)
	(segment
		(start 35.081464 -140.6652)
		(end 34.2138 -140.6652)
		(width 0.508)
		(layer "B.Cu")
		(net "P3V3_HDD13_LED")
	)
	(segment
		(start 35.157664 -140.589)
		(end 35.081464 -140.6652)
		(width 0.508)
		(layer "B.Cu")
		(net "P3V3_HDD13_LED")
	)
	(segment
		(start 40.259 -162.70478)
		(end 40.182546 -162.628326)
		(width 0.508)
		(layer "In5.Cu")
		(net "P3V3_HDD13_LED")
	)
	(segment
		(start 31.792672 -167.123872)
		(end 39.281608 -167.123872)
		(width 0.508)
		(layer "In5.Cu")
		(net "P3V3_HDD13_LED")
	)
	(segment
		(start 40.182546 -162.628326)
		(end 40.182546 -154.101546)
		(width 0.508)
		(layer "In5.Cu")
		(net "P3V3_HDD13_LED")
	)
	(segment
		(start 21.958554 -157.289754)
		(end 31.792672 -167.123872)
		(width 0.508)
		(layer "In5.Cu")
		(net "P3V3_HDD13_LED")
	)
	(segment
		(start 35.381946 -140.589)
		(end 35.157664 -140.589)
		(width 0.508)
		(layer "In5.Cu")
		(net "P3V3_HDD13_LED")
	)
	(segment
		(start 39.281608 -167.123872)
		(end 40.259 -166.14648)
		(width 0.508)
		(layer "In5.Cu")
		(net "P3V3_HDD13_LED")
	)
	(segment
		(start 40.182546 -154.101546)
		(end 37.769546 -151.688546)
		(width 0.508)
		(layer "In5.Cu")
		(net "P3V3_HDD13_LED")
	)
	(segment
		(start 40.259 -166.14648)
		(end 40.259 -162.70478)
		(width 0.508)
		(layer "In5.Cu")
		(net "P3V3_HDD13_LED")
	)
	(segment
		(start 37.769546 -151.688546)
		(end 37.769546 -142.9766)
		(width 0.508)
		(layer "In5.Cu")
		(net "P3V3_HDD13_LED")
	)
	(segment
		(start 37.769546 -142.9766)
		(end 35.381946 -140.589)
		(width 0.508)
		(layer "In5.Cu")
		(net "P3V3_HDD13_LED")
	)
	(segment
		(start 20.637754 -157.289754)
		(end 21.958554 -157.289754)
		(width 0.508)
		(layer "In5.Cu")
		(net "P3V3_HDD13_LED")
	)
	(segment
		(start 44.0436 -238.0234)
		(end 46.06036 -238.0234)
		(width 0.4064)
		(layer "F.Cu")
		(net "P3V3_HDD12_LED")
	)
	(segment
		(start 43.434 -238.633)
		(end 44.0436 -238.0234)
		(width 0.4064)
		(layer "F.Cu")
		(net "P3V3_HDD12_LED")
	)
	(segment
		(start 20.1295 -257.302)
		(end 19.364706 -257.302)
		(width 0.508)
		(layer "F.Cu")
		(net "P3V3_HDD12_LED")
	)
	(segment
		(start 19.364706 -257.302)
		(end 19.177 -257.114294)
		(width 0.508)
		(layer "F.Cu")
		(net "P3V3_HDD12_LED")
	)
	(via
		(at 26.3906 -253.8476)
		(size 0.7112)
		(drill 0.3556)
		(layers "F.Cu" "B.Cu")
		(net "P3V3_HDD12_LED")
	)
	(via
		(at 43.434 -238.633)
		(size 0.5588)
		(drill 0.3048)
		(layers "F.Cu" "B.Cu")
		(net "P3V3_HDD12_LED")
	)
	(via
		(at 19.177 -257.114294)
		(size 0.5588)
		(drill 0.3048)
		(layers "F.Cu" "B.Cu")
		(net "P3V3_HDD12_LED")
	)
	(via
		(at 26.5938 -251.4346)
		(size 0.5588)
		(drill 0.3048)
		(layers "F.Cu" "B.Cu")
		(net "P3V3_HDD12_LED")
	)
	(segment
		(start 26.5938 -252.095)
		(end 26.5938 -251.4346)
		(width 0.508)
		(layer "B.Cu")
		(net "P3V3_HDD12_LED")
	)
	(segment
		(start 26.3906 -252.2982)
		(end 26.5938 -252.095)
		(width 0.508)
		(layer "B.Cu")
		(net "P3V3_HDD12_LED")
	)
	(segment
		(start 26.3906 -254.5842)
		(end 26.3906 -253.8476)
		(width 0.508)
		(layer "B.Cu")
		(net "P3V3_HDD12_LED")
	)
	(segment
		(start 26.3906 -253.8476)
		(end 26.3906 -252.2982)
		(width 0.508)
		(layer "B.Cu")
		(net "P3V3_HDD12_LED")
	)
	(segment
		(start 23.860506 -257.114294)
		(end 26.3906 -254.5842)
		(width 0.508)
		(layer "B.Cu")
		(net "P3V3_HDD12_LED")
	)
	(segment
		(start 19.177 -257.114294)
		(end 23.860506 -257.114294)
		(width 0.508)
		(layer "B.Cu")
		(net "P3V3_HDD12_LED")
	)
	(segment
		(start 43.135804 -242.1763)
		(end 44.0563 -241.255804)
		(width 0.508)
		(layer "In5.Cu")
		(net "P3V3_HDD12_LED")
	)
	(segment
		(start 41.744138 -243.1288)
		(end 42.696638 -242.1763)
		(width 0.508)
		(layer "In5.Cu")
		(net "P3V3_HDD12_LED")
	)
	(segment
		(start 26.5938 -251.4346)
		(end 28.994608 -251.4346)
		(width 0.508)
		(layer "In5.Cu")
		(net "P3V3_HDD12_LED")
	)
	(segment
		(start 44.0563 -240.5761)
		(end 43.434 -239.9538)
		(width 0.508)
		(layer "In5.Cu")
		(net "P3V3_HDD12_LED")
	)
	(segment
		(start 42.696638 -242.1763)
		(end 43.135804 -242.1763)
		(width 0.508)
		(layer "In5.Cu")
		(net "P3V3_HDD12_LED")
	)
	(segment
		(start 28.994608 -251.4346)
		(end 37.300408 -243.1288)
		(width 0.508)
		(layer "In5.Cu")
		(net "P3V3_HDD12_LED")
	)
	(segment
		(start 37.300408 -243.1288)
		(end 41.744138 -243.1288)
		(width 0.508)
		(layer "In5.Cu")
		(net "P3V3_HDD12_LED")
	)
	(segment
		(start 43.434 -239.9538)
		(end 43.434 -238.633)
		(width 0.508)
		(layer "In5.Cu")
		(net "P3V3_HDD12_LED")
	)
	(segment
		(start 44.0563 -241.255804)
		(end 44.0563 -240.5761)
		(width 0.508)
		(layer "In5.Cu")
		(net "P3V3_HDD12_LED")
	)
	(segment
		(start 37.4396 -336.43316)
		(end 37.4396 -335.6864)
		(width 0.4064)
		(layer "F.Cu")
		(net "P3V3_HDD11_LED")
	)
	(segment
		(start 32.5755 -346.71)
		(end 32.0294 -346.71)
		(width 0.508)
		(layer "F.Cu")
		(net "P3V3_HDD11_LED")
	)
	(segment
		(start 32.0294 -346.71)
		(end 31.7754 -346.964)
		(width 0.508)
		(layer "F.Cu")
		(net "P3V3_HDD11_LED")
	)
	(via
		(at 31.7754 -346.964)
		(size 0.5588)
		(drill 0.3048)
		(layers "F.Cu" "B.Cu")
		(net "P3V3_HDD11_LED")
	)
	(via
		(at 37.4396 -335.6864)
		(size 0.5588)
		(drill 0.3048)
		(layers "F.Cu" "B.Cu")
		(net "P3V3_HDD11_LED")
	)
	(via
		(at 36.449 -336.169)
		(size 0.7112)
		(drill 0.3556)
		(layers "F.Cu" "B.Cu")
		(net "P3V3_HDD11_LED")
	)
	(segment
		(start 37.4396 -335.6864)
		(end 36.957 -336.169)
		(width 0.508)
		(layer "B.Cu")
		(net "P3V3_HDD11_LED")
	)
	(segment
		(start 36.957 -336.169)
		(end 36.449 -336.169)
		(width 0.508)
		(layer "B.Cu")
		(net "P3V3_HDD11_LED")
	)
	(segment
		(start 38.258496 -339.384132)
		(end 38.258496 -346.043504)
		(width 0.508)
		(layer "In2.Cu")
		(net "P3V3_HDD11_LED")
	)
	(segment
		(start 38.53815 -338.326222)
		(end 38.53815 -339.104478)
		(width 0.508)
		(layer "In2.Cu")
		(net "P3V3_HDD11_LED")
	)
	(segment
		(start 38.258496 -336.505296)
		(end 38.258496 -338.046568)
		(width 0.508)
		(layer "In2.Cu")
		(net "P3V3_HDD11_LED")
	)
	(segment
		(start 38.258496 -346.043504)
		(end 37.0332 -347.2688)
		(width 0.508)
		(layer "In2.Cu")
		(net "P3V3_HDD11_LED")
	)
	(segment
		(start 37.4396 -335.6864)
		(end 38.258496 -336.505296)
		(width 0.508)
		(layer "In2.Cu")
		(net "P3V3_HDD11_LED")
	)
	(segment
		(start 37.0332 -347.2688)
		(end 32.0802 -347.2688)
		(width 0.508)
		(layer "In2.Cu")
		(net "P3V3_HDD11_LED")
	)
	(segment
		(start 32.0802 -347.2688)
		(end 31.7754 -346.964)
		(width 0.508)
		(layer "In2.Cu")
		(net "P3V3_HDD11_LED")
	)
	(segment
		(start 38.258496 -338.046568)
		(end 38.53815 -338.326222)
		(width 0.508)
		(layer "In2.Cu")
		(net "P3V3_HDD11_LED")
	)
	(segment
		(start 38.53815 -339.104478)
		(end 38.258496 -339.384132)
		(width 0.508)
		(layer "In2.Cu")
		(net "P3V3_HDD11_LED")
	)
	(segment
		(start 21.843746 -465.483702)
		(end 21.872448 -465.455)
		(width 0.508)
		(layer "F.Cu")
		(net "P3V3_HDD10_LED")
	)
	(segment
		(start 23.673054 -464.845146)
		(end 23.0632 -465.455)
		(width 0.508)
		(layer "F.Cu")
		(net "P3V3_HDD10_LED")
	)
	(segment
		(start 21.872448 -465.455)
		(end 23.0632 -465.455)
		(width 0.508)
		(layer "F.Cu")
		(net "P3V3_HDD10_LED")
	)
	(segment
		(start 43.74896 -426.63364)
		(end 43.74896 -426.3136)
		(width 0.4064)
		(layer "F.Cu")
		(net "P3V3_HDD10_LED")
	)
	(segment
		(start 43.0784 -427.3042)
		(end 43.74896 -426.63364)
		(width 0.4064)
		(layer "F.Cu")
		(net "P3V3_HDD10_LED")
	)
	(segment
		(start 23.749 -464.2866)
		(end 23.673054 -464.362546)
		(width 0.508)
		(layer "F.Cu")
		(net "P3V3_HDD10_LED")
	)
	(segment
		(start 23.673054 -464.362546)
		(end 23.673054 -464.845146)
		(width 0.508)
		(layer "F.Cu")
		(net "P3V3_HDD10_LED")
	)
	(via
		(at 43.0784 -427.3042)
		(size 0.5588)
		(drill 0.3048)
		(layers "F.Cu" "B.Cu")
		(net "P3V3_HDD10_LED")
	)
	(via
		(at 23.0632 -465.455)
		(size 0.7112)
		(drill 0.3556)
		(layers "F.Cu" "B.Cu")
		(net "P3V3_HDD10_LED")
	)
	(via
		(at 23.749 -464.2866)
		(size 0.5588)
		(drill 0.3048)
		(layers "F.Cu" "B.Cu")
		(net "P3V3_HDD10_LED")
	)
	(segment
		(start 43.7642 -427.856142)
		(end 43.288458 -427.3804)
		(width 0.508)
		(layer "In2.Cu")
		(net "P3V3_HDD10_LED")
	)
	(segment
		(start 23.749 -464.2866)
		(end 23.9268 -464.4644)
		(width 0.508)
		(layer "In2.Cu")
		(net "P3V3_HDD10_LED")
	)
	(segment
		(start 43.1546 -427.3804)
		(end 43.0784 -427.3042)
		(width 0.508)
		(layer "In2.Cu")
		(net "P3V3_HDD10_LED")
	)
	(segment
		(start 43.288458 -427.3804)
		(end 43.1546 -427.3804)
		(width 0.508)
		(layer "In2.Cu")
		(net "P3V3_HDD10_LED")
	)
	(segment
		(start 39.497 -433.081938)
		(end 43.7642 -428.814738)
		(width 0.508)
		(layer "In2.Cu")
		(net "P3V3_HDD10_LED")
	)
	(segment
		(start 24.809958 -464.4644)
		(end 39.497 -449.777358)
		(width 0.508)
		(layer "In2.Cu")
		(net "P3V3_HDD10_LED")
	)
	(segment
		(start 39.497 -449.777358)
		(end 39.497 -433.081938)
		(width 0.508)
		(layer "In2.Cu")
		(net "P3V3_HDD10_LED")
	)
	(segment
		(start 23.9268 -464.4644)
		(end 24.809958 -464.4644)
		(width 0.508)
		(layer "In2.Cu")
		(net "P3V3_HDD10_LED")
	)
	(segment
		(start 43.7642 -428.814738)
		(end 43.7642 -427.856142)
		(width 0.508)
		(layer "In2.Cu")
		(net "P3V3_HDD10_LED")
	)
	(segment
		(start 38.366446 -145.40865)
		(end 39.52875 -146.570954)
		(width 0.508)
		(layer "F.Cu")
		(net "P3V3_HDD8_LED")
	)
	(segment
		(start 39.179246 -143.7767)
		(end 39.045388 -143.7767)
		(width 0.508)
		(layer "F.Cu")
		(net "P3V3_HDD8_LED")
	)
	(segment
		(start 39.52875 -146.570954)
		(end 40.767 -146.570954)
		(width 0.508)
		(layer "F.Cu")
		(net "P3V3_HDD8_LED")
	)
	(segment
		(start 38.366446 -144.455642)
		(end 38.366446 -145.40865)
		(width 0.508)
		(layer "F.Cu")
		(net "P3V3_HDD8_LED")
	)
	(segment
		(start 39.045388 -143.7767)
		(end 38.366446 -144.455642)
		(width 0.508)
		(layer "F.Cu")
		(net "P3V3_HDD8_LED")
	)
	(segment
		(start 61.087 -173.355)
		(end 61.32576 -173.355)
		(width 0.508)
		(layer "F.Cu")
		(net "P3V3_HDD8_LED")
	)
	(segment
		(start 60.579 -172.9232)
		(end 60.6552 -172.9232)
		(width 0.508)
		(layer "F.Cu")
		(net "P3V3_HDD8_LED")
	)
	(segment
		(start 40.767 -146.570954)
		(end 40.779954 -146.558)
		(width 0.508)
		(layer "F.Cu")
		(net "P3V3_HDD8_LED")
	)
	(segment
		(start 60.6552 -172.9232)
		(end 61.087 -173.355)
		(width 0.508)
		(layer "F.Cu")
		(net "P3V3_HDD8_LED")
	)
	(segment
		(start 40.779954 -146.558)
		(end 40.849296 -146.558)
		(width 0.508)
		(layer "F.Cu")
		(net "P3V3_HDD8_LED")
	)
	(via
		(at 60.579 -172.9232)
		(size 0.5588)
		(drill 0.3048)
		(layers "F.Cu" "B.Cu")
		(net "P3V3_HDD8_LED")
	)
	(via
		(at 40.849296 -146.558)
		(size 0.5588)
		(drill 0.3048)
		(layers "F.Cu" "B.Cu")
		(net "P3V3_HDD8_LED")
	)
	(via
		(at 40.8686 -145.542)
		(size 0.7112)
		(drill 0.3556)
		(layers "F.Cu" "B.Cu")
		(net "P3V3_HDD8_LED")
	)
	(segment
		(start 40.849296 -146.558)
		(end 40.8686 -146.4818)
		(width 0.508)
		(layer "B.Cu")
		(net "P3V3_HDD8_LED")
	)
	(segment
		(start 40.8686 -146.4818)
		(end 40.8686 -145.542)
		(width 0.508)
		(layer "B.Cu")
		(net "P3V3_HDD8_LED")
	)
	(segment
		(start 60.579 -161.96691)
		(end 60.579 -172.9232)
		(width 0.508)
		(layer "In2.Cu")
		(net "P3V3_HDD8_LED")
	)
	(segment
		(start 53.187346 -154.393392)
		(end 53.187346 -154.575256)
		(width 0.508)
		(layer "In2.Cu")
		(net "P3V3_HDD8_LED")
	)
	(segment
		(start 52.57419 -153.9621)
		(end 52.756054 -153.9621)
		(width 0.508)
		(layer "In2.Cu")
		(net "P3V3_HDD8_LED")
	)
	(segment
		(start 52.756054 -153.9621)
		(end 53.187346 -154.393392)
		(width 0.508)
		(layer "In2.Cu")
		(net "P3V3_HDD8_LED")
	)
	(segment
		(start 45.17009 -146.558)
		(end 52.57419 -153.9621)
		(width 0.508)
		(layer "In2.Cu")
		(net "P3V3_HDD8_LED")
	)
	(segment
		(start 53.187346 -154.575256)
		(end 60.579 -161.96691)
		(width 0.508)
		(layer "In2.Cu")
		(net "P3V3_HDD8_LED")
	)
	(segment
		(start 40.849296 -146.558)
		(end 45.17009 -146.558)
		(width 0.508)
		(layer "In2.Cu")
		(net "P3V3_HDD8_LED")
	)
	(segment
		(start 39.306246 -246.7737)
		(end 39.306246 -245.935246)
		(width 0.508)
		(layer "F.Cu")
		(net "P3V3_HDD7_LED")
	)
	(segment
		(start 61.468 -271.526)
		(end 61.468 -270.764)
		(width 0.4064)
		(layer "F.Cu")
		(net "P3V3_HDD7_LED")
	)
	(via
		(at 39.306246 -245.935246)
		(size 0.5588)
		(drill 0.3048)
		(layers "F.Cu" "B.Cu")
		(net "P3V3_HDD7_LED")
	)
	(via
		(at 61.468 -270.764)
		(size 0.5588)
		(drill 0.3048)
		(layers "F.Cu" "B.Cu")
		(net "P3V3_HDD7_LED")
	)
	(via
		(at 61.468 -271.7038)
		(size 0.7112)
		(drill 0.3556)
		(layers "F.Cu" "B.Cu")
		(net "P3V3_HDD7_LED")
	)
	(segment
		(start 61.468 -270.764)
		(end 61.468 -271.7038)
		(width 0.508)
		(layer "B.Cu")
		(net "P3V3_HDD7_LED")
	)
	(segment
		(start 59.182 -268.478)
		(end 59.182 -264.8966)
		(width 0.508)
		(layer "In2.Cu")
		(net "P3V3_HDD7_LED")
	)
	(segment
		(start 61.468 -270.764)
		(end 59.182 -268.478)
		(width 0.508)
		(layer "In2.Cu")
		(net "P3V3_HDD7_LED")
	)
	(segment
		(start 40.220646 -245.935246)
		(end 39.306246 -245.935246)
		(width 0.508)
		(layer "In2.Cu")
		(net "P3V3_HDD7_LED")
	)
	(segment
		(start 59.182 -264.8966)
		(end 40.220646 -245.935246)
		(width 0.508)
		(layer "In2.Cu")
		(net "P3V3_HDD7_LED")
	)
	(segment
		(start 59.3344 -376.301)
		(end 59.3344 -375.50344)
		(width 0.4064)
		(layer "F.Cu")
		(net "P3V3_HDD6_LED")
	)
	(segment
		(start 45.847 -348.7547)
		(end 45.847 -347.9546)
		(width 0.508)
		(layer "F.Cu")
		(net "P3V3_HDD6_LED")
	)
	(segment
		(start 59.3598 -376.3264)
		(end 59.3344 -376.301)
		(width 0.4064)
		(layer "F.Cu")
		(net "P3V3_HDD6_LED")
	)
	(via
		(at 59.3598 -376.3264)
		(size 0.5588)
		(drill 0.3048)
		(layers "F.Cu" "B.Cu")
		(net "P3V3_HDD6_LED")
	)
	(via
		(at 45.847 -347.9546)
		(size 0.5588)
		(drill 0.3048)
		(layers "F.Cu" "B.Cu")
		(net "P3V3_HDD6_LED")
	)
	(via
		(at 45.8216 -348.996)
		(size 0.7112)
		(drill 0.3556)
		(layers "F.Cu" "B.Cu")
		(net "P3V3_HDD6_LED")
	)
	(segment
		(start 45.847 -347.9546)
		(end 45.8216 -347.98)
		(width 0.508)
		(layer "B.Cu")
		(net "P3V3_HDD6_LED")
	)
	(segment
		(start 45.8216 -347.98)
		(end 45.8216 -348.996)
		(width 0.508)
		(layer "B.Cu")
		(net "P3V3_HDD6_LED")
	)
	(segment
		(start 46.0756 -359.289604)
		(end 46.0756 -348.1832)
		(width 0.508)
		(layer "In2.Cu")
		(net "P3V3_HDD6_LED")
	)
	(segment
		(start 59.3598 -372.573804)
		(end 46.0756 -359.289604)
		(width 0.508)
		(layer "In2.Cu")
		(net "P3V3_HDD6_LED")
	)
	(segment
		(start 59.3598 -376.3264)
		(end 59.3598 -372.573804)
		(width 0.508)
		(layer "In2.Cu")
		(net "P3V3_HDD6_LED")
	)
	(segment
		(start 46.0756 -348.1832)
		(end 45.847 -347.9546)
		(width 0.508)
		(layer "In2.Cu")
		(net "P3V3_HDD6_LED")
	)
	(segment
		(start 38.486334 -453.283066)
		(end 38.486334 -454.462642)
		(width 0.508)
		(layer "F.Cu")
		(net "P3V3_HDD5_LED")
	)
	(segment
		(start 38.910514 -452.858886)
		(end 38.486334 -453.283066)
		(width 0.508)
		(layer "F.Cu")
		(net "P3V3_HDD5_LED")
	)
	(segment
		(start 38.486334 -454.462642)
		(end 39.547292 -455.5236)
		(width 0.508)
		(layer "F.Cu")
		(net "P3V3_HDD5_LED")
	)
	(segment
		(start 55.3974 -478.27184)
		(end 55.3974 -479.1456)
		(width 0.4064)
		(layer "F.Cu")
		(net "P3V3_HDD5_LED")
	)
	(segment
		(start 39.547292 -455.5236)
		(end 41.1226 -455.5236)
		(width 0.508)
		(layer "F.Cu")
		(net "P3V3_HDD5_LED")
	)
	(segment
		(start 39.299134 -452.858886)
		(end 38.910514 -452.858886)
		(width 0.508)
		(layer "F.Cu")
		(net "P3V3_HDD5_LED")
	)
	(via
		(at 41.1226 -455.5236)
		(size 0.5588)
		(drill 0.3048)
		(layers "F.Cu" "B.Cu")
		(net "P3V3_HDD5_LED")
	)
	(via
		(at 55.3974 -478.2058)
		(size 0.7112)
		(drill 0.3556)
		(layers "F.Cu" "B.Cu")
		(net "P3V3_HDD5_LED")
	)
	(via
		(at 55.3974 -479.1456)
		(size 0.5588)
		(drill 0.3048)
		(layers "F.Cu" "B.Cu")
		(net "P3V3_HDD5_LED")
	)
	(segment
		(start 55.3974 -479.1456)
		(end 55.3974 -478.2058)
		(width 0.508)
		(layer "B.Cu")
		(net "P3V3_HDD5_LED")
	)
	(segment
		(start 55.2069 -464.387946)
		(end 46.418754 -455.5998)
		(width 0.508)
		(layer "In2.Cu")
		(net "P3V3_HDD5_LED")
	)
	(segment
		(start 55.2069 -478.9551)
		(end 55.2069 -464.387946)
		(width 0.508)
		(layer "In2.Cu")
		(net "P3V3_HDD5_LED")
	)
	(segment
		(start 41.1988 -455.5998)
		(end 41.1226 -455.5236)
		(width 0.508)
		(layer "In2.Cu")
		(net "P3V3_HDD5_LED")
	)
	(segment
		(start 46.418754 -455.5998)
		(end 41.1988 -455.5998)
		(width 0.508)
		(layer "In2.Cu")
		(net "P3V3_HDD5_LED")
	)
	(segment
		(start 55.3974 -479.1456)
		(end 55.2069 -478.9551)
		(width 0.508)
		(layer "In2.Cu")
		(net "P3V3_HDD5_LED")
	)
	(segment
		(start 80.898746 -400.6215)
		(end 80.898746 -401.967954)
		(width 0.111252)
		(layer "F.Cu")
		(net "SW_HDD6_G")
	)
	(segment
		(start 80.898746 -401.967954)
		(end 80.8863 -401.9804)
		(width 0.111252)
		(layer "F.Cu")
		(net "SW_HDD6_G")
	)
	(segment
		(start 80.8863 -401.9804)
		(end 82.042 -401.9804)
		(width 0.111252)
		(layer "F.Cu")
		(net "SW_HDD6_G")
	)
	(via
		(at 82.042 -401.9804)
		(size 0.7112)
		(drill 0.3556)
		(layers "F.Cu" "B.Cu")
		(net "SW_HDD6_G")
	)
	(via
		(at 221.8182 -441.9854)
		(size 0.5588)
		(drill 0.3048)
		(layers "F.Cu" "B.Cu")
		(net "P3V3_IN")
	)
	(via
		(at 221.178882 -442.675518)
		(size 0.7112)
		(drill 0.3556)
		(layers "F.Cu" "B.Cu")
		(net "P3V3_IN")
	)
	(segment
		(start 221.8182 -441.9854)
		(end 221.8182 -442.0362)
		(width 0.508)
		(layer "B.Cu")
		(net "P3V3_IN")
	)
	(segment
		(start 221.8182 -442.0362)
		(end 221.178882 -442.675518)
		(width 0.508)
		(layer "B.Cu")
		(net "P3V3_IN")
	)
	(segment
		(start 82.677 -500.761)
		(end 82.55 -500.888)
		(width 0.111252)
		(layer "F.Cu")
		(net "SW_HDD5_G")
	)
	(segment
		(start 81.69656 -500.86006)
		(end 81.69656 -499.483888)
		(width 0.111252)
		(layer "F.Cu")
		(net "SW_HDD5_G")
	)
	(segment
		(start 81.6991 -500.8626)
		(end 81.69656 -500.86006)
		(width 0.111252)
		(layer "F.Cu")
		(net "SW_HDD5_G")
	)
	(segment
		(start 81.7372 -500.888)
		(end 81.6991 -500.8626)
		(width 0.111252)
		(layer "F.Cu")
		(net "SW_HDD5_G")
	)
	(segment
		(start 82.55 -500.888)
		(end 81.7372 -500.888)
		(width 0.111252)
		(layer "F.Cu")
		(net "SW_HDD5_G")
	)
	(via
		(at 82.677 -500.761)
		(size 0.7112)
		(drill 0.3556)
		(layers "F.Cu" "B.Cu")
		(net "SW_HDD5_G")
	)
	(segment
		(start 59.2201 -380.8222)
		(end 59.2582 -380.8476)
		(width 0.111252)
		(layer "F.Cu")
		(net "HDD6_LED_B")
	)
	(segment
		(start 60.09005 -379.95225)
		(end 59.2201 -380.8222)
		(width 0.111252)
		(layer "F.Cu")
		(net "HDD6_LED_B")
	)
	(segment
		(start 59.2582 -380.8476)
		(end 61.6458 -380.8476)
		(width 0.111252)
		(layer "F.Cu")
		(net "HDD6_LED_B")
	)
	(segment
		(start 60.09005 -379.3363)
		(end 60.09005 -379.95225)
		(width 0.111252)
		(layer "F.Cu")
		(net "HDD6_LED_B")
	)
	(via
		(at 61.6458 -380.8476)
		(size 0.7112)
		(drill 0.3556)
		(layers "F.Cu" "B.Cu")
		(net "HDD6_LED_B")
	)
	(segment
		(start 58.7756 -374.8532)
		(end 59.3344 -374.8532)
		(width 0.111252)
		(layer "F.Cu")
		(net "HDD6_LED_G")
	)
	(segment
		(start 59.1058 -377.4313)
		(end 57.9755 -376.301)
		(width 0.111252)
		(layer "F.Cu")
		(net "HDD6_LED_G")
	)
	(segment
		(start 57.9755 -375.9454)
		(end 57.9755 -375.6533)
		(width 0.111252)
		(layer "F.Cu")
		(net "HDD6_LED_G")
	)
	(segment
		(start 61.214 -374.8532)
		(end 59.3344 -374.8532)
		(width 0.111252)
		(layer "F.Cu")
		(net "HDD6_LED_G")
	)
	(segment
		(start 57.145936 -377.4313)
		(end 59.1058 -377.4313)
		(width 0.111252)
		(layer "F.Cu")
		(net "HDD6_LED_G")
	)
	(segment
		(start 57.9755 -375.6533)
		(end 58.7756 -374.8532)
		(width 0.111252)
		(layer "F.Cu")
		(net "HDD6_LED_G")
	)
	(segment
		(start 57.9755 -376.301)
		(end 57.9755 -375.9454)
		(width 0.111252)
		(layer "F.Cu")
		(net "HDD6_LED_G")
	)
	(segment
		(start 56.769254 -377.807982)
		(end 57.145936 -377.4313)
		(width 0.111252)
		(layer "F.Cu")
		(net "HDD6_LED_G")
	)
	(via
		(at 56.769254 -377.807982)
		(size 0.7112)
		(drill 0.3556)
		(layers "F.Cu" "B.Cu")
		(net "HDD6_LED_G")
	)
	(segment
		(start 46.8884 -348.7547)
		(end 46.8884 -347.7514)
		(width 0.508)
		(layer "F.Cu")
		(net "P5VB_HDD6_LED")
	)
	(segment
		(start 46.8884 -347.7514)
		(end 45.974 -346.837)
		(width 0.508)
		(layer "F.Cu")
		(net "P5VB_HDD6_LED")
	)
	(segment
		(start 61.214 -373.2784)
		(end 61.214 -374.20296)
		(width 0.4064)
		(layer "F.Cu")
		(net "P5VB_HDD6_LED")
	)
	(via
		(at 61.214 -373.2784)
		(size 0.5588)
		(drill 0.3048)
		(layers "F.Cu" "B.Cu")
		(net "P5VB_HDD6_LED")
	)
	(via
		(at 45.974 -345.694)
		(size 0.7112)
		(drill 0.3556)
		(layers "F.Cu" "B.Cu")
		(net "P5VB_HDD6_LED")
	)
	(via
		(at 45.974 -346.837)
		(size 0.5588)
		(drill 0.3048)
		(layers "F.Cu" "B.Cu")
		(net "P5VB_HDD6_LED")
	)
	(segment
		(start 45.974 -346.837)
		(end 45.974 -345.694)
		(width 0.508)
		(layer "B.Cu")
		(net "P5VB_HDD6_LED")
	)
	(segment
		(start 46.8884 -358.9528)
		(end 46.8884 -347.7514)
		(width 0.508)
		(layer "In2.Cu")
		(net "P5VB_HDD6_LED")
	)
	(segment
		(start 61.214 -373.2784)
		(end 46.8884 -358.9528)
		(width 0.508)
		(layer "In2.Cu")
		(net "P5VB_HDD6_LED")
	)
	(segment
		(start 46.8884 -347.7514)
		(end 45.974 -346.837)
		(width 0.508)
		(layer "In2.Cu")
		(net "P5VB_HDD6_LED")
	)
	(segment
		(start 196.596 -84.7217)
		(end 195.961 -85.3567)
		(width 0.111252)
		(layer "F.Cu")
		(net "SW_HDD4_G")
	)
	(segment
		(start 196.596 -84.709)
		(end 196.596 -84.7217)
		(width 0.111252)
		(layer "F.Cu")
		(net "SW_HDD4_G")
	)
	(segment
		(start 195.961 -85.3567)
		(end 195.961 -85.7885)
		(width 0.111252)
		(layer "F.Cu")
		(net "SW_HDD4_G")
	)
	(segment
		(start 195.535804 -86.213696)
		(end 194.609212 -86.213696)
		(width 0.111252)
		(layer "F.Cu")
		(net "SW_HDD4_G")
	)
	(segment
		(start 195.961 -85.7885)
		(end 195.535804 -86.213696)
		(width 0.111252)
		(layer "F.Cu")
		(net "SW_HDD4_G")
	)
	(via
		(at 196.596 -84.709)
		(size 0.7112)
		(drill 0.3556)
		(layers "F.Cu" "B.Cu")
		(net "SW_HDD4_G")
	)
	(segment
		(start 40.08755 -427.2407)
		(end 39.42715 -427.9011)
		(width 0.111252)
		(layer "F.Cu")
		(net "HDD10_LED_B")
	)
	(segment
		(start 37.9349 -427.9011)
		(end 37.6174 -427.5836)
		(width 0.111252)
		(layer "F.Cu")
		(net "HDD10_LED_B")
	)
	(segment
		(start 38.7604 -427.9011)
		(end 37.9349 -427.9011)
		(width 0.111252)
		(layer "F.Cu")
		(net "HDD10_LED_B")
	)
	(segment
		(start 39.42715 -427.9011)
		(end 38.7604 -427.9011)
		(width 0.111252)
		(layer "F.Cu")
		(net "HDD10_LED_B")
	)
	(via
		(at 37.6174 -427.5836)
		(size 0.7112)
		(drill 0.3556)
		(layers "F.Cu" "B.Cu")
		(net "HDD10_LED_B")
	)
	(segment
		(start 43.3705 -429.5648)
		(end 44.3992 -428.5361)
		(width 0.111252)
		(layer "F.Cu")
		(net "HDD10_LED_G")
	)
	(segment
		(start 44.3992 -426.3136)
		(end 44.3992 -428.1932)
		(width 0.111252)
		(layer "F.Cu")
		(net "HDD10_LED_G")
	)
	(segment
		(start 44.3992 -428.5361)
		(end 44.3992 -428.1932)
		(width 0.111252)
		(layer "F.Cu")
		(net "HDD10_LED_G")
	)
	(segment
		(start 41.0718 -429.1457)
		(end 41.4909 -429.5648)
		(width 0.111252)
		(layer "F.Cu")
		(net "HDD10_LED_G")
	)
	(segment
		(start 44.3992 -424.3832)
		(end 44.3992 -426.3136)
		(width 0.111252)
		(layer "F.Cu")
		(net "HDD10_LED_G")
	)
	(segment
		(start 41.4909 -429.5648)
		(end 43.3705 -429.5648)
		(width 0.111252)
		(layer "F.Cu")
		(net "HDD10_LED_G")
	)
	(via
		(at 44.3992 -424.3832)
		(size 0.7112)
		(drill 0.3556)
		(layers "F.Cu" "B.Cu")
		(net "HDD10_LED_G")
	)
	(segment
		(start 195.292472 -187.930028)
		(end 194.156584 -187.930028)
		(width 0.111252)
		(layer "F.Cu")
		(net "SW_HDD3_G")
	)
	(segment
		(start 195.58 -187.6425)
		(end 195.292472 -187.930028)
		(width 0.111252)
		(layer "F.Cu")
		(net "SW_HDD3_G")
	)
	(segment
		(start 195.58 -187.2615)
		(end 195.58 -187.6425)
		(width 0.111252)
		(layer "F.Cu")
		(net "SW_HDD3_G")
	)
	(segment
		(start 196.469 -186.436)
		(end 196.4055 -186.436)
		(width 0.111252)
		(layer "F.Cu")
		(net "SW_HDD3_G")
	)
	(segment
		(start 196.723 -186.182)
		(end 196.469 -186.436)
		(width 0.111252)
		(layer "F.Cu")
		(net "SW_HDD3_G")
	)
	(segment
		(start 196.4055 -186.436)
		(end 195.58 -187.2615)
		(width 0.111252)
		(layer "F.Cu")
		(net "SW_HDD3_G")
	)
	(via
		(at 196.723 -186.182)
		(size 0.7112)
		(drill 0.3556)
		(layers "F.Cu" "B.Cu")
		(net "SW_HDD3_G")
	)
	(segment
		(start 195.453 -289.1536)
		(end 195.58 -289.0266)
		(width 0.111252)
		(layer "F.Cu")
		(net "SW_HDD2_G")
	)
	(segment
		(start 194.106546 -290.5887)
		(end 194.8688 -290.5887)
		(width 0.111252)
		(layer "F.Cu")
		(net "SW_HDD2_G")
	)
	(segment
		(start 195.453 -290.0045)
		(end 195.453 -289.1536)
		(width 0.111252)
		(layer "F.Cu")
		(net "SW_HDD2_G")
	)
	(segment
		(start 194.8688 -290.5887)
		(end 195.453 -290.0045)
		(width 0.111252)
		(layer "F.Cu")
		(net "SW_HDD2_G")
	)
	(via
		(at 195.58 -289.0266)
		(size 0.7112)
		(drill 0.3556)
		(layers "F.Cu" "B.Cu")
		(net "SW_HDD2_G")
	)
	(segment
		(start 61.96965 -479.5393)
		(end 61.9252 -479.5774)
		(width 0.111252)
		(layer "F.Cu")
		(net "HDD5_LED_B")
	)
	(segment
		(start 61.468 -479.5393)
		(end 61.96965 -479.5393)
		(width 0.111252)
		(layer "F.Cu")
		(net "HDD5_LED_B")
	)
	(segment
		(start 59.9694 -481.0379)
		(end 61.468 -479.5393)
		(width 0.111252)
		(layer "F.Cu")
		(net "HDD5_LED_B")
	)
	(segment
		(start 61.9252 -481.287836)
		(end 62.293246 -481.655882)
		(width 0.111252)
		(layer "F.Cu")
		(net "HDD5_LED_B")
	)
	(segment
		(start 61.9252 -479.5774)
		(end 61.9252 -481.287836)
		(width 0.111252)
		(layer "F.Cu")
		(net "HDD5_LED_B")
	)
	(via
		(at 62.293246 -481.655882)
		(size 0.7112)
		(drill 0.3556)
		(layers "F.Cu" "B.Cu")
		(net "HDD5_LED_B")
	)
	(segment
		(start 55.3974 -477.6216)
		(end 57.277 -477.6216)
		(width 0.111252)
		(layer "F.Cu")
		(net "HDD5_LED_G")
	)
	(segment
		(start 58.674 -477.6343)
		(end 60.9854 -477.6343)
		(width 0.111252)
		(layer "F.Cu")
		(net "HDD5_LED_G")
	)
	(segment
		(start 58.6613 -477.6216)
		(end 58.674 -477.6343)
		(width 0.111252)
		(layer "F.Cu")
		(net "HDD5_LED_G")
	)
	(segment
		(start 57.277 -477.6216)
		(end 58.6613 -477.6216)
		(width 0.111252)
		(layer "F.Cu")
		(net "HDD5_LED_G")
	)
	(segment
		(start 60.9854 -477.6343)
		(end 60.9854 -476.25)
		(width 0.111252)
		(layer "F.Cu")
		(net "HDD5_LED_G")
	)
	(via
		(at 60.9854 -476.25)
		(size 0.7112)
		(drill 0.3556)
		(layers "F.Cu" "B.Cu")
		(net "HDD5_LED_G")
	)
	(segment
		(start 39.299134 -453.874886)
		(end 39.299134 -454.125838)
		(width 0.508)
		(layer "F.Cu")
		(net "P5VB_HDD5_LED")
	)
	(segment
		(start 42.0624 -454.7108)
		(end 42.1386 -454.787)
		(width 0.508)
		(layer "F.Cu")
		(net "P5VB_HDD5_LED")
	)
	(segment
		(start 58.3692 -476.4278)
		(end 57.82564 -476.97136)
		(width 0.4064)
		(layer "F.Cu")
		(net "P5VB_HDD5_LED")
	)
	(segment
		(start 39.299134 -454.125838)
		(end 39.884096 -454.7108)
		(width 0.508)
		(layer "F.Cu")
		(net "P5VB_HDD5_LED")
	)
	(segment
		(start 39.884096 -454.7108)
		(end 42.0624 -454.7108)
		(width 0.508)
		(layer "F.Cu")
		(net "P5VB_HDD5_LED")
	)
	(segment
		(start 57.82564 -476.97136)
		(end 57.277 -476.97136)
		(width 0.4064)
		(layer "F.Cu")
		(net "P5VB_HDD5_LED")
	)
	(via
		(at 58.3692 -475.488)
		(size 0.7112)
		(drill 0.3556)
		(layers "F.Cu" "B.Cu")
		(net "P5VB_HDD5_LED")
	)
	(via
		(at 42.1386 -454.787)
		(size 0.5588)
		(drill 0.3048)
		(layers "F.Cu" "B.Cu")
		(net "P5VB_HDD5_LED")
	)
	(via
		(at 58.3692 -476.4278)
		(size 0.5588)
		(drill 0.3048)
		(layers "F.Cu" "B.Cu")
		(net "P5VB_HDD5_LED")
	)
	(segment
		(start 58.3692 -475.488)
		(end 58.3692 -476.4278)
		(width 0.508)
		(layer "B.Cu")
		(net "P5VB_HDD5_LED")
	)
	(segment
		(start 42.1386 -454.787)
		(end 42.1894 -454.7362)
		(width 0.508)
		(layer "In2.Cu")
		(net "P5VB_HDD5_LED")
	)
	(segment
		(start 57.8739 -476.4278)
		(end 58.3692 -476.4278)
		(width 0.508)
		(layer "In2.Cu")
		(net "P5VB_HDD5_LED")
	)
	(segment
		(start 46.80331 -454.7362)
		(end 56.0197 -463.95259)
		(width 0.508)
		(layer "In2.Cu")
		(net "P5VB_HDD5_LED")
	)
	(segment
		(start 56.0197 -463.95259)
		(end 56.0197 -474.5736)
		(width 0.508)
		(layer "In2.Cu")
		(net "P5VB_HDD5_LED")
	)
	(segment
		(start 42.1894 -454.7362)
		(end 46.80331 -454.7362)
		(width 0.508)
		(layer "In2.Cu")
		(net "P5VB_HDD5_LED")
	)
	(segment
		(start 56.0197 -474.5736)
		(end 57.8739 -476.4278)
		(width 0.508)
		(layer "In2.Cu")
		(net "P5VB_HDD5_LED")
	)
	(segment
		(start 196.650356 -391.580624)
		(end 196.088 -392.14298)
		(width 0.111252)
		(layer "F.Cu")
		(net "SW_HDD1_G")
	)
	(segment
		(start 196.088 -392.14298)
		(end 196.088 -392.6205)
		(width 0.111252)
		(layer "F.Cu")
		(net "SW_HDD1_G")
	)
	(segment
		(start 195.822316 -392.886184)
		(end 194.697858 -392.886184)
		(width 0.111252)
		(layer "F.Cu")
		(net "SW_HDD1_G")
	)
	(segment
		(start 196.088 -392.6205)
		(end 195.822316 -392.886184)
		(width 0.111252)
		(layer "F.Cu")
		(net "SW_HDD1_G")
	)
	(via
		(at 196.650356 -391.580624)
		(size 0.7112)
		(drill 0.3556)
		(layers "F.Cu" "B.Cu")
		(net "SW_HDD1_G")
	)
	(segment
		(start 194.872356 -495.862102)
		(end 194.186556 -495.862102)
		(width 0.111252)
		(layer "F.Cu")
		(net "SW_HDD0_G")
	)
	(segment
		(start 196.4055 -494.284)
		(end 195.58 -495.1095)
		(width 0.111252)
		(layer "F.Cu")
		(net "SW_HDD0_G")
	)
	(segment
		(start 195.0974 -495.6048)
		(end 195.0974 -495.637058)
		(width 0.111252)
		(layer "F.Cu")
		(net "SW_HDD0_G")
	)
	(segment
		(start 195.58 -495.1222)
		(end 195.0974 -495.6048)
		(width 0.111252)
		(layer "F.Cu")
		(net "SW_HDD0_G")
	)
	(segment
		(start 195.58 -495.1095)
		(end 195.58 -495.1222)
		(width 0.111252)
		(layer "F.Cu")
		(net "SW_HDD0_G")
	)
	(segment
		(start 196.4055 -493.776)
		(end 196.4055 -494.284)
		(width 0.111252)
		(layer "F.Cu")
		(net "SW_HDD0_G")
	)
	(segment
		(start 195.0974 -495.637058)
		(end 194.872356 -495.862102)
		(width 0.111252)
		(layer "F.Cu")
		(net "SW_HDD0_G")
	)
	(via
		(at 196.4055 -493.776)
		(size 0.7112)
		(drill 0.3556)
		(layers "F.Cu" "B.Cu")
		(net "SW_HDD0_G")
	)
	(segment
		(start 249.8979 -419.379908)
		(end 255.474978 -419.379908)
		(width 0.111252)
		(layer "F.Cu")
		(net "SD_LATCH_RELEASE")
	)
	(segment
		(start 19.5834 -211.709)
		(end 18.7452 -212.5472)
		(width 0.111252)
		(layer "F.Cu")
		(net "SD_LATCH_RELEASE")
	)
	(segment
		(start 12.436094 -216.776808)
		(end 7.657592 -216.776808)
		(width 0.111252)
		(layer "F.Cu")
		(net "SD_LATCH_RELEASE")
	)
	(segment
		(start 249.4407 -418.922708)
		(end 249.8979 -419.379908)
		(width 0.111252)
		(layer "F.Cu")
		(net "SD_LATCH_RELEASE")
	)
	(segment
		(start 16.665702 -212.5472)
		(end 12.436094 -216.776808)
		(width 0.111252)
		(layer "F.Cu")
		(net "SD_LATCH_RELEASE")
	)
	(segment
		(start 24.892 -211.709)
		(end 19.5834 -211.709)
		(width 0.111252)
		(layer "F.Cu")
		(net "SD_LATCH_RELEASE")
	)
	(segment
		(start 18.7452 -212.5472)
		(end 16.665702 -212.5472)
		(width 0.111252)
		(layer "F.Cu")
		(net "SD_LATCH_RELEASE")
	)
	(segment
		(start 7.657592 -216.776808)
		(end 7.5184 -216.916)
		(width 0.111252)
		(layer "F.Cu")
		(net "SD_LATCH_RELEASE")
	)
	(via
		(at 249.4407 -418.922708)
		(size 0.5588)
		(drill 0.3048)
		(layers "F.Cu" "B.Cu")
		(net "SD_LATCH_RELEASE")
	)
	(via
		(at 6.146546 -387.0198)
		(size 0.5588)
		(drill 0.3048)
		(layers "F.Cu" "B.Cu")
		(net "SD_LATCH_RELEASE")
	)
	(via
		(at 24.928576 -389.714486)
		(size 0.5588)
		(drill 0.3048)
		(layers "F.Cu" "B.Cu")
		(net "SD_LATCH_RELEASE")
	)
	(via
		(at 6.908546 -137.0584)
		(size 0.5588)
		(drill 0.3048)
		(layers "F.Cu" "B.Cu")
		(net "SD_LATCH_RELEASE")
	)
	(via
		(at 24.892 -211.709)
		(size 0.5588)
		(drill 0.3048)
		(layers "F.Cu" "B.Cu")
		(net "SD_LATCH_RELEASE")
	)
	(via
		(at 7.5184 -216.916)
		(size 0.5588)
		(drill 0.3048)
		(layers "F.Cu" "B.Cu")
		(net "SD_LATCH_RELEASE")
	)
	(via
		(at 15.24 -390.017)
		(size 0.7112)
		(drill 0.3556)
		(layers "F.Cu" "B.Cu")
		(net "SD_LATCH_RELEASE")
	)
	(segment
		(start 15.24 -390.017)
		(end 15.212314 -390.044686)
		(width 0.111252)
		(layer "B.Cu")
		(net "SD_LATCH_RELEASE")
	)
	(segment
		(start 6.908546 -137.0584)
		(end 6.350508 -136.500362)
		(width 0.111252)
		(layer "B.Cu")
		(net "SD_LATCH_RELEASE")
	)
	(segment
		(start 15.542514 -389.714486)
		(end 15.24 -390.017)
		(width 0.111252)
		(layer "B.Cu")
		(net "SD_LATCH_RELEASE")
	)
	(segment
		(start 8.457692 -388.386574)
		(end 7.51332 -388.386574)
		(width 0.111252)
		(layer "B.Cu")
		(net "SD_LATCH_RELEASE")
	)
	(segment
		(start 5.627116 -386.50037)
		(end 2.81305 -386.50037)
		(width 0.111252)
		(layer "B.Cu")
		(net "SD_LATCH_RELEASE")
	)
	(segment
		(start 7.51332 -388.386574)
		(end 6.146546 -387.0198)
		(width 0.111252)
		(layer "B.Cu")
		(net "SD_LATCH_RELEASE")
	)
	(segment
		(start 9.397492 -389.326374)
		(end 8.457692 -388.386574)
		(width 0.111252)
		(layer "B.Cu")
		(net "SD_LATCH_RELEASE")
	)
	(segment
		(start 2.81305 -386.50037)
		(end 2.811526 -386.498846)
		(width 0.111252)
		(layer "B.Cu")
		(net "SD_LATCH_RELEASE")
	)
	(segment
		(start 15.212314 -390.044686)
		(end 10.688828 -390.044686)
		(width 0.111252)
		(layer "B.Cu")
		(net "SD_LATCH_RELEASE")
	)
	(segment
		(start 24.928576 -389.714486)
		(end 15.542514 -389.714486)
		(width 0.111252)
		(layer "B.Cu")
		(net "SD_LATCH_RELEASE")
	)
	(segment
		(start 10.688828 -390.044686)
		(end 9.970516 -389.326374)
		(width 0.111252)
		(layer "B.Cu")
		(net "SD_LATCH_RELEASE")
	)
	(segment
		(start 6.350508 -136.500362)
		(end 2.81305 -136.500362)
		(width 0.111252)
		(layer "B.Cu")
		(net "SD_LATCH_RELEASE")
	)
	(segment
		(start 2.81305 -136.500362)
		(end 2.811526 -136.498838)
		(width 0.111252)
		(layer "B.Cu")
		(net "SD_LATCH_RELEASE")
	)
	(segment
		(start 9.970516 -389.326374)
		(end 9.397492 -389.326374)
		(width 0.111252)
		(layer "B.Cu")
		(net "SD_LATCH_RELEASE")
	)
	(segment
		(start 6.146546 -387.0198)
		(end 5.627116 -386.50037)
		(width 0.111252)
		(layer "B.Cu")
		(net "SD_LATCH_RELEASE")
	)
	(segment
		(start 247.59285 -413.872426)
		(end 248.52757 -414.807146)
		(width 0.14605)
		(layer "In2.Cu")
		(net "SD_LATCH_RELEASE")
	)
	(segment
		(start 27.1399 -396.783814)
		(end 32.222186 -401.8661)
		(width 0.14605)
		(layer "In2.Cu")
		(net "SD_LATCH_RELEASE")
	)
	(segment
		(start 24.928576 -389.714486)
		(end 24.834596 -389.808466)
		(width 0.14605)
		(layer "In2.Cu")
		(net "SD_LATCH_RELEASE")
	)
	(segment
		(start 24.892 -211.709)
		(end 24.27605 -211.09305)
		(width 0.14605)
		(layer "In2.Cu")
		(net "SD_LATCH_RELEASE")
	)
	(segment
		(start 236.818932 -403.098)
		(end 247.59285 -413.872426)
		(width 0.14605)
		(layer "In2.Cu")
		(net "SD_LATCH_RELEASE")
	)
	(segment
		(start 24.27605 -211.09305)
		(end 24.27605 -164.565838)
		(width 0.14605)
		(layer "In2.Cu")
		(net "SD_LATCH_RELEASE")
	)
	(segment
		(start 13.3223 -149.181312)
		(end 13.3223 -140.5509)
		(width 0.14605)
		(layer "In2.Cu")
		(net "SD_LATCH_RELEASE")
	)
	(segment
		(start 248.52757 -414.807146)
		(end 248.52757 -416.07867)
		(width 0.14605)
		(layer "In2.Cu")
		(net "SD_LATCH_RELEASE")
	)
	(segment
		(start 12.655296 -152.945084)
		(end 12.655296 -149.848316)
		(width 0.14605)
		(layer "In2.Cu")
		(net "SD_LATCH_RELEASE")
	)
	(segment
		(start 86.5886 -403.098)
		(end 236.818932 -403.098)
		(width 0.14605)
		(layer "In2.Cu")
		(net "SD_LATCH_RELEASE")
	)
	(segment
		(start 9.8298 -137.0584)
		(end 6.908546 -137.0584)
		(width 0.14605)
		(layer "In2.Cu")
		(net "SD_LATCH_RELEASE")
	)
	(segment
		(start 32.222186 -401.8661)
		(end 85.3567 -401.8661)
		(width 0.14605)
		(layer "In2.Cu")
		(net "SD_LATCH_RELEASE")
	)
	(segment
		(start 248.52757 -416.07867)
		(end 249.4407 -416.9918)
		(width 0.14605)
		(layer "In2.Cu")
		(net "SD_LATCH_RELEASE")
	)
	(segment
		(start 24.27605 -164.565838)
		(end 12.655296 -152.945084)
		(width 0.14605)
		(layer "In2.Cu")
		(net "SD_LATCH_RELEASE")
	)
	(segment
		(start 85.3567 -401.8661)
		(end 86.5886 -403.098)
		(width 0.14605)
		(layer "In2.Cu")
		(net "SD_LATCH_RELEASE")
	)
	(segment
		(start 24.834596 -392.994896)
		(end 27.1399 -395.3002)
		(width 0.14605)
		(layer "In2.Cu")
		(net "SD_LATCH_RELEASE")
	)
	(segment
		(start 24.834596 -389.808466)
		(end 24.834596 -392.994896)
		(width 0.14605)
		(layer "In2.Cu")
		(net "SD_LATCH_RELEASE")
	)
	(segment
		(start 13.3223 -140.5509)
		(end 9.8298 -137.0584)
		(width 0.14605)
		(layer "In2.Cu")
		(net "SD_LATCH_RELEASE")
	)
	(segment
		(start 12.655296 -149.848316)
		(end 13.3223 -149.181312)
		(width 0.14605)
		(layer "In2.Cu")
		(net "SD_LATCH_RELEASE")
	)
	(segment
		(start 27.1399 -395.3002)
		(end 27.1399 -396.783814)
		(width 0.14605)
		(layer "In2.Cu")
		(net "SD_LATCH_RELEASE")
	)
	(segment
		(start 249.4407 -416.9918)
		(end 249.4407 -418.922708)
		(width 0.14605)
		(layer "In2.Cu")
		(net "SD_LATCH_RELEASE")
	)
	(segment
		(start 6.6548 -386.511546)
		(end 6.146546 -387.0198)
		(width 0.14605)
		(layer "In5.Cu")
		(net "SD_LATCH_RELEASE")
	)
	(segment
		(start 9.937496 -382.111504)
		(end 9.4488 -382.6002)
		(width 0.14605)
		(layer "In5.Cu")
		(net "SD_LATCH_RELEASE")
	)
	(segment
		(start 9.4488 -382.6002)
		(end 7.4676 -382.6002)
		(width 0.14605)
		(layer "In5.Cu")
		(net "SD_LATCH_RELEASE")
	)
	(segment
		(start 7.4676 -382.6002)
		(end 6.6548 -383.413)
		(width 0.14605)
		(layer "In5.Cu")
		(net "SD_LATCH_RELEASE")
	)
	(segment
		(start 7.5184 -216.916)
		(end 9.937496 -219.335096)
		(width 0.14605)
		(layer "In5.Cu")
		(net "SD_LATCH_RELEASE")
	)
	(segment
		(start 9.937496 -219.335096)
		(end 9.937496 -382.111504)
		(width 0.14605)
		(layer "In5.Cu")
		(net "SD_LATCH_RELEASE")
	)
	(segment
		(start 6.6548 -383.413)
		(end 6.6548 -386.511546)
		(width 0.14605)
		(layer "In5.Cu")
		(net "SD_LATCH_RELEASE")
	)
	(segment
		(start 16.744696 -211.715096)
		(end 16.299434 -211.269834)
		(width 0.111252)
		(layer "F.Cu")
		(net "TRAY_ID")
	)
	(segment
		(start 25.0698 -208.9277)
		(end 20.777708 -208.9277)
		(width 0.111252)
		(layer "F.Cu")
		(net "TRAY_ID")
	)
	(segment
		(start 20.098004 -209.614262)
		(end 17.99717 -211.715096)
		(width 0.111252)
		(layer "F.Cu")
		(net "TRAY_ID")
	)
	(segment
		(start 249.1232 -421.5384)
		(end 249.504708 -421.919908)
		(width 0.111252)
		(layer "F.Cu")
		(net "TRAY_ID")
	)
	(segment
		(start 249.504708 -421.919908)
		(end 255.474978 -421.919908)
		(width 0.111252)
		(layer "F.Cu")
		(net "TRAY_ID")
	)
	(segment
		(start 20.777708 -208.9277)
		(end 20.098004 -209.607404)
		(width 0.111252)
		(layer "F.Cu")
		(net "TRAY_ID")
	)
	(segment
		(start 16.299434 -211.269834)
		(end 12.130024 -211.269834)
		(width 0.111252)
		(layer "F.Cu")
		(net "TRAY_ID")
	)
	(segment
		(start 17.99717 -211.715096)
		(end 16.744696 -211.715096)
		(width 0.111252)
		(layer "F.Cu")
		(net "TRAY_ID")
	)
	(segment
		(start 12.130024 -211.269834)
		(end 11.830304 -211.569554)
		(width 0.111252)
		(layer "F.Cu")
		(net "TRAY_ID")
	)
	(segment
		(start 20.098004 -209.607404)
		(end 20.098004 -209.614262)
		(width 0.111252)
		(layer "F.Cu")
		(net "TRAY_ID")
	)
	(via
		(at 21.7424 -396.621)
		(size 0.5588)
		(drill 0.3048)
		(layers "F.Cu" "B.Cu")
		(net "TRAY_ID")
	)
	(via
		(at 18.542 -139.3698)
		(size 0.7112)
		(drill 0.3556)
		(layers "F.Cu" "B.Cu")
		(net "TRAY_ID")
	)
	(via
		(at 18.415 -138.43)
		(size 0.5588)
		(drill 0.3048)
		(layers "F.Cu" "B.Cu")
		(net "TRAY_ID")
	)
	(via
		(at 17.4752 -115.3922)
		(size 0.7112)
		(drill 0.3556)
		(layers "F.Cu" "B.Cu")
		(net "TRAY_ID")
	)
	(via
		(at 11.830304 -211.569554)
		(size 0.5588)
		(drill 0.3048)
		(layers "F.Cu" "B.Cu")
		(net "TRAY_ID")
	)
	(via
		(at 19.304 -363.4994)
		(size 0.5588)
		(drill 0.3048)
		(layers "F.Cu" "B.Cu")
		(net "TRAY_ID")
	)
	(via
		(at 7.3406 -106.1212)
		(size 0.5588)
		(drill 0.3048)
		(layers "F.Cu" "B.Cu")
		(net "TRAY_ID")
	)
	(via
		(at 249.1232 -421.5384)
		(size 0.5588)
		(drill 0.3048)
		(layers "F.Cu" "B.Cu")
		(net "TRAY_ID")
	)
	(via
		(at 25.0698 -208.9277)
		(size 0.5588)
		(drill 0.3048)
		(layers "F.Cu" "B.Cu")
		(net "TRAY_ID")
	)
	(via
		(at 16.51 -115.697)
		(size 0.5588)
		(drill 0.3048)
		(layers "F.Cu" "B.Cu")
		(net "TRAY_ID")
	)
	(segment
		(start 15.7226 -359.918)
		(end 7.463028 -359.918)
		(width 0.111252)
		(layer "B.Cu")
		(net "TRAY_ID")
	)
	(segment
		(start 2.81305 -107.500166)
		(end 2.811526 -107.498642)
		(width 0.111252)
		(layer "B.Cu")
		(net "TRAY_ID")
	)
	(segment
		(start 18.415 -138.43)
		(end 18.542 -138.557)
		(width 0.111252)
		(layer "B.Cu")
		(net "TRAY_ID")
	)
	(segment
		(start 2.81305 -357.500174)
		(end 2.811526 -357.49865)
		(width 0.111252)
		(layer "B.Cu")
		(net "TRAY_ID")
	)
	(segment
		(start 6.731 -358.6988)
		(end 5.532374 -357.500174)
		(width 0.111252)
		(layer "B.Cu")
		(net "TRAY_ID")
	)
	(segment
		(start 7.1628 -106.1212)
		(end 5.783834 -107.500166)
		(width 0.111252)
		(layer "B.Cu")
		(net "TRAY_ID")
	)
	(segment
		(start 18.542 -138.557)
		(end 18.542 -139.3698)
		(width 0.111252)
		(layer "B.Cu")
		(net "TRAY_ID")
	)
	(segment
		(start 19.304 -363.4994)
		(end 15.7226 -359.918)
		(width 0.111252)
		(layer "B.Cu")
		(net "TRAY_ID")
	)
	(segment
		(start 16.51 -115.697)
		(end 17.1704 -115.697)
		(width 0.111252)
		(layer "B.Cu")
		(net "TRAY_ID")
	)
	(segment
		(start 7.463028 -359.918)
		(end 6.731 -359.185972)
		(width 0.111252)
		(layer "B.Cu")
		(net "TRAY_ID")
	)
	(segment
		(start 5.532374 -357.500174)
		(end 2.81305 -357.500174)
		(width 0.111252)
		(layer "B.Cu")
		(net "TRAY_ID")
	)
	(segment
		(start 6.731 -359.185972)
		(end 6.731 -358.6988)
		(width 0.111252)
		(layer "B.Cu")
		(net "TRAY_ID")
	)
	(segment
		(start 5.783834 -107.500166)
		(end 2.81305 -107.500166)
		(width 0.111252)
		(layer "B.Cu")
		(net "TRAY_ID")
	)
	(segment
		(start 17.1704 -115.697)
		(end 17.4752 -115.3922)
		(width 0.111252)
		(layer "B.Cu")
		(net "TRAY_ID")
	)
	(segment
		(start 7.3406 -106.1212)
		(end 7.1628 -106.1212)
		(width 0.111252)
		(layer "B.Cu")
		(net "TRAY_ID")
	)
	(segment
		(start 236.445044 -403.9997)
		(end 236.476794 -404.03145)
		(width 0.14605)
		(layer "In2.Cu")
		(net "TRAY_ID")
	)
	(segment
		(start 248.35485 -420.77005)
		(end 249.1232 -421.5384)
		(width 0.14605)
		(layer "In2.Cu")
		(net "TRAY_ID")
	)
	(segment
		(start 239.856264 -407.411174)
		(end 244.345714 -411.900878)
		(width 0.14605)
		(layer "In2.Cu")
		(net "TRAY_ID")
	)
	(segment
		(start 86.214712 -403.9997)
		(end 236.445044 -403.9997)
		(width 0.14605)
		(layer "In2.Cu")
		(net "TRAY_ID")
	)
	(segment
		(start 247.62587 -415.181288)
		(end 247.62587 -416.682682)
		(width 0.14605)
		(layer "In2.Cu")
		(net "TRAY_ID")
	)
	(segment
		(start 27.8892 -402.7678)
		(end 84.982812 -402.7678)
		(width 0.14605)
		(layer "In2.Cu")
		(net "TRAY_ID")
	)
	(segment
		(start 25.31745 -164.969444)
		(end 25.31745 -208.008982)
		(width 0.14605)
		(layer "In2.Cu")
		(net "TRAY_ID")
	)
	(segment
		(start 18.2118 -138.2268)
		(end 16.891 -138.2268)
		(width 0.14605)
		(layer "In2.Cu")
		(net "TRAY_ID")
	)
	(segment
		(start 9.525 -108.3056)
		(end 9.525 -110.5154)
		(width 0.14605)
		(layer "In2.Cu")
		(net "TRAY_ID")
	)
	(segment
		(start 13.77315 -149.368256)
		(end 13.106146 -150.03526)
		(width 0.14605)
		(layer "In2.Cu")
		(net "TRAY_ID")
	)
	(segment
		(start 247.62587 -416.682682)
		(end 248.35485 -417.411662)
		(width 0.14605)
		(layer "In2.Cu")
		(net "TRAY_ID")
	)
	(segment
		(start 13.77315 -141.34465)
		(end 13.77315 -149.368256)
		(width 0.14605)
		(layer "In2.Cu")
		(net "TRAY_ID")
	)
	(segment
		(start 18.415 -138.43)
		(end 18.2118 -138.2268)
		(width 0.14605)
		(layer "In2.Cu")
		(net "TRAY_ID")
	)
	(segment
		(start 21.7424 -396.621)
		(end 27.8892 -402.7678)
		(width 0.14605)
		(layer "In2.Cu")
		(net "TRAY_ID")
	)
	(segment
		(start 16.891 -138.2268)
		(end 13.77315 -141.34465)
		(width 0.14605)
		(layer "In2.Cu")
		(net "TRAY_ID")
	)
	(segment
		(start 13.106146 -152.75814)
		(end 25.31745 -164.969444)
		(width 0.14605)
		(layer "In2.Cu")
		(net "TRAY_ID")
	)
	(segment
		(start 25.31745 -208.008982)
		(end 25.0698 -208.256632)
		(width 0.14605)
		(layer "In2.Cu")
		(net "TRAY_ID")
	)
	(segment
		(start 236.476794 -404.03145)
		(end 239.856264 -407.411174)
		(width 0.14605)
		(layer "In2.Cu")
		(net "TRAY_ID")
	)
	(segment
		(start 13.106146 -150.03526)
		(end 13.106146 -152.75814)
		(width 0.14605)
		(layer "In2.Cu")
		(net "TRAY_ID")
	)
	(segment
		(start 25.0698 -208.256632)
		(end 25.0698 -208.9277)
		(width 0.14605)
		(layer "In2.Cu")
		(net "TRAY_ID")
	)
	(segment
		(start 14.7066 -115.697)
		(end 16.51 -115.697)
		(width 0.14605)
		(layer "In2.Cu")
		(net "TRAY_ID")
	)
	(segment
		(start 7.3406 -106.1212)
		(end 9.525 -108.3056)
		(width 0.14605)
		(layer "In2.Cu")
		(net "TRAY_ID")
	)
	(segment
		(start 9.525 -110.5154)
		(end 14.7066 -115.697)
		(width 0.14605)
		(layer "In2.Cu")
		(net "TRAY_ID")
	)
	(segment
		(start 244.345714 -411.900878)
		(end 247.62587 -415.181288)
		(width 0.14605)
		(layer "In2.Cu")
		(net "TRAY_ID")
	)
	(segment
		(start 248.35485 -417.411662)
		(end 248.35485 -420.77005)
		(width 0.14605)
		(layer "In2.Cu")
		(net "TRAY_ID")
	)
	(segment
		(start 84.982812 -402.7678)
		(end 86.214712 -403.9997)
		(width 0.14605)
		(layer "In2.Cu")
		(net "TRAY_ID")
	)
	(segment
		(start 22.15642 -138.43)
		(end 18.415 -138.43)
		(width 0.14605)
		(layer "In5.Cu")
		(net "TRAY_ID")
	)
	(segment
		(start 24.329898 -136.256522)
		(end 22.15642 -138.43)
		(width 0.14605)
		(layer "In5.Cu")
		(net "TRAY_ID")
	)
	(segment
		(start 21.7424 -395.096746)
		(end 21.7424 -396.621)
		(width 0.14605)
		(layer "In5.Cu")
		(net "TRAY_ID")
	)
	(segment
		(start 16.51 -115.697)
		(end 15.662402 -116.544598)
		(width 0.14605)
		(layer "In5.Cu")
		(net "TRAY_ID")
	)
	(segment
		(start 14.020546 -358.152954)
		(end 19.304 -363.436408)
		(width 0.14605)
		(layer "In5.Cu")
		(net "TRAY_ID")
	)
	(segment
		(start 11.800332 -214.708994)
		(end 14.020546 -216.929208)
		(width 0.14605)
		(layer "In5.Cu")
		(net "TRAY_ID")
	)
	(segment
		(start 19.304 -363.4994)
		(end 14.077696 -368.725704)
		(width 0.14605)
		(layer "In5.Cu")
		(net "TRAY_ID")
	)
	(segment
		(start 14.077696 -368.725704)
		(end 14.077696 -387.432042)
		(width 0.14605)
		(layer "In5.Cu")
		(net "TRAY_ID")
	)
	(segment
		(start 14.077696 -387.432042)
		(end 21.7424 -395.096746)
		(width 0.14605)
		(layer "In5.Cu")
		(net "TRAY_ID")
	)
	(segment
		(start 11.830304 -211.569554)
		(end 11.800332 -211.599526)
		(width 0.14605)
		(layer "In5.Cu")
		(net "TRAY_ID")
	)
	(segment
		(start 19.304 -363.436408)
		(end 19.304 -363.4994)
		(width 0.14605)
		(layer "In5.Cu")
		(net "TRAY_ID")
	)
	(segment
		(start 15.662402 -125.000766)
		(end 24.329898 -133.668262)
		(width 0.14605)
		(layer "In5.Cu")
		(net "TRAY_ID")
	)
	(segment
		(start 14.020546 -216.929208)
		(end 14.020546 -358.152954)
		(width 0.14605)
		(layer "In5.Cu")
		(net "TRAY_ID")
	)
	(segment
		(start 15.662402 -116.544598)
		(end 15.662402 -125.000766)
		(width 0.14605)
		(layer "In5.Cu")
		(net "TRAY_ID")
	)
	(segment
		(start 24.329898 -133.668262)
		(end 24.329898 -136.256522)
		(width 0.14605)
		(layer "In5.Cu")
		(net "TRAY_ID")
	)
	(segment
		(start 11.800332 -211.599526)
		(end 11.800332 -214.708994)
		(width 0.14605)
		(layer "In5.Cu")
		(net "TRAY_ID")
	)
	(segment
		(start 13.3096 -104.1146)
		(end 12.6873 -104.7369)
		(width 0.111252)
		(layer "F.Cu")
		(net "DPB_HW_REV")
	)
	(segment
		(start 3.192526 -354.498402)
		(end 7.705598 -354.498402)
		(width 0.111252)
		(layer "F.Cu")
		(net "DPB_HW_REV")
	)
	(segment
		(start 3.19405 -104.499918)
		(end 3.192526 -104.498394)
		(width 0.111252)
		(layer "F.Cu")
		(net "DPB_HW_REV")
	)
	(segment
		(start 10.8458 -104.7369)
		(end 9.1821 -104.7369)
		(width 0.111252)
		(layer "F.Cu")
		(net "DPB_HW_REV")
	)
	(segment
		(start 8.818118 -104.499918)
		(end 3.19405 -104.499918)
		(width 0.111252)
		(layer "F.Cu")
		(net "DPB_HW_REV")
	)
	(segment
		(start 9.1186 -104.8004)
		(end 8.818118 -104.499918)
		(width 0.111252)
		(layer "F.Cu")
		(net "DPB_HW_REV")
	)
	(segment
		(start 13.39342 -103.24338)
		(end 13.3096 -103.3272)
		(width 0.111252)
		(layer "F.Cu")
		(net "DPB_HW_REV")
	)
	(segment
		(start 11.8872 -104.7369)
		(end 10.8458 -104.7369)
		(width 0.111252)
		(layer "F.Cu")
		(net "DPB_HW_REV")
	)
	(segment
		(start 7.705598 -354.498402)
		(end 7.747 -354.457)
		(width 0.111252)
		(layer "F.Cu")
		(net "DPB_HW_REV")
	)
	(segment
		(start 13.3096 -103.3272)
		(end 13.3096 -104.1146)
		(width 0.111252)
		(layer "F.Cu")
		(net "DPB_HW_REV")
	)
	(segment
		(start 9.1821 -104.7369)
		(end 9.1186 -104.8004)
		(width 0.111252)
		(layer "F.Cu")
		(net "DPB_HW_REV")
	)
	(segment
		(start 12.6873 -104.7369)
		(end 11.8872 -104.7369)
		(width 0.111252)
		(layer "F.Cu")
		(net "DPB_HW_REV")
	)
	(via
		(at 13.39342 -103.24338)
		(size 0.7112)
		(drill 0.3556)
		(layers "F.Cu" "B.Cu")
		(net "DPB_HW_REV")
	)
	(via
		(at 9.1186 -104.8004)
		(size 0.5588)
		(drill 0.3048)
		(layers "F.Cu" "B.Cu")
		(net "DPB_HW_REV")
	)
	(via
		(at 7.747 -354.457)
		(size 0.5588)
		(drill 0.3048)
		(layers "F.Cu" "B.Cu")
		(net "DPB_HW_REV")
	)
	(segment
		(start 6.200394 -196.440806)
		(end 7.464298 -195.176902)
		(width 0.14605)
		(layer "In5.Cu")
		(net "DPB_HW_REV")
	)
	(segment
		(start 5.311648 -144.275048)
		(end 5.311648 -132.475478)
		(width 0.14605)
		(layer "In5.Cu")
		(net "DPB_HW_REV")
	)
	(segment
		(start 6.315964 -145.279364)
		(end 5.311648 -144.275048)
		(width 0.14605)
		(layer "In5.Cu")
		(net "DPB_HW_REV")
	)
	(segment
		(start 4.97205 -260.4262)
		(end 9.486646 -255.911604)
		(width 0.14605)
		(layer "In5.Cu")
		(net "DPB_HW_REV")
	)
	(segment
		(start 7.747 -354.457)
		(end 8.42518 -354.457)
		(width 0.14605)
		(layer "In5.Cu")
		(net "DPB_HW_REV")
	)
	(segment
		(start 9.486646 -353.395788)
		(end 9.486646 -267.2334)
		(width 0.14605)
		(layer "In5.Cu")
		(net "DPB_HW_REV")
	)
	(segment
		(start 6.315964 -153.915364)
		(end 6.315964 -145.279364)
		(width 0.14605)
		(layer "In5.Cu")
		(net "DPB_HW_REV")
	)
	(segment
		(start 8.353298 -165.041072)
		(end 8.337296 -165.02507)
		(width 0.14605)
		(layer "In5.Cu")
		(net "DPB_HW_REV")
	)
	(segment
		(start 9.486646 -267.2334)
		(end 4.97205 -262.718804)
		(width 0.14605)
		(layer "In5.Cu")
		(net "DPB_HW_REV")
	)
	(segment
		(start 7.464298 -195.176902)
		(end 7.464298 -178.417474)
		(width 0.14605)
		(layer "In5.Cu")
		(net "DPB_HW_REV")
	)
	(segment
		(start 7.972552 -129.814574)
		(end 7.972552 -105.946448)
		(width 0.14605)
		(layer "In5.Cu")
		(net "DPB_HW_REV")
	)
	(segment
		(start 8.353298 -177.528474)
		(end 8.353298 -165.041072)
		(width 0.14605)
		(layer "In5.Cu")
		(net "DPB_HW_REV")
	)
	(segment
		(start 9.486646 -219.798646)
		(end 6.858 -217.17)
		(width 0.14605)
		(layer "In5.Cu")
		(net "DPB_HW_REV")
	)
	(segment
		(start 8.42518 -354.457)
		(end 8.8646 -354.01758)
		(width 0.14605)
		(layer "In5.Cu")
		(net "DPB_HW_REV")
	)
	(segment
		(start 8.8646 -354.01758)
		(end 9.486646 -353.395788)
		(width 0.14605)
		(layer "In5.Cu")
		(net "DPB_HW_REV")
	)
	(segment
		(start 8.337296 -165.02507)
		(end 8.337296 -155.936696)
		(width 0.14605)
		(layer "In5.Cu")
		(net "DPB_HW_REV")
	)
	(segment
		(start 6.200394 -207.221328)
		(end 6.200394 -196.440806)
		(width 0.14605)
		(layer "In5.Cu")
		(net "DPB_HW_REV")
	)
	(segment
		(start 5.311648 -132.475478)
		(end 7.972552 -129.814574)
		(width 0.14605)
		(layer "In5.Cu")
		(net "DPB_HW_REV")
	)
	(segment
		(start 4.97205 -262.718804)
		(end 4.97205 -260.4262)
		(width 0.14605)
		(layer "In5.Cu")
		(net "DPB_HW_REV")
	)
	(segment
		(start 7.972552 -105.946448)
		(end 9.1186 -104.8004)
		(width 0.14605)
		(layer "In5.Cu")
		(net "DPB_HW_REV")
	)
	(segment
		(start 9.486646 -255.911604)
		(end 9.486646 -219.798646)
		(width 0.14605)
		(layer "In5.Cu")
		(net "DPB_HW_REV")
	)
	(segment
		(start 6.858 -217.17)
		(end 6.858 -207.878934)
		(width 0.14605)
		(layer "In5.Cu")
		(net "DPB_HW_REV")
	)
	(segment
		(start 8.337296 -155.936696)
		(end 6.315964 -153.915364)
		(width 0.14605)
		(layer "In5.Cu")
		(net "DPB_HW_REV")
	)
	(segment
		(start 6.858 -207.878934)
		(end 6.200394 -207.221328)
		(width 0.14605)
		(layer "In5.Cu")
		(net "DPB_HW_REV")
	)
	(segment
		(start 7.464298 -178.417474)
		(end 8.353298 -177.528474)
		(width 0.14605)
		(layer "In5.Cu")
		(net "DPB_HW_REV")
	)
	(segment
		(start 221.355412 -41.636696)
		(end 220.345 -41.636696)
		(width 0.508)
		(layer "F.Cu")
		(net "P5VA_HDD4_LED")
	)
	(segment
		(start 208.8134 -67.29476)
		(end 208.8134 -66.4718)
		(width 0.4064)
		(layer "F.Cu")
		(net "P5VA_HDD4_LED")
	)
	(via
		(at 208.8388 -65.532)
		(size 0.7112)
		(drill 0.3556)
		(layers "F.Cu" "B.Cu")
		(net "P5VA_HDD4_LED")
	)
	(via
		(at 220.345 -41.636696)
		(size 0.5588)
		(drill 0.3048)
		(layers "F.Cu" "B.Cu")
		(net "P5VA_HDD4_LED")
	)
	(via
		(at 208.8134 -66.4718)
		(size 0.5588)
		(drill 0.3048)
		(layers "F.Cu" "B.Cu")
		(net "P5VA_HDD4_LED")
	)
	(segment
		(start 208.8388 -66.4464)
		(end 208.8388 -65.532)
		(width 0.508)
		(layer "B.Cu")
		(net "P5VA_HDD4_LED")
	)
	(segment
		(start 208.8134 -66.4718)
		(end 208.8388 -66.4464)
		(width 0.508)
		(layer "B.Cu")
		(net "P5VA_HDD4_LED")
	)
	(segment
		(start 208.8134 -63.119)
		(end 218.1098 -53.8226)
		(width 0.508)
		(layer "In2.Cu")
		(net "P5VA_HDD4_LED")
	)
	(segment
		(start 218.1098 -53.8226)
		(end 218.1098 -43.871896)
		(width 0.508)
		(layer "In2.Cu")
		(net "P5VA_HDD4_LED")
	)
	(segment
		(start 208.8134 -66.4718)
		(end 208.8134 -63.119)
		(width 0.508)
		(layer "In2.Cu")
		(net "P5VA_HDD4_LED")
	)
	(segment
		(start 218.1098 -43.871896)
		(end 220.345 -41.636696)
		(width 0.508)
		(layer "In2.Cu")
		(net "P5VA_HDD4_LED")
	)
	(segment
		(start 19.368516 -214.853774)
		(end 19.373342 -214.8586)
		(width 0.111252)
		(layer "F.Cu")
		(net "FCB_HW_REV")
	)
	(segment
		(start 6.35 -217.9574)
		(end 6.858 -217.4494)
		(width 0.111252)
		(layer "F.Cu")
		(net "FCB_HW_REV")
	)
	(segment
		(start 6.633464 -95.499936)
		(end 3.19405 -95.499936)
		(width 0.111252)
		(layer "F.Cu")
		(net "FCB_HW_REV")
	)
	(segment
		(start 7.1374 -94.996)
		(end 6.633464 -95.499936)
		(width 0.111252)
		(layer "F.Cu")
		(net "FCB_HW_REV")
	)
	(segment
		(start 18.985484 -214.853774)
		(end 19.368516 -214.853774)
		(width 0.111252)
		(layer "F.Cu")
		(net "FCB_HW_REV")
	)
	(segment
		(start 12.3698 -217.4494)
		(end 14.9606 -214.8586)
		(width 0.111252)
		(layer "F.Cu")
		(net "FCB_HW_REV")
	)
	(segment
		(start 22.8092 -214.8586)
		(end 23.6474 -214.0204)
		(width 0.111252)
		(layer "F.Cu")
		(net "FCB_HW_REV")
	)
	(segment
		(start 23.6474 -214.0204)
		(end 25.0698 -214.0204)
		(width 0.111252)
		(layer "F.Cu")
		(net "FCB_HW_REV")
	)
	(segment
		(start 3.19405 -345.499944)
		(end 3.192526 -345.49842)
		(width 0.111252)
		(layer "F.Cu")
		(net "FCB_HW_REV")
	)
	(segment
		(start 250.088908 -420.649908)
		(end 255.474978 -420.649908)
		(width 0.111252)
		(layer "F.Cu")
		(net "FCB_HW_REV")
	)
	(segment
		(start 19.373342 -214.8586)
		(end 22.8092 -214.8586)
		(width 0.111252)
		(layer "F.Cu")
		(net "FCB_HW_REV")
	)
	(segment
		(start 6.858 -217.4494)
		(end 12.3698 -217.4494)
		(width 0.111252)
		(layer "F.Cu")
		(net "FCB_HW_REV")
	)
	(segment
		(start 6.35 -344.866468)
		(end 5.716524 -345.499944)
		(width 0.111252)
		(layer "F.Cu")
		(net "FCB_HW_REV")
	)
	(segment
		(start 18.980658 -214.8586)
		(end 18.985484 -214.853774)
		(width 0.111252)
		(layer "F.Cu")
		(net "FCB_HW_REV")
	)
	(segment
		(start 3.19405 -95.499936)
		(end 3.192526 -95.498412)
		(width 0.111252)
		(layer "F.Cu")
		(net "FCB_HW_REV")
	)
	(segment
		(start 14.9606 -214.8586)
		(end 18.980658 -214.8586)
		(width 0.111252)
		(layer "F.Cu")
		(net "FCB_HW_REV")
	)
	(segment
		(start 249.301 -419.862)
		(end 250.088908 -420.649908)
		(width 0.111252)
		(layer "F.Cu")
		(net "FCB_HW_REV")
	)
	(segment
		(start 5.716524 -345.499944)
		(end 3.19405 -345.499944)
		(width 0.111252)
		(layer "F.Cu")
		(net "FCB_HW_REV")
	)
	(via
		(at 22.700742 -396.512542)
		(size 0.5588)
		(drill 0.3048)
		(layers "F.Cu" "B.Cu")
		(net "FCB_HW_REV")
	)
	(via
		(at 6.35 -344.866468)
		(size 0.5588)
		(drill 0.3048)
		(layers "F.Cu" "B.Cu")
		(net "FCB_HW_REV")
	)
	(via
		(at 15.5956 -114.9604)
		(size 0.5588)
		(drill 0.3048)
		(layers "F.Cu" "B.Cu")
		(net "FCB_HW_REV")
	)
	(via
		(at 6.35 -217.9574)
		(size 0.5588)
		(drill 0.3048)
		(layers "F.Cu" "B.Cu")
		(net "FCB_HW_REV")
	)
	(via
		(at 17.272 -138.811)
		(size 0.5588)
		(drill 0.3048)
		(layers "F.Cu" "B.Cu")
		(net "FCB_HW_REV")
	)
	(via
		(at 249.301 -419.862)
		(size 0.5588)
		(drill 0.3048)
		(layers "F.Cu" "B.Cu")
		(net "FCB_HW_REV")
	)
	(via
		(at 16.891 -137.922)
		(size 0.7112)
		(drill 0.3556)
		(layers "F.Cu" "B.Cu")
		(net "FCB_HW_REV")
	)
	(via
		(at 25.0698 -214.0204)
		(size 0.5588)
		(drill 0.3048)
		(layers "F.Cu" "B.Cu")
		(net "FCB_HW_REV")
	)
	(via
		(at 19.750532 -344.866468)
		(size 0.5588)
		(drill 0.3048)
		(layers "F.Cu" "B.Cu")
		(net "FCB_HW_REV")
	)
	(via
		(at 7.1374 -94.996)
		(size 0.5588)
		(drill 0.3048)
		(layers "F.Cu" "B.Cu")
		(net "FCB_HW_REV")
	)
	(via
		(at 14.5542 -114.9858)
		(size 0.7112)
		(drill 0.3556)
		(layers "F.Cu" "B.Cu")
		(net "FCB_HW_REV")
	)
	(segment
		(start 15.5702 -114.9858)
		(end 14.5542 -114.9858)
		(width 0.111252)
		(layer "B.Cu")
		(net "FCB_HW_REV")
	)
	(segment
		(start 17.272 -138.811)
		(end 16.891 -138.43)
		(width 0.111252)
		(layer "B.Cu")
		(net "FCB_HW_REV")
	)
	(segment
		(start 15.5956 -114.9604)
		(end 15.5702 -114.9858)
		(width 0.111252)
		(layer "B.Cu")
		(net "FCB_HW_REV")
	)
	(segment
		(start 19.750532 -344.866468)
		(end 6.35 -344.866468)
		(width 0.111252)
		(layer "B.Cu")
		(net "FCB_HW_REV")
	)
	(segment
		(start 16.891 -138.43)
		(end 16.891 -137.922)
		(width 0.111252)
		(layer "B.Cu")
		(net "FCB_HW_REV")
	)
	(segment
		(start 13.556996 -152.571196)
		(end 13.556996 -150.222204)
		(width 0.14605)
		(layer "In2.Cu")
		(net "FCB_HW_REV")
	)
	(segment
		(start 247.932448 -414.849818)
		(end 248.07672 -414.994344)
		(width 0.14605)
		(layer "In2.Cu")
		(net "FCB_HW_REV")
	)
	(segment
		(start 248.07672 -416.44697)
		(end 248.85015 -417.2204)
		(width 0.14605)
		(layer "In2.Cu")
		(net "FCB_HW_REV")
	)
	(segment
		(start 14.224 -141.859)
		(end 17.272 -138.811)
		(width 0.14605)
		(layer "In2.Cu")
		(net "FCB_HW_REV")
	)
	(segment
		(start 243.709698 -410.627068)
		(end 247.932448 -414.849818)
		(width 0.14605)
		(layer "In2.Cu")
		(net "FCB_HW_REV")
	)
	(segment
		(start 10.033 -97.8916)
		(end 10.033 -109.3978)
		(width 0.14605)
		(layer "In2.Cu")
		(net "FCB_HW_REV")
	)
	(segment
		(start 248.07672 -414.994344)
		(end 248.07672 -416.44697)
		(width 0.14605)
		(layer "In2.Cu")
		(net "FCB_HW_REV")
	)
	(segment
		(start 85.169756 -402.31695)
		(end 86.401656 -403.54885)
		(width 0.14605)
		(layer "In2.Cu")
		(net "FCB_HW_REV")
	)
	(segment
		(start 10.033 -109.3978)
		(end 15.5956 -114.9604)
		(width 0.14605)
		(layer "In2.Cu")
		(net "FCB_HW_REV")
	)
	(segment
		(start 22.700742 -396.512542)
		(end 28.50515 -402.31695)
		(width 0.14605)
		(layer "In2.Cu")
		(net "FCB_HW_REV")
	)
	(segment
		(start 7.1374 -94.996)
		(end 10.033 -97.8916)
		(width 0.14605)
		(layer "In2.Cu")
		(net "FCB_HW_REV")
	)
	(segment
		(start 248.85015 -419.41115)
		(end 249.301 -419.862)
		(width 0.14605)
		(layer "In2.Cu")
		(net "FCB_HW_REV")
	)
	(segment
		(start 25.7683 -164.7825)
		(end 13.556996 -152.571196)
		(width 0.14605)
		(layer "In2.Cu")
		(net "FCB_HW_REV")
	)
	(segment
		(start 25.0698 -214.0204)
		(end 25.7683 -213.3219)
		(width 0.14605)
		(layer "In2.Cu")
		(net "FCB_HW_REV")
	)
	(segment
		(start 236.631988 -403.54885)
		(end 243.709698 -410.627068)
		(width 0.14605)
		(layer "In2.Cu")
		(net "FCB_HW_REV")
	)
	(segment
		(start 14.224 -149.5552)
		(end 14.224 -141.859)
		(width 0.14605)
		(layer "In2.Cu")
		(net "FCB_HW_REV")
	)
	(segment
		(start 28.50515 -402.31695)
		(end 85.169756 -402.31695)
		(width 0.14605)
		(layer "In2.Cu")
		(net "FCB_HW_REV")
	)
	(segment
		(start 13.556996 -150.222204)
		(end 14.224 -149.5552)
		(width 0.14605)
		(layer "In2.Cu")
		(net "FCB_HW_REV")
	)
	(segment
		(start 86.401656 -403.54885)
		(end 236.631988 -403.54885)
		(width 0.14605)
		(layer "In2.Cu")
		(net "FCB_HW_REV")
	)
	(segment
		(start 248.85015 -417.2204)
		(end 248.85015 -419.41115)
		(width 0.14605)
		(layer "In2.Cu")
		(net "FCB_HW_REV")
	)
	(segment
		(start 25.7683 -213.3219)
		(end 25.7683 -164.7825)
		(width 0.14605)
		(layer "In2.Cu")
		(net "FCB_HW_REV")
	)
	(segment
		(start 22.19325 -394.990574)
		(end 22.700742 -396.512542)
		(width 0.14605)
		(layer "In5.Cu")
		(net "FCB_HW_REV")
	)
	(segment
		(start 18.702274 -128.683004)
		(end 23.879048 -133.859778)
		(width 0.14605)
		(layer "In5.Cu")
		(net "FCB_HW_REV")
	)
	(segment
		(start 15.99184 -357.72852)
		(end 16.007842 -357.744522)
		(width 0.14605)
		(layer "In5.Cu")
		(net "FCB_HW_REV")
	)
	(segment
		(start 23.879048 -133.859778)
		(end 23.879048 -136.069578)
		(width 0.14605)
		(layer "In5.Cu")
		(net "FCB_HW_REV")
	)
	(segment
		(start 16.007842 -357.744522)
		(end 16.007842 -359.502456)
		(width 0.14605)
		(layer "In5.Cu")
		(net "FCB_HW_REV")
	)
	(segment
		(start 22.026626 -137.922)
		(end 18.161 -137.922)
		(width 0.14605)
		(layer "In5.Cu")
		(net "FCB_HW_REV")
	)
	(segment
		(start 6.35 -217.9574)
		(end 6.574028 -217.9574)
		(width 0.14605)
		(layer "In5.Cu")
		(net "FCB_HW_REV")
	)
	(segment
		(start 15.211552 -125.221746)
		(end 18.67281 -128.683004)
		(width 0.14605)
		(layer "In5.Cu")
		(net "FCB_HW_REV")
	)
	(segment
		(start 18.161 -137.922)
		(end 17.272 -138.811)
		(width 0.14605)
		(layer "In5.Cu")
		(net "FCB_HW_REV")
	)
	(segment
		(start 16.007842 -348.609158)
		(end 16.007842 -356.915466)
		(width 0.14605)
		(layer "In5.Cu")
		(net "FCB_HW_REV")
	)
	(segment
		(start 14.528546 -386.606542)
		(end 14.979904 -387.696456)
		(width 0.14605)
		(layer "In5.Cu")
		(net "FCB_HW_REV")
	)
	(segment
		(start 19.750532 -344.866468)
		(end 16.007842 -348.609158)
		(width 0.14605)
		(layer "In5.Cu")
		(net "FCB_HW_REV")
	)
	(segment
		(start 6.574028 -217.9574)
		(end 7.362698 -218.74607)
		(width 0.14605)
		(layer "In5.Cu")
		(net "FCB_HW_REV")
	)
	(segment
		(start 7.362952 -343.853516)
		(end 6.35 -344.866468)
		(width 0.14605)
		(layer "In5.Cu")
		(net "FCB_HW_REV")
	)
	(segment
		(start 19.783552 -363.883448)
		(end 14.528546 -369.138454)
		(width 0.14605)
		(layer "In5.Cu")
		(net "FCB_HW_REV")
	)
	(segment
		(start 15.5956 -114.9604)
		(end 15.211552 -115.344448)
		(width 0.14605)
		(layer "In5.Cu")
		(net "FCB_HW_REV")
	)
	(segment
		(start 7.362698 -218.74607)
		(end 7.362698 -222.365824)
		(width 0.14605)
		(layer "In5.Cu")
		(net "FCB_HW_REV")
	)
	(segment
		(start 19.75485 -363.249464)
		(end 19.75485 -363.27207)
		(width 0.14605)
		(layer "In5.Cu")
		(net "FCB_HW_REV")
	)
	(segment
		(start 15.99184 -356.931468)
		(end 15.99184 -357.72852)
		(width 0.14605)
		(layer "In5.Cu")
		(net "FCB_HW_REV")
	)
	(segment
		(start 16.007842 -359.502456)
		(end 19.75485 -363.249464)
		(width 0.14605)
		(layer "In5.Cu")
		(net "FCB_HW_REV")
	)
	(segment
		(start 16.007842 -356.915466)
		(end 15.99184 -356.931468)
		(width 0.14605)
		(layer "In5.Cu")
		(net "FCB_HW_REV")
	)
	(segment
		(start 4.5212 -260.1722)
		(end 4.5212 -262.905748)
		(width 0.14605)
		(layer "In5.Cu")
		(net "FCB_HW_REV")
	)
	(segment
		(start 23.879048 -136.069578)
		(end 22.026626 -137.922)
		(width 0.14605)
		(layer "In5.Cu")
		(net "FCB_HW_REV")
	)
	(segment
		(start 5.514594 -224.213928)
		(end 5.514594 -259.178806)
		(width 0.14605)
		(layer "In5.Cu")
		(net "FCB_HW_REV")
	)
	(segment
		(start 7.362698 -222.365824)
		(end 5.514594 -224.213928)
		(width 0.14605)
		(layer "In5.Cu")
		(net "FCB_HW_REV")
	)
	(segment
		(start 19.783552 -363.300772)
		(end 19.783552 -363.883448)
		(width 0.14605)
		(layer "In5.Cu")
		(net "FCB_HW_REV")
	)
	(segment
		(start 22.19325 -394.909802)
		(end 22.19325 -394.990574)
		(width 0.14605)
		(layer "In5.Cu")
		(net "FCB_HW_REV")
	)
	(segment
		(start 4.5212 -262.905748)
		(end 7.362952 -265.7475)
		(width 0.14605)
		(layer "In5.Cu")
		(net "FCB_HW_REV")
	)
	(segment
		(start 15.211552 -115.344448)
		(end 15.211552 -125.221746)
		(width 0.14605)
		(layer "In5.Cu")
		(net "FCB_HW_REV")
	)
	(segment
		(start 14.528546 -369.138454)
		(end 14.528546 -386.606542)
		(width 0.14605)
		(layer "In5.Cu")
		(net "FCB_HW_REV")
	)
	(segment
		(start 5.514594 -259.178806)
		(end 4.5212 -260.1722)
		(width 0.14605)
		(layer "In5.Cu")
		(net "FCB_HW_REV")
	)
	(segment
		(start 18.67281 -128.683004)
		(end 18.702274 -128.683004)
		(width 0.14605)
		(layer "In5.Cu")
		(net "FCB_HW_REV")
	)
	(segment
		(start 14.979904 -387.696456)
		(end 22.19325 -394.909802)
		(width 0.14605)
		(layer "In5.Cu")
		(net "FCB_HW_REV")
	)
	(segment
		(start 7.362952 -265.7475)
		(end 7.362952 -343.853516)
		(width 0.14605)
		(layer "In5.Cu")
		(net "FCB_HW_REV")
	)
	(segment
		(start 19.75485 -363.27207)
		(end 19.783552 -363.300772)
		(width 0.14605)
		(layer "In5.Cu")
		(net "FCB_HW_REV")
	)
	(segment
		(start 208.8134 -67.945)
		(end 210.1723 -67.945)
		(width 0.111252)
		(layer "F.Cu")
		(net "HDD4_LED_G")
	)
	(segment
		(start 212.5218 -67.9323)
		(end 212.5218 -66.3194)
		(width 0.111252)
		(layer "F.Cu")
		(net "HDD4_LED_G")
	)
	(segment
		(start 212.5218 -66.3194)
		(end 212.4964 -66.294)
		(width 0.111252)
		(layer "F.Cu")
		(net "HDD4_LED_G")
	)
	(segment
		(start 210.185 -67.9323)
		(end 212.5218 -67.9323)
		(width 0.111252)
		(layer "F.Cu")
		(net "HDD4_LED_G")
	)
	(segment
		(start 210.1723 -67.945)
		(end 210.185 -67.9323)
		(width 0.111252)
		(layer "F.Cu")
		(net "HDD4_LED_G")
	)
	(segment
		(start 206.9338 -67.945)
		(end 208.8134 -67.945)
		(width 0.111252)
		(layer "F.Cu")
		(net "HDD4_LED_G")
	)
	(via
		(at 212.4964 -66.294)
		(size 0.7112)
		(drill 0.3556)
		(layers "F.Cu" "B.Cu")
		(net "HDD4_LED_G")
	)
	(segment
		(start 214.3506 -69.8373)
		(end 213.50605 -69.8373)
		(width 0.111252)
		(layer "F.Cu")
		(net "HDD4_LED_B")
	)
	(segment
		(start 213.50605 -69.8373)
		(end 213.50605 -69.55155)
		(width 0.111252)
		(layer "F.Cu")
		(net "HDD4_LED_B")
	)
	(segment
		(start 213.50605 -69.55155)
		(end 215.1888 -67.8688)
		(width 0.111252)
		(layer "F.Cu")
		(net "HDD4_LED_B")
	)
	(segment
		(start 214.8205 -70.3072)
		(end 214.3506 -69.8373)
		(width 0.111252)
		(layer "F.Cu")
		(net "HDD4_LED_B")
	)
	(via
		(at 215.1888 -67.8688)
		(size 0.7112)
		(drill 0.3556)
		(layers "F.Cu" "B.Cu")
		(net "HDD4_LED_B")
	)
	(segment
		(start 76.0984 -25.8826)
		(end 75.057 -25.8826)
		(width 0.111252)
		(layer "F.Cu")
		(net "HDD14_LED_B")
	)
	(segment
		(start 76.99375 -24.8031)
		(end 76.9112 -25.0698)
		(width 0.111252)
		(layer "F.Cu")
		(net "HDD14_LED_B")
	)
	(segment
		(start 76.9112 -25.0698)
		(end 76.0984 -25.8826)
		(width 0.111252)
		(layer "F.Cu")
		(net "HDD14_LED_B")
	)
	(segment
		(start 76.99375 -23.70455)
		(end 76.99375 -24.8031)
		(width 0.111252)
		(layer "F.Cu")
		(net "HDD14_LED_B")
	)
	(segment
		(start 77.6605 -23.0378)
		(end 76.99375 -23.70455)
		(width 0.111252)
		(layer "F.Cu")
		(net "HDD14_LED_B")
	)
	(via
		(at 75.057 -25.8826)
		(size 0.7112)
		(drill 0.3556)
		(layers "F.Cu" "B.Cu")
		(net "HDD14_LED_B")
	)
	(segment
		(start 77.978 -26.7081)
		(end 77.9907 -26.7208)
		(width 0.111252)
		(layer "F.Cu")
		(net "HDD14_LED_G")
	)
	(segment
		(start 79.6544 -24.511)
		(end 80.0608 -24.1046)
		(width 0.111252)
		(layer "F.Cu")
		(net "HDD14_LED_G")
	)
	(segment
		(start 78.0542 -26.8732)
		(end 77.978 -26.7081)
		(width 0.111252)
		(layer "F.Cu")
		(net "HDD14_LED_G")
	)
	(segment
		(start 80.0608 -24.1046)
		(end 80.6196 -24.1046)
		(width 0.111252)
		(layer "F.Cu")
		(net "HDD14_LED_G")
	)
	(segment
		(start 82.4992 -24.1046)
		(end 80.6196 -24.1046)
		(width 0.111252)
		(layer "F.Cu")
		(net "HDD14_LED_G")
	)
	(segment
		(start 78.0542 -28.7782)
		(end 78.0542 -26.8732)
		(width 0.111252)
		(layer "F.Cu")
		(net "HDD14_LED_G")
	)
	(segment
		(start 79.6544 -26.0731)
		(end 79.6544 -24.511)
		(width 0.111252)
		(layer "F.Cu")
		(net "HDD14_LED_G")
	)
	(segment
		(start 80.3021 -26.7208)
		(end 79.6544 -26.0731)
		(width 0.111252)
		(layer "F.Cu")
		(net "HDD14_LED_G")
	)
	(segment
		(start 77.9907 -26.7208)
		(end 80.3021 -26.7208)
		(width 0.111252)
		(layer "F.Cu")
		(net "HDD14_LED_G")
	)
	(via
		(at 78.0542 -28.7782)
		(size 0.7112)
		(drill 0.3556)
		(layers "F.Cu" "B.Cu")
		(net "HDD14_LED_G")
	)
	(segment
		(start 80.6196 -25.1206)
		(end 80.6196 -24.75484)
		(width 0.4064)
		(layer "F.Cu")
		(net "P5VC_HDD14_LED")
	)
	(segment
		(start 80.2132 -25.527)
		(end 80.6196 -25.1206)
		(width 0.4064)
		(layer "F.Cu")
		(net "P5VC_HDD14_LED")
	)
	(segment
		(start 20.637246 -51.9557)
		(end 24.2189 -51.9557)
		(width 0.508)
		(layer "F.Cu")
		(net "P5VC_HDD14_LED")
	)
	(via
		(at 24.2189 -51.9557)
		(size 0.5588)
		(drill 0.3048)
		(layers "F.Cu" "B.Cu")
		(net "P5VC_HDD14_LED")
	)
	(via
		(at 80.2132 -26.4668)
		(size 0.7112)
		(drill 0.3556)
		(layers "F.Cu" "B.Cu")
		(net "P5VC_HDD14_LED")
	)
	(via
		(at 80.2132 -25.527)
		(size 0.5588)
		(drill 0.3048)
		(layers "F.Cu" "B.Cu")
		(net "P5VC_HDD14_LED")
	)
	(segment
		(start 80.2132 -25.527)
		(end 80.2132 -26.4668)
		(width 0.508)
		(layer "B.Cu")
		(net "P5VC_HDD14_LED")
	)
	(segment
		(start 37.429694 -39.316406)
		(end 66.423794 -39.316406)
		(width 0.508)
		(layer "In2.Cu")
		(net "P5VC_HDD14_LED")
	)
	(segment
		(start 66.423794 -39.316406)
		(end 80.2132 -25.527)
		(width 0.508)
		(layer "In2.Cu")
		(net "P5VC_HDD14_LED")
	)
	(segment
		(start 24.2189 -51.9557)
		(end 24.7904 -51.9557)
		(width 0.508)
		(layer "In2.Cu")
		(net "P5VC_HDD14_LED")
	)
	(segment
		(start 24.7904 -51.9557)
		(end 37.429694 -39.316406)
		(width 0.508)
		(layer "In2.Cu")
		(net "P5VC_HDD14_LED")
	)
	(segment
		(start 208.4324 -169.55516)
		(end 208.4324 -168.7322)
		(width 0.4064)
		(layer "F.Cu")
		(net "P5VA_HDD3_LED")
	)
	(segment
		(start 224.345246 -144.9197)
		(end 223.4565 -144.9197)
		(width 0.508)
		(layer "F.Cu")
		(net "P5VA_HDD3_LED")
	)
	(via
		(at 208.5086 -169.672)
		(size 0.7112)
		(drill 0.3556)
		(layers "F.Cu" "B.Cu")
		(net "P5VA_HDD3_LED")
	)
	(via
		(at 223.4565 -144.9197)
		(size 0.5588)
		(drill 0.3048)
		(layers "F.Cu" "B.Cu")
		(net "P5VA_HDD3_LED")
	)
	(via
		(at 208.4324 -168.7322)
		(size 0.5588)
		(drill 0.3048)
		(layers "F.Cu" "B.Cu")
		(net "P5VA_HDD3_LED")
	)
	(segment
		(start 208.4324 -168.7322)
		(end 208.5086 -168.8084)
		(width 0.508)
		(layer "B.Cu")
		(net "P5VA_HDD3_LED")
	)
	(segment
		(start 208.5086 -168.8084)
		(end 208.5086 -169.672)
		(width 0.508)
		(layer "B.Cu")
		(net "P5VA_HDD3_LED")
	)
	(segment
		(start 208.4324 -159.47771)
		(end 208.4324 -168.7322)
		(width 0.508)
		(layer "In2.Cu")
		(net "P5VA_HDD3_LED")
	)
	(segment
		(start 223.4565 -144.9197)
		(end 222.99041 -144.9197)
		(width 0.508)
		(layer "In2.Cu")
		(net "P5VA_HDD3_LED")
	)
	(segment
		(start 222.99041 -144.9197)
		(end 208.4324 -159.47771)
		(width 0.508)
		(layer "In2.Cu")
		(net "P5VA_HDD3_LED")
	)
	(segment
		(start 12.7762 -177.5968)
		(end 12.76604 -177.586894)
		(width 0.09525)
		(layer "F.Cu")
		(net "SEB_BA_TX-")
	)
	(segment
		(start 6.004814 -174.190406)
		(end 5.484114 -174.190406)
		(width 0.09525)
		(layer "F.Cu")
		(net "SEB_BA_TX-")
	)
	(segment
		(start 32.8168 -274.5994)
		(end 32.770826 -274.553426)
		(width 0.09525)
		(layer "F.Cu")
		(net "SEB_BA_TX-")
	)
	(segment
		(start 5.319522 -174.258732)
		(end 5.2324 -174.3456)
		(width 0.09525)
		(layer "F.Cu")
		(net "SEB_BA_TX-")
	)
	(segment
		(start 9.245346 -176.834546)
		(end 7.022846 -174.612046)
		(width 0.09525)
		(layer "F.Cu")
		(net "SEB_BA_TX-")
	)
	(segment
		(start 7.022846 -174.612046)
		(end 7.0231 -174.612046)
		(width 0.09525)
		(layer "F.Cu")
		(net "SEB_BA_TX-")
	)
	(segment
		(start 31.687008 -274.535646)
		(end 31.603442 -274.618958)
		(width 0.09525)
		(layer "F.Cu")
		(net "SEB_BA_TX-")
	)
	(segment
		(start 4.976876 -174.498762)
		(end 3.192526 -174.498762)
		(width 0.09525)
		(layer "F.Cu")
		(net "SEB_BA_TX-")
	)
	(segment
		(start 12.1158 -177.3174)
		(end 10.41146 -177.3174)
		(width 0.09525)
		(layer "F.Cu")
		(net "SEB_BA_TX-")
	)
	(segment
		(start 9.2456 -176.834546)
		(end 9.245346 -176.834546)
		(width 0.09525)
		(layer "F.Cu")
		(net "SEB_BA_TX-")
	)
	(segment
		(start 4.9784 -174.500286)
		(end 4.976876 -174.498762)
		(width 0.09525)
		(layer "F.Cu")
		(net "SEB_BA_TX-")
	)
	(segment
		(start 5.2324 -174.3456)
		(end 5.148072 -174.430182)
		(width 0.09525)
		(layer "F.Cu")
		(net "SEB_BA_TX-")
	)
	(via
		(at 12.7762 -177.5968)
		(size 0.5588)
		(drill 0.3048)
		(layers "F.Cu" "B.Cu")
		(net "SEB_BA_TX-")
	)
	(via
		(at 31.603442 -274.618958)
		(size 0.5588)
		(drill 0.3048)
		(layers "F.Cu" "B.Cu")
		(net "SEB_BA_TX-")
	)
	(arc
		(start 7.0231 -174.612046)
		(mid 6.555906 -174.299906)
		(end 6.004814 -174.190406)
		(width 0.09525)
		(layer "F.Cu")
		(net "SEB_BA_TX-")
	)
	(arc
		(start 32.2072 -274.32)
		(mid 31.925661 -274.376095)
		(end 31.687008 -274.535646)
		(width 0.09525)
		(layer "F.Cu")
		(net "SEB_BA_TX-")
	)
	(arc
		(start 10.41146 -177.3174)
		(mid 9.780485 -177.191967)
		(end 9.2456 -176.834546)
		(width 0.09525)
		(layer "F.Cu")
		(net "SEB_BA_TX-")
	)
	(arc
		(start 5.484114 -174.190406)
		(mid 5.395034 -174.208219)
		(end 5.319522 -174.258732)
		(width 0.09525)
		(layer "F.Cu")
		(net "SEB_BA_TX-")
	)
	(arc
		(start 5.148072 -174.430182)
		(mid 5.070211 -174.482114)
		(end 4.9784 -174.500286)
		(width 0.09525)
		(layer "F.Cu")
		(net "SEB_BA_TX-")
	)
	(arc
		(start 32.770826 -274.553426)
		(mid 32.512232 -274.380639)
		(end 32.2072 -274.32)
		(width 0.09525)
		(layer "F.Cu")
		(net "SEB_BA_TX-")
	)
	(arc
		(start 12.76604 -177.586894)
		(mid 12.467722 -177.387472)
		(end 12.1158 -177.3174)
		(width 0.09525)
		(layer "F.Cu")
		(net "SEB_BA_TX-")
	)
	(segment
		(start 13.450062 -177.317654)
		(end 16.364966 -177.317654)
		(width 0.1143)
		(layer "In5.Cu")
		(net "SEB_BA_TX-")
	)
	(segment
		(start 21.2598 -240.578894)
		(end 21.2598 -246.761254)
		(width 0.1143)
		(layer "In5.Cu")
		(net "SEB_BA_TX-")
	)
	(segment
		(start 17.527016 -177.798984)
		(end 20.931632 -181.2036)
		(width 0.1143)
		(layer "In5.Cu")
		(net "SEB_BA_TX-")
	)
	(segment
		(start 20.1676 -236.962696)
		(end 20.1676 -238.734854)
		(width 0.1143)
		(layer "In5.Cu")
		(net "SEB_BA_TX-")
	)
	(segment
		(start 20.508468 -239.558068)
		(end 21.0693 -240.1189)
		(width 0.1143)
		(layer "In5.Cu")
		(net "SEB_BA_TX-")
	)
	(segment
		(start 25.0825 -268.6685)
		(end 30.482794 -274.068794)
		(width 0.1143)
		(layer "In5.Cu")
		(net "SEB_BA_TX-")
	)
	(segment
		(start 31.089346 -274.32)
		(end 31.0896 -274.32)
		(width 0.1143)
		(layer "In5.Cu")
		(net "SEB_BA_TX-")
	)
	(segment
		(start 20.9296 -235.6612)
		(end 20.5486 -236.0422)
		(width 0.1143)
		(layer "In5.Cu")
		(net "SEB_BA_TX-")
	)
	(segment
		(start 25.082754 -268.668246)
		(end 25.0825 -268.6685)
		(width 0.1143)
		(layer "In5.Cu")
		(net "SEB_BA_TX-")
	)
	(segment
		(start 24.7015 -251.458476)
		(end 24.7015 -267.748004)
		(width 0.1143)
		(layer "In5.Cu")
		(net "SEB_BA_TX-")
	)
	(segment
		(start 21.764752 -247.980454)
		(end 24.318722 -250.534424)
		(width 0.1143)
		(layer "In5.Cu")
		(net "SEB_BA_TX-")
	)
	(segment
		(start 21.310346 -182.118)
		(end 21.310346 -234.741974)
		(width 0.1143)
		(layer "In5.Cu")
		(net "SEB_BA_TX-")
	)
	(segment
		(start 20.5486 -236.0422)
		(end 20.548854 -236.042454)
		(width 0.1143)
		(layer "In5.Cu")
		(net "SEB_BA_TX-")
	)
	(segment
		(start 31.456376 -274.471892)
		(end 31.603442 -274.618958)
		(width 0.1143)
		(layer "In5.Cu")
		(net "SEB_BA_TX-")
	)
	(arc
		(start 24.7015 -267.748004)
		(mid 24.800586 -268.246051)
		(end 25.082754 -268.668246)
		(width 0.1143)
		(layer "In5.Cu")
		(net "SEB_BA_TX-")
	)
	(arc
		(start 20.548854 -236.042454)
		(mid 20.266688 -236.46465)
		(end 20.1676 -236.962696)
		(width 0.1143)
		(layer "In5.Cu")
		(net "SEB_BA_TX-")
	)
	(arc
		(start 20.931632 -181.2036)
		(mid 21.211899 -181.623145)
		(end 21.310346 -182.118)
		(width 0.1143)
		(layer "In5.Cu")
		(net "SEB_BA_TX-")
	)
	(arc
		(start 12.7762 -177.5968)
		(mid 13.085371 -177.390219)
		(end 13.450062 -177.317654)
		(width 0.1143)
		(layer "In5.Cu")
		(net "SEB_BA_TX-")
	)
	(arc
		(start 21.0693 -240.1189)
		(mid 21.210317 -240.329947)
		(end 21.2598 -240.578894)
		(width 0.1143)
		(layer "In5.Cu")
		(net "SEB_BA_TX-")
	)
	(arc
		(start 30.482794 -274.068794)
		(mid 30.761097 -274.254687)
		(end 31.089346 -274.32)
		(width 0.1143)
		(layer "In5.Cu")
		(net "SEB_BA_TX-")
	)
	(arc
		(start 16.364966 -177.317654)
		(mid 16.99386 -177.442749)
		(end 17.527016 -177.798984)
		(width 0.1143)
		(layer "In5.Cu")
		(net "SEB_BA_TX-")
	)
	(arc
		(start 21.310346 -234.741974)
		(mid 21.211392 -235.239452)
		(end 20.9296 -235.6612)
		(width 0.1143)
		(layer "In5.Cu")
		(net "SEB_BA_TX-")
	)
	(arc
		(start 20.1676 -238.734854)
		(mid 20.25618 -239.180357)
		(end 20.508468 -239.558068)
		(width 0.1143)
		(layer "In5.Cu")
		(net "SEB_BA_TX-")
	)
	(arc
		(start 24.318722 -250.534424)
		(mid 24.602002 -250.958383)
		(end 24.7015 -251.458476)
		(width 0.1143)
		(layer "In5.Cu")
		(net "SEB_BA_TX-")
	)
	(arc
		(start 21.2598 -246.761254)
		(mid 21.391028 -247.421073)
		(end 21.764752 -247.980454)
		(width 0.1143)
		(layer "In5.Cu")
		(net "SEB_BA_TX-")
	)
	(arc
		(start 31.0896 -274.32)
		(mid 31.288086 -274.359481)
		(end 31.456376 -274.471892)
		(width 0.1143)
		(layer "In5.Cu")
		(net "SEB_BA_TX-")
	)
	(segment
		(start 6.005068 -173.860206)
		(end 5.465826 -173.860206)
		(width 0.09525)
		(layer "F.Cu")
		(net "SEB_BA_TX+")
	)
	(segment
		(start 12.191492 -176.9872)
		(end 10.411206 -176.9872)
		(width 0.09525)
		(layer "F.Cu")
		(net "SEB_BA_TX+")
	)
	(segment
		(start 9.479026 -176.60112)
		(end 7.256526 -174.37862)
		(width 0.09525)
		(layer "F.Cu")
		(net "SEB_BA_TX+")
	)
	(segment
		(start 4.8006 -173.500288)
		(end 4.799076 -173.498764)
		(width 0.09525)
		(layer "F.Cu")
		(net "SEB_BA_TX+")
	)
	(segment
		(start 32.8168 -273.7104)
		(end 32.770826 -273.756374)
		(width 0.09525)
		(layer "F.Cu")
		(net "SEB_BA_TX+")
	)
	(segment
		(start 31.687008 -273.774154)
		(end 31.603442 -273.690842)
		(width 0.09525)
		(layer "F.Cu")
		(net "SEB_BA_TX+")
	)
	(segment
		(start 4.799076 -173.498764)
		(end 3.192526 -173.498764)
		(width 0.09525)
		(layer "F.Cu")
		(net "SEB_BA_TX+")
	)
	(segment
		(start 5.24256 -173.76775)
		(end 5.098542 -173.623732)
		(width 0.09525)
		(layer "F.Cu")
		(net "SEB_BA_TX+")
	)
	(via
		(at 31.603442 -273.690842)
		(size 0.5588)
		(drill 0.3048)
		(layers "F.Cu" "B.Cu")
		(net "SEB_BA_TX+")
	)
	(via
		(at 12.80414 -176.733454)
		(size 0.5588)
		(drill 0.3048)
		(layers "F.Cu" "B.Cu")
		(net "SEB_BA_TX+")
	)
	(arc
		(start 32.2072 -273.9898)
		(mid 31.925661 -273.933705)
		(end 31.687008 -273.774154)
		(width 0.09525)
		(layer "F.Cu")
		(net "SEB_BA_TX+")
	)
	(arc
		(start 5.465826 -173.860206)
		(mid 5.416313 -173.856178)
		(end 5.368036 -173.844458)
		(width 0.09525)
		(layer "F.Cu")
		(net "SEB_BA_TX+")
	)
	(arc
		(start 7.256526 -174.37862)
		(mid 6.682352 -173.994969)
		(end 6.005068 -173.860206)
		(width 0.09525)
		(layer "F.Cu")
		(net "SEB_BA_TX+")
	)
	(arc
		(start 5.368036 -173.844458)
		(mid 5.300758 -173.813527)
		(end 5.24256 -173.76775)
		(width 0.09525)
		(layer "F.Cu")
		(net "SEB_BA_TX+")
	)
	(arc
		(start 10.411206 -176.9872)
		(mid 9.90673 -176.886853)
		(end 9.479026 -176.60112)
		(width 0.09525)
		(layer "F.Cu")
		(net "SEB_BA_TX+")
	)
	(arc
		(start 12.80414 -176.733454)
		(mid 12.523055 -176.921269)
		(end 12.191492 -176.9872)
		(width 0.09525)
		(layer "F.Cu")
		(net "SEB_BA_TX+")
	)
	(arc
		(start 5.098542 -173.623732)
		(mid 4.961845 -173.532394)
		(end 4.8006 -173.500288)
		(width 0.09525)
		(layer "F.Cu")
		(net "SEB_BA_TX+")
	)
	(arc
		(start 32.770826 -273.756374)
		(mid 32.512232 -273.929161)
		(end 32.2072 -273.9898)
		(width 0.09525)
		(layer "F.Cu")
		(net "SEB_BA_TX+")
	)
	(segment
		(start 31.412942 -273.881088)
		(end 31.603442 -273.690842)
		(width 0.1143)
		(layer "In5.Cu")
		(net "SEB_BA_TX+")
	)
	(segment
		(start 21.615146 -182.117746)
		(end 21.615146 -234.74172)
		(width 0.1143)
		(layer "In5.Cu")
		(net "SEB_BA_TX+")
	)
	(segment
		(start 21.980398 -247.764808)
		(end 24.534368 -250.318778)
		(width 0.1143)
		(layer "In5.Cu")
		(net "SEB_BA_TX+")
	)
	(segment
		(start 20.4724 -236.962442)
		(end 20.4724 -238.7346)
		(width 0.1143)
		(layer "In5.Cu")
		(net "SEB_BA_TX+")
	)
	(segment
		(start 17.742662 -177.583338)
		(end 21.147278 -180.987954)
		(width 0.1143)
		(layer "In5.Cu")
		(net "SEB_BA_TX+")
	)
	(segment
		(start 17.742408 -177.583592)
		(end 17.742662 -177.583338)
		(width 0.1143)
		(layer "In5.Cu")
		(net "SEB_BA_TX+")
	)
	(segment
		(start 21.284946 -239.903254)
		(end 21.284692 -239.903508)
		(width 0.1143)
		(layer "In5.Cu")
		(net "SEB_BA_TX+")
	)
	(segment
		(start 21.145246 -235.876846)
		(end 20.764246 -236.257846)
		(width 0.1143)
		(layer "In5.Cu")
		(net "SEB_BA_TX+")
	)
	(segment
		(start 13.478764 -177.012854)
		(end 16.364712 -177.012854)
		(width 0.1143)
		(layer "In5.Cu")
		(net "SEB_BA_TX+")
	)
	(segment
		(start 20.724114 -239.342422)
		(end 21.284946 -239.903254)
		(width 0.1143)
		(layer "In5.Cu")
		(net "SEB_BA_TX+")
	)
	(segment
		(start 21.5646 -240.579148)
		(end 21.5646 -246.761)
		(width 0.1143)
		(layer "In5.Cu")
		(net "SEB_BA_TX+")
	)
	(segment
		(start 25.298146 -268.452854)
		(end 30.69844 -273.853148)
		(width 0.1143)
		(layer "In5.Cu")
		(net "SEB_BA_TX+")
	)
	(segment
		(start 25.0063 -251.458222)
		(end 25.0063 -267.748258)
		(width 0.1143)
		(layer "In5.Cu")
		(net "SEB_BA_TX+")
	)
	(segment
		(start 24.534368 -250.318778)
		(end 24.534114 -250.319032)
		(width 0.1143)
		(layer "In5.Cu")
		(net "SEB_BA_TX+")
	)
	(segment
		(start 21.144992 -235.876592)
		(end 21.145246 -235.876846)
		(width 0.1143)
		(layer "In5.Cu")
		(net "SEB_BA_TX+")
	)
	(arc
		(start 30.69844 -273.853148)
		(mid 30.877906 -273.973063)
		(end 31.0896 -274.0152)
		(width 0.1143)
		(layer "In5.Cu")
		(net "SEB_BA_TX+")
	)
	(arc
		(start 20.764246 -236.257846)
		(mid 20.548243 -236.581117)
		(end 20.4724 -236.962442)
		(width 0.1143)
		(layer "In5.Cu")
		(net "SEB_BA_TX+")
	)
	(arc
		(start 21.5646 -246.761)
		(mid 21.672661 -247.30426)
		(end 21.980398 -247.764808)
		(width 0.1143)
		(layer "In5.Cu")
		(net "SEB_BA_TX+")
	)
	(arc
		(start 21.615146 -234.74172)
		(mid 21.492956 -235.355923)
		(end 21.144992 -235.876592)
		(width 0.1143)
		(layer "In5.Cu")
		(net "SEB_BA_TX+")
	)
	(arc
		(start 31.0896 -274.0152)
		(mid 31.264606 -273.980295)
		(end 31.412942 -273.881088)
		(width 0.1143)
		(layer "In5.Cu")
		(net "SEB_BA_TX+")
	)
	(arc
		(start 12.80414 -176.733454)
		(mid 13.11366 -176.940269)
		(end 13.478764 -177.012854)
		(width 0.1143)
		(layer "In5.Cu")
		(net "SEB_BA_TX+")
	)
	(arc
		(start 21.284692 -239.903508)
		(mid 21.491872 -240.21348)
		(end 21.5646 -240.579148)
		(width 0.1143)
		(layer "In5.Cu")
		(net "SEB_BA_TX+")
	)
	(arc
		(start 24.534114 -250.319032)
		(mid 24.88346 -250.841681)
		(end 25.0063 -251.458222)
		(width 0.1143)
		(layer "In5.Cu")
		(net "SEB_BA_TX+")
	)
	(arc
		(start 20.4724 -238.7346)
		(mid 20.537813 -239.063544)
		(end 20.724114 -239.342422)
		(width 0.1143)
		(layer "In5.Cu")
		(net "SEB_BA_TX+")
	)
	(arc
		(start 16.364712 -177.012854)
		(mid 17.110331 -177.161185)
		(end 17.742408 -177.583592)
		(width 0.1143)
		(layer "In5.Cu")
		(net "SEB_BA_TX+")
	)
	(arc
		(start 21.147278 -180.987954)
		(mid 21.493523 -181.506335)
		(end 21.615146 -182.117746)
		(width 0.1143)
		(layer "In5.Cu")
		(net "SEB_BA_TX+")
	)
	(arc
		(start 25.0063 -267.748258)
		(mid 25.08215 -268.12958)
		(end 25.298146 -268.452854)
		(width 0.1143)
		(layer "In5.Cu")
		(net "SEB_BA_TX+")
	)
	(segment
		(start 214.4776 -172.1231)
		(end 214.4903 -172.1358)
		(width 0.111252)
		(layer "F.Cu")
		(net "HDD3_LED_B")
	)
	(segment
		(start 214.5538 -172.0723)
		(end 214.5538 -169.4688)
		(width 0.111252)
		(layer "F.Cu")
		(net "HDD3_LED_B")
	)
	(segment
		(start 214.5538 -169.4688)
		(end 214.9856 -169.037)
		(width 0.111252)
		(layer "F.Cu")
		(net "HDD3_LED_B")
	)
	(segment
		(start 213.15045 -172.1231)
		(end 214.4776 -172.1231)
		(width 0.111252)
		(layer "F.Cu")
		(net "HDD3_LED_B")
	)
	(segment
		(start 214.4903 -172.1358)
		(end 214.5538 -172.0723)
		(width 0.111252)
		(layer "F.Cu")
		(net "HDD3_LED_B")
	)
	(via
		(at 214.9856 -169.037)
		(size 0.7112)
		(drill 0.3556)
		(layers "F.Cu" "B.Cu")
		(net "HDD3_LED_B")
	)
	(segment
		(start 26.8478 -342.4174)
		(end 26.766012 -342.335612)
		(width 0.09525)
		(layer "F.Cu")
		(net "SEB_AB_RX-")
	)
	(segment
		(start 25.9969 -342.4301)
		(end 25.9969 -342.431116)
		(width 0.09525)
		(layer "F.Cu")
		(net "SEB_AB_RX-")
	)
	(via
		(at 25.9969 -342.431116)
		(size 0.5588)
		(drill 0.3048)
		(layers "F.Cu" "B.Cu")
		(net "SEB_AB_RX-")
	)
	(arc
		(start 26.766012 -342.335612)
		(mid 26.547157 -342.189378)
		(end 26.289 -342.138)
		(width 0.09525)
		(layer "F.Cu")
		(net "SEB_AB_RX-")
	)
	(arc
		(start 26.289 -342.138)
		(mid 26.082454 -342.223554)
		(end 25.9969 -342.4301)
		(width 0.09525)
		(layer "F.Cu")
		(net "SEB_AB_RX-")
	)
	(segment
		(start 24.9682 -343.535)
		(end 24.967946 -343.535)
		(width 0.09525)
		(layer "B.Cu")
		(net "SEB_AB_RX-")
	)
	(segment
		(start 21.22932 -343.895426)
		(end 15.83182 -338.497926)
		(width 0.09525)
		(layer "B.Cu")
		(net "SEB_AB_RX-")
	)
	(segment
		(start 6.714998 -172.165518)
		(end 5.46989 -172.165518)
		(width 0.09525)
		(layer "B.Cu")
		(net "SEB_AB_RX-")
	)
	(segment
		(start 8.236458 -173.082458)
		(end 7.747 -172.593)
		(width 0.09525)
		(layer "B.Cu")
		(net "SEB_AB_RX-")
	)
	(segment
		(start 15.762986 -221.472506)
		(end 15.76324 -221.47276)
		(width 0.09525)
		(layer "B.Cu")
		(net "SEB_AB_RX-")
	)
	(segment
		(start 24.9682 -342.69426)
		(end 24.9682 -343.535)
		(width 0.09525)
		(layer "B.Cu")
		(net "SEB_AB_RX-")
	)
	(segment
		(start 15.0368 -336.578448)
		(end 15.0368 -223.138746)
		(width 0.09525)
		(layer "B.Cu")
		(net "SEB_AB_RX-")
	)
	(segment
		(start 8.5598 -175.61052)
		(end 8.5598 -173.863)
		(width 0.09525)
		(layer "B.Cu")
		(net "SEB_AB_RX-")
	)
	(segment
		(start 15.76324 -221.47276)
		(end 23.594314 -213.641686)
		(width 0.09525)
		(layer "B.Cu")
		(net "SEB_AB_RX-")
	)
	(segment
		(start 4.661662 -172.50029)
		(end 4.660138 -172.498766)
		(width 0.09525)
		(layer "B.Cu")
		(net "SEB_AB_RX-")
	)
	(segment
		(start 21.229574 -343.895426)
		(end 21.22932 -343.895426)
		(width 0.09525)
		(layer "B.Cu")
		(net "SEB_AB_RX-")
	)
	(segment
		(start 4.660138 -172.498766)
		(end 2.811526 -172.498766)
		(width 0.09525)
		(layer "B.Cu")
		(net "SEB_AB_RX-")
	)
	(segment
		(start 23.70582 -191.431926)
		(end 9.03732 -176.763426)
		(width 0.09525)
		(layer "B.Cu")
		(net "SEB_AB_RX-")
	)
	(segment
		(start 9.03732 -176.763426)
		(end 9.037574 -176.763426)
		(width 0.09525)
		(layer "B.Cu")
		(net "SEB_AB_RX-")
	)
	(segment
		(start 24.001476 -344.5002)
		(end 22.689058 -344.5002)
		(width 0.09525)
		(layer "B.Cu")
		(net "SEB_AB_RX-")
	)
	(segment
		(start 24.0792 -212.471)
		(end 24.0792 -192.333372)
		(width 0.09525)
		(layer "B.Cu")
		(net "SEB_AB_RX-")
	)
	(segment
		(start 24.691594 -344.202766)
		(end 24.67102 -344.222832)
		(width 0.09525)
		(layer "B.Cu")
		(net "SEB_AB_RX-")
	)
	(segment
		(start 15.701264 -221.534228)
		(end 15.762986 -221.472506)
		(width 0.09525)
		(layer "B.Cu")
		(net "SEB_AB_RX-")
	)
	(segment
		(start 15.83182 -338.497926)
		(end 15.832074 -338.497926)
		(width 0.09525)
		(layer "B.Cu")
		(net "SEB_AB_RX-")
	)
	(segment
		(start 25.9969 -342.431116)
		(end 25.830784 -342.265)
		(width 0.09525)
		(layer "B.Cu")
		(net "SEB_AB_RX-")
	)
	(arc
		(start 23.594314 -213.641686)
		(mid 23.953203 -213.104571)
		(end 24.0792 -212.471)
		(width 0.09525)
		(layer "B.Cu")
		(net "SEB_AB_RX-")
	)
	(arc
		(start 5.46989 -172.165518)
		(mid 5.337113 -172.191929)
		(end 5.224526 -172.267118)
		(width 0.09525)
		(layer "B.Cu")
		(net "SEB_AB_RX-")
	)
	(arc
		(start 24.67102 -344.222832)
		(mid 24.363831 -344.428089)
		(end 24.001476 -344.5002)
		(width 0.09525)
		(layer "B.Cu")
		(net "SEB_AB_RX-")
	)
	(arc
		(start 24.0792 -192.333372)
		(mid 23.98216 -191.845517)
		(end 23.70582 -191.431926)
		(width 0.09525)
		(layer "B.Cu")
		(net "SEB_AB_RX-")
	)
	(arc
		(start 9.037574 -176.763426)
		(mid 8.684024 -176.234484)
		(end 8.5598 -175.61052)
		(width 0.09525)
		(layer "B.Cu")
		(net "SEB_AB_RX-")
	)
	(arc
		(start 15.0368 -223.138746)
		(mid 15.209486 -222.270416)
		(end 15.701264 -221.534228)
		(width 0.09525)
		(layer "B.Cu")
		(net "SEB_AB_RX-")
	)
	(arc
		(start 8.5598 -173.863)
		(mid 8.475772 -173.440562)
		(end 8.236458 -173.082458)
		(width 0.09525)
		(layer "B.Cu")
		(net "SEB_AB_RX-")
	)
	(arc
		(start 25.146 -342.265)
		(mid 25.014405 -342.461946)
		(end 24.9682 -342.69426)
		(width 0.09525)
		(layer "B.Cu")
		(net "SEB_AB_RX-")
	)
	(arc
		(start 7.747 -172.593)
		(mid 7.273513 -172.276626)
		(end 6.714998 -172.165518)
		(width 0.09525)
		(layer "B.Cu")
		(net "SEB_AB_RX-")
	)
	(arc
		(start 15.832074 -338.497926)
		(mid 15.243604 -337.617263)
		(end 15.0368 -336.578448)
		(width 0.09525)
		(layer "B.Cu")
		(net "SEB_AB_RX-")
	)
	(arc
		(start 25.830784 -342.265)
		(mid 25.488392 -342.123177)
		(end 25.146 -342.265)
		(width 0.09525)
		(layer "B.Cu")
		(net "SEB_AB_RX-")
	)
	(arc
		(start 24.967946 -343.535)
		(mid 24.896253 -343.896388)
		(end 24.691594 -344.202766)
		(width 0.09525)
		(layer "B.Cu")
		(net "SEB_AB_RX-")
	)
	(arc
		(start 5.224526 -172.267118)
		(mid 4.966282 -172.439671)
		(end 4.661662 -172.50029)
		(width 0.09525)
		(layer "B.Cu")
		(net "SEB_AB_RX-")
	)
	(arc
		(start 22.689058 -344.5002)
		(mid 21.899194 -344.342917)
		(end 21.229574 -343.895426)
		(width 0.09525)
		(layer "B.Cu")
		(net "SEB_AB_RX-")
	)
	(segment
		(start 206.5528 -170.2054)
		(end 208.4324 -170.2054)
		(width 0.111252)
		(layer "F.Cu")
		(net "HDD3_LED_G")
	)
	(segment
		(start 212.1662 -170.2181)
		(end 212.1662 -168.4528)
		(width 0.111252)
		(layer "F.Cu")
		(net "HDD3_LED_G")
	)
	(segment
		(start 209.8294 -170.2181)
		(end 212.1662 -170.2181)
		(width 0.111252)
		(layer "F.Cu")
		(net "HDD3_LED_G")
	)
	(segment
		(start 208.4324 -170.2054)
		(end 209.8167 -170.2054)
		(width 0.111252)
		(layer "F.Cu")
		(net "HDD3_LED_G")
	)
	(segment
		(start 209.8167 -170.2054)
		(end 209.8294 -170.2181)
		(width 0.111252)
		(layer "F.Cu")
		(net "HDD3_LED_G")
	)
	(via
		(at 212.1662 -168.4528)
		(size 0.7112)
		(drill 0.3556)
		(layers "F.Cu" "B.Cu")
		(net "HDD3_LED_G")
	)
	(segment
		(start 26.134314 -341.64016)
		(end 25.9969 -341.503)
		(width 0.09525)
		(layer "F.Cu")
		(net "SEB_AB_RX+")
	)
	(segment
		(start 26.8478 -341.5284)
		(end 26.76271 -341.613236)
		(width 0.09525)
		(layer "F.Cu")
		(net "SEB_AB_RX+")
	)
	(via
		(at 25.9969 -341.503)
		(size 0.5588)
		(drill 0.3048)
		(layers "F.Cu" "B.Cu")
		(net "SEB_AB_RX+")
	)
	(arc
		(start 26.416 -341.757)
		(mid 26.263544 -341.726581)
		(end 26.134314 -341.64016)
		(width 0.09525)
		(layer "F.Cu")
		(net "SEB_AB_RX+")
	)
	(arc
		(start 26.76271 -341.613236)
		(mid 26.603653 -341.719607)
		(end 26.416 -341.757)
		(width 0.09525)
		(layer "F.Cu")
		(net "SEB_AB_RX+")
	)
	(segment
		(start 15.996412 -221.706186)
		(end 15.996666 -221.70644)
		(width 0.09525)
		(layer "B.Cu")
		(net "SEB_AB_RX+")
	)
	(segment
		(start 8.470138 -172.848778)
		(end 8.36168 -172.74032)
		(width 0.09525)
		(layer "B.Cu")
		(net "SEB_AB_RX+")
	)
	(segment
		(start 17.06118 -220.64218)
		(end 23.664926 -214.038434)
		(width 0.09525)
		(layer "B.Cu")
		(net "SEB_AB_RX+")
	)
	(segment
		(start 23.664926 -214.037926)
		(end 23.66518 -214.03818)
		(width 0.09525)
		(layer "B.Cu")
		(net "SEB_AB_RX+")
	)
	(segment
		(start 24.4094 -212.470746)
		(end 24.4094 -192.333626)
		(width 0.09525)
		(layer "B.Cu")
		(net "SEB_AB_RX+")
	)
	(segment
		(start 15.367 -336.578194)
		(end 15.367 -223.139)
		(width 0.09525)
		(layer "B.Cu")
		(net "SEB_AB_RX+")
	)
	(segment
		(start 21.463 -343.662)
		(end 16.0655 -338.2645)
		(width 0.09525)
		(layer "B.Cu")
		(net "SEB_AB_RX+")
	)
	(segment
		(start 8.36168 -172.74032)
		(end 8.361426 -172.74032)
		(width 0.09525)
		(layer "B.Cu")
		(net "SEB_AB_RX+")
	)
	(segment
		(start 25.9969 -341.503)
		(end 25.7429 -341.757)
		(width 0.09525)
		(layer "B.Cu")
		(net "SEB_AB_RX+")
	)
	(segment
		(start 23.664926 -214.038434)
		(end 23.664926 -214.037926)
		(width 0.09525)
		(layer "B.Cu")
		(net "SEB_AB_RX+")
	)
	(segment
		(start 4.822952 -171.500292)
		(end 4.821428 -171.498768)
		(width 0.09525)
		(layer "B.Cu")
		(net "SEB_AB_RX+")
	)
	(segment
		(start 15.996666 -221.70644)
		(end 17.06118 -220.64218)
		(width 0.09525)
		(layer "B.Cu")
		(net "SEB_AB_RX+")
	)
	(segment
		(start 8.89 -175.610266)
		(end 8.89 -173.862746)
		(width 0.09525)
		(layer "B.Cu")
		(net "SEB_AB_RX+")
	)
	(segment
		(start 23.66518 -214.03818)
		(end 23.827994 -213.875366)
		(width 0.09525)
		(layer "B.Cu")
		(net "SEB_AB_RX+")
	)
	(segment
		(start 24.458676 -343.968324)
		(end 24.438864 -343.987882)
		(width 0.09525)
		(layer "B.Cu")
		(net "SEB_AB_RX+")
	)
	(segment
		(start 7.980426 -172.35932)
		(end 7.980426 -172.359574)
		(width 0.09525)
		(layer "B.Cu")
		(net "SEB_AB_RX+")
	)
	(segment
		(start 8.361426 -172.74032)
		(end 7.980426 -172.35932)
		(width 0.09525)
		(layer "B.Cu")
		(net "SEB_AB_RX+")
	)
	(segment
		(start 23.939246 -191.1985)
		(end 23.939246 -191.198246)
		(width 0.09525)
		(layer "B.Cu")
		(net "SEB_AB_RX+")
	)
	(segment
		(start 4.821428 -171.498768)
		(end 2.811526 -171.498768)
		(width 0.09525)
		(layer "B.Cu")
		(net "SEB_AB_RX+")
	)
	(segment
		(start 23.999444 -344.17)
		(end 22.689312 -344.17)
		(width 0.09525)
		(layer "B.Cu")
		(net "SEB_AB_RX+")
	)
	(segment
		(start 6.715252 -171.835318)
		(end 5.470144 -171.835318)
		(width 0.09525)
		(layer "B.Cu")
		(net "SEB_AB_RX+")
	)
	(segment
		(start 15.934944 -221.767908)
		(end 15.996412 -221.706186)
		(width 0.09525)
		(layer "B.Cu")
		(net "SEB_AB_RX+")
	)
	(segment
		(start 24.638 -342.69426)
		(end 24.638 -343.535)
		(width 0.09525)
		(layer "B.Cu")
		(net "SEB_AB_RX+")
	)
	(segment
		(start 5.2451 -171.742354)
		(end 5.1308 -171.6278)
		(width 0.09525)
		(layer "B.Cu")
		(net "SEB_AB_RX+")
	)
	(segment
		(start 23.939246 -191.198246)
		(end 9.271 -176.53)
		(width 0.09525)
		(layer "B.Cu")
		(net "SEB_AB_RX+")
	)
	(arc
		(start 24.638 -343.535)
		(mid 24.591448 -343.769504)
		(end 24.458676 -343.968324)
		(width 0.09525)
		(layer "B.Cu")
		(net "SEB_AB_RX+")
	)
	(arc
		(start 16.0655 -338.2645)
		(mid 15.548541 -337.490816)
		(end 15.367 -336.578194)
		(width 0.09525)
		(layer "B.Cu")
		(net "SEB_AB_RX+")
	)
	(arc
		(start 25.608534 -341.80145)
		(mid 25.233128 -341.833683)
		(end 24.91232 -342.03132)
		(width 0.09525)
		(layer "B.Cu")
		(net "SEB_AB_RX+")
	)
	(arc
		(start 8.89 -173.862746)
		(mid 8.780886 -173.314015)
		(end 8.470138 -172.848778)
		(width 0.09525)
		(layer "B.Cu")
		(net "SEB_AB_RX+")
	)
	(arc
		(start 5.1308 -171.6278)
		(mid 4.989558 -171.533425)
		(end 4.822952 -171.500292)
		(width 0.09525)
		(layer "B.Cu")
		(net "SEB_AB_RX+")
	)
	(arc
		(start 24.4094 -192.333626)
		(mid 24.287273 -191.719272)
		(end 23.939246 -191.1985)
		(width 0.09525)
		(layer "B.Cu")
		(net "SEB_AB_RX+")
	)
	(arc
		(start 5.470144 -171.835318)
		(mid 5.469763 -171.835191)
		(end 5.469382 -171.835064)
		(width 0.09525)
		(layer "B.Cu")
		(net "SEB_AB_RX+")
	)
	(arc
		(start 9.271 -176.53)
		(mid 8.989044 -176.108022)
		(end 8.89 -175.610266)
		(width 0.09525)
		(layer "B.Cu")
		(net "SEB_AB_RX+")
	)
	(arc
		(start 24.91232 -342.03132)
		(mid 24.709224 -342.335509)
		(end 24.638 -342.69426)
		(width 0.09525)
		(layer "B.Cu")
		(net "SEB_AB_RX+")
	)
	(arc
		(start 5.469382 -171.835064)
		(mid 5.348032 -171.810979)
		(end 5.2451 -171.742354)
		(width 0.09525)
		(layer "B.Cu")
		(net "SEB_AB_RX+")
	)
	(arc
		(start 7.980426 -172.359574)
		(mid 7.399975 -171.971606)
		(end 6.715252 -171.835318)
		(width 0.09525)
		(layer "B.Cu")
		(net "SEB_AB_RX+")
	)
	(arc
		(start 23.827994 -213.875366)
		(mid 24.258433 -213.230891)
		(end 24.4094 -212.470746)
		(width 0.09525)
		(layer "B.Cu")
		(net "SEB_AB_RX+")
	)
	(arc
		(start 25.7429 -341.757)
		(mid 25.681004 -341.795205)
		(end 25.608534 -341.80145)
		(width 0.09525)
		(layer "B.Cu")
		(net "SEB_AB_RX+")
	)
	(arc
		(start 24.438864 -343.987882)
		(mid 24.237285 -344.122699)
		(end 23.999444 -344.17)
		(width 0.09525)
		(layer "B.Cu")
		(net "SEB_AB_RX+")
	)
	(arc
		(start 22.689312 -344.17)
		(mid 22.02562 -344.037983)
		(end 21.463 -343.662)
		(width 0.09525)
		(layer "B.Cu")
		(net "SEB_AB_RX+")
	)
	(arc
		(start 15.367 -223.139)
		(mid 15.5146 -222.396963)
		(end 15.934944 -221.767908)
		(width 0.09525)
		(layer "B.Cu")
		(net "SEB_AB_RX+")
	)
	(segment
		(start 5.384292 -424.3451)
		(end 5.384546 -424.3451)
		(width 0.09525)
		(layer "F.Cu")
		(net "SEB_AB_TX-")
	)
	(segment
		(start 11.169904 -441.127896)
		(end 11.0744 -441.2234)
		(width 0.09525)
		(layer "F.Cu")
		(net "SEB_AB_TX-")
	)
	(segment
		(start 28.687776 -342.289892)
		(end 28.829 -342.431116)
		(width 0.09525)
		(layer "F.Cu")
		(net "SEB_AB_TX-")
	)
	(segment
		(start 10.796524 -440.4614)
		(end 11.1506 -440.4614)
		(width 0.09525)
		(layer "F.Cu")
		(net "SEB_AB_TX-")
	)
	(segment
		(start 9.525 -438.9882)
		(end 9.525254 -438.9882)
		(width 0.09525)
		(layer "F.Cu")
		(net "SEB_AB_TX-")
	)
	(segment
		(start 3.19405 -424.500294)
		(end 5.165852 -424.500294)
		(width 0.09525)
		(layer "F.Cu")
		(net "SEB_AB_TX-")
	)
	(segment
		(start 27.7368 -342.4174)
		(end 27.800808 -342.353646)
		(width 0.09525)
		(layer "F.Cu")
		(net "SEB_AB_TX-")
	)
	(segment
		(start 5.273802 -424.45559)
		(end 5.384292 -424.3451)
		(width 0.09525)
		(layer "F.Cu")
		(net "SEB_AB_TX-")
	)
	(segment
		(start 9.891014 -439.87212)
		(end 10.25652 -440.23788)
		(width 0.09525)
		(layer "F.Cu")
		(net "SEB_AB_TX-")
	)
	(segment
		(start 6.293612 -424.403266)
		(end 6.3627 -424.4721)
		(width 0.09525)
		(layer "F.Cu")
		(net "SEB_AB_TX-")
	)
	(segment
		(start 11.2776 -440.5884)
		(end 11.2776 -440.8678)
		(width 0.09525)
		(layer "F.Cu")
		(net "SEB_AB_TX-")
	)
	(segment
		(start 6.3627 -424.4721)
		(end 9.2456 -427.355)
		(width 0.09525)
		(layer "F.Cu")
		(net "SEB_AB_TX-")
	)
	(segment
		(start 9.525 -428.029624)
		(end 9.525 -438.9882)
		(width 0.09525)
		(layer "F.Cu")
		(net "SEB_AB_TX-")
	)
	(segment
		(start 3.192526 -424.49877)
		(end 3.19405 -424.500294)
		(width 0.09525)
		(layer "F.Cu")
		(net "SEB_AB_TX-")
	)
	(segment
		(start 5.569204 -424.268646)
		(end 5.969 -424.268646)
		(width 0.09525)
		(layer "F.Cu")
		(net "SEB_AB_TX-")
	)
	(via
		(at 28.829 -342.431116)
		(size 0.5588)
		(drill 0.3048)
		(layers "F.Cu" "B.Cu")
		(net "SEB_AB_TX-")
	)
	(via
		(at 11.0744 -441.2234)
		(size 0.5588)
		(drill 0.3048)
		(layers "F.Cu" "B.Cu")
		(net "SEB_AB_TX-")
	)
	(arc
		(start 11.1506 -440.4614)
		(mid 11.240403 -440.498597)
		(end 11.2776 -440.5884)
		(width 0.09525)
		(layer "F.Cu")
		(net "SEB_AB_TX-")
	)
	(arc
		(start 28.321 -342.138)
		(mid 28.519486 -342.177481)
		(end 28.687776 -342.289892)
		(width 0.09525)
		(layer "F.Cu")
		(net "SEB_AB_TX-")
	)
	(arc
		(start 9.2456 -427.355)
		(mid 9.452415 -427.66452)
		(end 9.525 -428.029624)
		(width 0.09525)
		(layer "F.Cu")
		(net "SEB_AB_TX-")
	)
	(arc
		(start 5.969 -424.268646)
		(mid 6.144687 -424.303686)
		(end 6.293612 -424.403266)
		(width 0.09525)
		(layer "F.Cu")
		(net "SEB_AB_TX-")
	)
	(arc
		(start 9.525254 -438.9882)
		(mid 9.620199 -439.466553)
		(end 9.891014 -439.87212)
		(width 0.09525)
		(layer "F.Cu")
		(net "SEB_AB_TX-")
	)
	(arc
		(start 5.384546 -424.3451)
		(mid 5.469268 -424.288491)
		(end 5.569204 -424.268646)
		(width 0.09525)
		(layer "F.Cu")
		(net "SEB_AB_TX-")
	)
	(arc
		(start 11.2776 -440.8678)
		(mid 11.249619 -441.008562)
		(end 11.169904 -441.127896)
		(width 0.09525)
		(layer "F.Cu")
		(net "SEB_AB_TX-")
	)
	(arc
		(start 27.800808 -342.353646)
		(mid 28.039459 -342.194091)
		(end 28.321 -342.138)
		(width 0.09525)
		(layer "F.Cu")
		(net "SEB_AB_TX-")
	)
	(arc
		(start 5.165852 -424.500294)
		(mid 5.22427 -424.488674)
		(end 5.273802 -424.45559)
		(width 0.09525)
		(layer "F.Cu")
		(net "SEB_AB_TX-")
	)
	(arc
		(start 10.25652 -440.23788)
		(mid 10.504304 -440.403318)
		(end 10.796524 -440.4614)
		(width 0.09525)
		(layer "F.Cu")
		(net "SEB_AB_TX-")
	)
	(segment
		(start 33.885886 -359.603802)
		(end 33.885886 -359.260902)
		(width 0.1143)
		(layer "In5.Cu")
		(net "SEB_AB_TX-")
	)
	(segment
		(start 32.87014 -342.119458)
		(end 29.581348 -342.119458)
		(width 0.1143)
		(layer "In5.Cu")
		(net "SEB_AB_TX-")
	)
	(segment
		(start 18.2245 -436.8165)
		(end 19.3167 -437.9087)
		(width 0.1143)
		(layer "In5.Cu")
		(net "SEB_AB_TX-")
	)
	(segment
		(start 11.220196 -440.226196)
		(end 10.9855 -439.9915)
		(width 0.1143)
		(layer "In5.Cu")
		(net "SEB_AB_TX-")
	)
	(segment
		(start 34.073846 -360.322622)
		(end 34.073846 -359.979722)
		(width 0.1143)
		(layer "In5.Cu")
		(net "SEB_AB_TX-")
	)
	(segment
		(start 34.073846 -388.33298)
		(end 34.073846 -387.99008)
		(width 0.1143)
		(layer "In5.Cu")
		(net "SEB_AB_TX-")
	)
	(segment
		(start 37.655754 -424.878754)
		(end 37.6555 -424.8785)
		(width 0.1143)
		(layer "In5.Cu")
		(net "SEB_AB_TX-")
	)
	(segment
		(start 33.885886 -363.916722)
		(end 33.885886 -363.573822)
		(width 0.1143)
		(layer "In5.Cu")
		(net "SEB_AB_TX-")
	)
	(segment
		(start 33.885886 -361.041442)
		(end 33.885886 -360.698542)
		(width 0.1143)
		(layer "In5.Cu")
		(net "SEB_AB_TX-")
	)
	(segment
		(start 11.2522 -440.8043)
		(end 11.2522 -440.302904)
		(width 0.1143)
		(layer "In5.Cu")
		(net "SEB_AB_TX-")
	)
	(segment
		(start 34.073846 -384.02006)
		(end 34.073846 -365.730282)
		(width 0.1143)
		(layer "In5.Cu")
		(net "SEB_AB_TX-")
	)
	(segment
		(start 34.073846 -361.760262)
		(end 34.073846 -361.417362)
		(width 0.1143)
		(layer "In5.Cu")
		(net "SEB_AB_TX-")
	)
	(segment
		(start 34.073846 -386.89534)
		(end 34.073846 -386.55244)
		(width 0.1143)
		(layer "In5.Cu")
		(net "SEB_AB_TX-")
	)
	(segment
		(start 11.2522 -440.302904)
		(end 11.251946 -440.303158)
		(width 0.1143)
		(layer "In5.Cu")
		(net "SEB_AB_TX-")
	)
	(segment
		(start 34.073846 -385.4577)
		(end 34.073846 -385.1148)
		(width 0.1143)
		(layer "In5.Cu")
		(net "SEB_AB_TX-")
	)
	(segment
		(start 10.9855 -439.9915)
		(end 10.985754 -439.991246)
		(width 0.1143)
		(layer "In5.Cu")
		(net "SEB_AB_TX-")
	)
	(segment
		(start 41.699688 -404.030688)
		(end 34.90849 -397.23949)
		(width 0.1143)
		(layer "In5.Cu")
		(net "SEB_AB_TX-")
	)
	(segment
		(start 34.073846 -363.197902)
		(end 34.073846 -362.855002)
		(width 0.1143)
		(layer "In5.Cu")
		(net "SEB_AB_TX-")
	)
	(segment
		(start 33.885886 -386.17652)
		(end 33.885886 -385.83362)
		(width 0.1143)
		(layer "In5.Cu")
		(net "SEB_AB_TX-")
	)
	(segment
		(start 34.073846 -358.884982)
		(end 34.073846 -343.535)
		(width 0.1143)
		(layer "In5.Cu")
		(net "SEB_AB_TX-")
	)
	(segment
		(start 33.885886 -384.73888)
		(end 33.885886 -384.39598)
		(width 0.1143)
		(layer "In5.Cu")
		(net "SEB_AB_TX-")
	)
	(segment
		(start 42.418 -419.397688)
		(end 42.418 -405.765)
		(width 0.1143)
		(layer "In5.Cu")
		(net "SEB_AB_TX-")
	)
	(segment
		(start 12.128754 -436.3212)
		(end 17.028668 -436.3212)
		(width 0.1143)
		(layer "In5.Cu")
		(net "SEB_AB_TX-")
	)
	(segment
		(start 37.084 -432.104546)
		(end 37.084 -426.25899)
		(width 0.1143)
		(layer "In5.Cu")
		(net "SEB_AB_TX-")
	)
	(segment
		(start 34.073846 -364.635542)
		(end 34.073846 -364.292642)
		(width 0.1143)
		(layer "In5.Cu")
		(net "SEB_AB_TX-")
	)
	(segment
		(start 11.2395 -436.6895)
		(end 11.239754 -436.689754)
		(width 0.1143)
		(layer "In5.Cu")
		(net "SEB_AB_TX-")
	)
	(segment
		(start 34.073846 -395.223746)
		(end 34.073846 -390.86536)
		(width 0.1143)
		(layer "In5.Cu")
		(net "SEB_AB_TX-")
	)
	(segment
		(start 33.885886 -389.0518)
		(end 33.885886 -388.7089)
		(width 0.1143)
		(layer "In5.Cu")
		(net "SEB_AB_TX-")
	)
	(segment
		(start 34.073846 -389.77062)
		(end 34.073846 -389.42772)
		(width 0.1143)
		(layer "In5.Cu")
		(net "SEB_AB_TX-")
	)
	(segment
		(start 10.541 -438.91835)
		(end 10.541 -437.896254)
		(width 0.1143)
		(layer "In5.Cu")
		(net "SEB_AB_TX-")
	)
	(segment
		(start 33.885886 -387.61416)
		(end 33.885886 -387.27126)
		(width 0.1143)
		(layer "In5.Cu")
		(net "SEB_AB_TX-")
	)
	(segment
		(start 18.224246 -436.816754)
		(end 18.2245 -436.8165)
		(width 0.1143)
		(layer "In5.Cu")
		(net "SEB_AB_TX-")
	)
	(segment
		(start 32.1945 -437.8325)
		(end 36.491164 -433.535836)
		(width 0.1143)
		(layer "In5.Cu")
		(net "SEB_AB_TX-")
	)
	(segment
		(start 33.885886 -390.48944)
		(end 33.885886 -390.14654)
		(width 0.1143)
		(layer "In5.Cu")
		(net "SEB_AB_TX-")
	)
	(segment
		(start 37.6555 -424.8785)
		(end 41.91 -420.624)
		(width 0.1143)
		(layer "In5.Cu")
		(net "SEB_AB_TX-")
	)
	(segment
		(start 33.885886 -365.354362)
		(end 33.885886 -365.011462)
		(width 0.1143)
		(layer "In5.Cu")
		(net "SEB_AB_TX-")
	)
	(segment
		(start 10.899902 -437.029098)
		(end 11.2395 -436.6895)
		(width 0.1143)
		(layer "In5.Cu")
		(net "SEB_AB_TX-")
	)
	(segment
		(start 33.885886 -362.479082)
		(end 33.885886 -362.136182)
		(width 0.1143)
		(layer "In5.Cu")
		(net "SEB_AB_TX-")
	)
	(segment
		(start 11.0744 -441.2234)
		(end 11.081512 -441.216288)
		(width 0.1143)
		(layer "In5.Cu")
		(net "SEB_AB_TX-")
	)
	(segment
		(start 20.574 -438.4294)
		(end 30.753558 -438.4294)
		(width 0.1143)
		(layer "In5.Cu")
		(net "SEB_AB_TX-")
	)
	(segment
		(start 33.651698 -342.515698)
		(end 33.528 -342.392)
		(width 0.1143)
		(layer "In5.Cu")
		(net "SEB_AB_TX-")
	)
	(arc
		(start 34.073846 -387.99008)
		(mid 34.048691 -387.88517)
		(end 33.979866 -387.80212)
		(width 0.1143)
		(layer "In5.Cu")
		(net "SEB_AB_TX-")
	)
	(arc
		(start 33.885886 -365.011462)
		(mid 33.911041 -364.906552)
		(end 33.979866 -364.823502)
		(width 0.1143)
		(layer "In5.Cu")
		(net "SEB_AB_TX-")
	)
	(arc
		(start 33.979866 -364.104682)
		(mid 33.911041 -364.021607)
		(end 33.885886 -363.916722)
		(width 0.1143)
		(layer "In5.Cu")
		(net "SEB_AB_TX-")
	)
	(arc
		(start 34.073846 -390.86536)
		(mid 34.048691 -390.76045)
		(end 33.979866 -390.6774)
		(width 0.1143)
		(layer "In5.Cu")
		(net "SEB_AB_TX-")
	)
	(arc
		(start 33.979866 -390.6774)
		(mid 33.91113 -390.594306)
		(end 33.885886 -390.48944)
		(width 0.1143)
		(layer "In5.Cu")
		(net "SEB_AB_TX-")
	)
	(arc
		(start 33.885886 -384.39598)
		(mid 33.911041 -384.29107)
		(end 33.979866 -384.20802)
		(width 0.1143)
		(layer "In5.Cu")
		(net "SEB_AB_TX-")
	)
	(arc
		(start 34.073846 -365.730282)
		(mid 34.048691 -365.625372)
		(end 33.979866 -365.542322)
		(width 0.1143)
		(layer "In5.Cu")
		(net "SEB_AB_TX-")
	)
	(arc
		(start 33.979866 -361.229402)
		(mid 33.911041 -361.146327)
		(end 33.885886 -361.041442)
		(width 0.1143)
		(layer "In5.Cu")
		(net "SEB_AB_TX-")
	)
	(arc
		(start 34.90849 -397.23949)
		(mid 34.29065 -396.314643)
		(end 34.073846 -395.223746)
		(width 0.1143)
		(layer "In5.Cu")
		(net "SEB_AB_TX-")
	)
	(arc
		(start 33.979866 -389.95858)
		(mid 34.048602 -389.875486)
		(end 34.073846 -389.77062)
		(width 0.1143)
		(layer "In5.Cu")
		(net "SEB_AB_TX-")
	)
	(arc
		(start 30.753558 -438.4294)
		(mid 31.533406 -438.274279)
		(end 32.1945 -437.8325)
		(width 0.1143)
		(layer "In5.Cu")
		(net "SEB_AB_TX-")
	)
	(arc
		(start 41.91 -420.624)
		(mid 42.285942 -420.061363)
		(end 42.418 -419.397688)
		(width 0.1143)
		(layer "In5.Cu")
		(net "SEB_AB_TX-")
	)
	(arc
		(start 33.979866 -359.072942)
		(mid 34.048691 -358.989867)
		(end 34.073846 -358.884982)
		(width 0.1143)
		(layer "In5.Cu")
		(net "SEB_AB_TX-")
	)
	(arc
		(start 33.979866 -387.0833)
		(mid 34.048602 -387.000206)
		(end 34.073846 -386.89534)
		(width 0.1143)
		(layer "In5.Cu")
		(net "SEB_AB_TX-")
	)
	(arc
		(start 33.885886 -363.573822)
		(mid 33.911041 -363.468912)
		(end 33.979866 -363.385862)
		(width 0.1143)
		(layer "In5.Cu")
		(net "SEB_AB_TX-")
	)
	(arc
		(start 33.885886 -388.7089)
		(mid 33.911041 -388.60399)
		(end 33.979866 -388.52094)
		(width 0.1143)
		(layer "In5.Cu")
		(net "SEB_AB_TX-")
	)
	(arc
		(start 33.979866 -363.385862)
		(mid 34.048691 -363.302787)
		(end 34.073846 -363.197902)
		(width 0.1143)
		(layer "In5.Cu")
		(net "SEB_AB_TX-")
	)
	(arc
		(start 42.418 -405.765)
		(mid 42.23132 -404.826407)
		(end 41.699688 -404.030688)
		(width 0.1143)
		(layer "In5.Cu")
		(net "SEB_AB_TX-")
	)
	(arc
		(start 33.979866 -389.23976)
		(mid 33.91113 -389.156666)
		(end 33.885886 -389.0518)
		(width 0.1143)
		(layer "In5.Cu")
		(net "SEB_AB_TX-")
	)
	(arc
		(start 33.885886 -385.83362)
		(mid 33.911041 -385.72871)
		(end 33.979866 -385.64566)
		(width 0.1143)
		(layer "In5.Cu")
		(net "SEB_AB_TX-")
	)
	(arc
		(start 33.979866 -388.52094)
		(mid 34.048602 -388.437846)
		(end 34.073846 -388.33298)
		(width 0.1143)
		(layer "In5.Cu")
		(net "SEB_AB_TX-")
	)
	(arc
		(start 33.979866 -387.80212)
		(mid 33.91113 -387.719026)
		(end 33.885886 -387.61416)
		(width 0.1143)
		(layer "In5.Cu")
		(net "SEB_AB_TX-")
	)
	(arc
		(start 34.073846 -359.979722)
		(mid 34.048691 -359.874812)
		(end 33.979866 -359.791762)
		(width 0.1143)
		(layer "In5.Cu")
		(net "SEB_AB_TX-")
	)
	(arc
		(start 36.491164 -433.535836)
		(mid 36.929945 -432.879155)
		(end 37.084 -432.104546)
		(width 0.1143)
		(layer "In5.Cu")
		(net "SEB_AB_TX-")
	)
	(arc
		(start 33.979866 -386.36448)
		(mid 33.91113 -386.281386)
		(end 33.885886 -386.17652)
		(width 0.1143)
		(layer "In5.Cu")
		(net "SEB_AB_TX-")
	)
	(arc
		(start 33.979866 -359.791762)
		(mid 33.911041 -359.708687)
		(end 33.885886 -359.603802)
		(width 0.1143)
		(layer "In5.Cu")
		(net "SEB_AB_TX-")
	)
	(arc
		(start 11.081512 -441.216288)
		(mid 11.207812 -441.027266)
		(end 11.2522 -440.8043)
		(width 0.1143)
		(layer "In5.Cu")
		(net "SEB_AB_TX-")
	)
	(arc
		(start 34.073846 -386.55244)
		(mid 34.048691 -386.44753)
		(end 33.979866 -386.36448)
		(width 0.1143)
		(layer "In5.Cu")
		(net "SEB_AB_TX-")
	)
	(arc
		(start 10.541 -437.896254)
		(mid 10.634177 -437.426969)
		(end 10.899902 -437.029098)
		(width 0.1143)
		(layer "In5.Cu")
		(net "SEB_AB_TX-")
	)
	(arc
		(start 33.979866 -365.542322)
		(mid 33.911041 -365.459247)
		(end 33.885886 -365.354362)
		(width 0.1143)
		(layer "In5.Cu")
		(net "SEB_AB_TX-")
	)
	(arc
		(start 33.885886 -360.698542)
		(mid 33.911041 -360.593632)
		(end 33.979866 -360.510582)
		(width 0.1143)
		(layer "In5.Cu")
		(net "SEB_AB_TX-")
	)
	(arc
		(start 11.251946 -440.303158)
		(mid 11.243754 -440.261502)
		(end 11.220196 -440.226196)
		(width 0.1143)
		(layer "In5.Cu")
		(net "SEB_AB_TX-")
	)
	(arc
		(start 33.979866 -361.948222)
		(mid 34.048691 -361.865147)
		(end 34.073846 -361.760262)
		(width 0.1143)
		(layer "In5.Cu")
		(net "SEB_AB_TX-")
	)
	(arc
		(start 17.028668 -436.3212)
		(mid 17.675743 -436.450081)
		(end 18.224246 -436.816754)
		(width 0.1143)
		(layer "In5.Cu")
		(net "SEB_AB_TX-")
	)
	(arc
		(start 19.3167 -437.9087)
		(mid 19.893568 -438.294088)
		(end 20.574 -438.4294)
		(width 0.1143)
		(layer "In5.Cu")
		(net "SEB_AB_TX-")
	)
	(arc
		(start 34.073846 -343.535)
		(mid 33.964137 -342.983367)
		(end 33.651698 -342.515698)
		(width 0.1143)
		(layer "In5.Cu")
		(net "SEB_AB_TX-")
	)
	(arc
		(start 37.084 -426.25899)
		(mid 37.232601 -425.51201)
		(end 37.655754 -424.878754)
		(width 0.1143)
		(layer "In5.Cu")
		(net "SEB_AB_TX-")
	)
	(arc
		(start 33.885886 -390.14654)
		(mid 33.911041 -390.04163)
		(end 33.979866 -389.95858)
		(width 0.1143)
		(layer "In5.Cu")
		(net "SEB_AB_TX-")
	)
	(arc
		(start 34.073846 -389.42772)
		(mid 34.048691 -389.32281)
		(end 33.979866 -389.23976)
		(width 0.1143)
		(layer "In5.Cu")
		(net "SEB_AB_TX-")
	)
	(arc
		(start 33.528 -342.392)
		(mid 33.226171 -342.190324)
		(end 32.87014 -342.119458)
		(width 0.1143)
		(layer "In5.Cu")
		(net "SEB_AB_TX-")
	)
	(arc
		(start 33.979866 -384.20802)
		(mid 34.048602 -384.124926)
		(end 34.073846 -384.02006)
		(width 0.1143)
		(layer "In5.Cu")
		(net "SEB_AB_TX-")
	)
	(arc
		(start 34.073846 -364.292642)
		(mid 34.048691 -364.187732)
		(end 33.979866 -364.104682)
		(width 0.1143)
		(layer "In5.Cu")
		(net "SEB_AB_TX-")
	)
	(arc
		(start 29.581348 -342.119458)
		(mid 29.174171 -342.200451)
		(end 28.829 -342.431116)
		(width 0.1143)
		(layer "In5.Cu")
		(net "SEB_AB_TX-")
	)
	(arc
		(start 33.885886 -362.136182)
		(mid 33.911041 -362.031272)
		(end 33.979866 -361.948222)
		(width 0.1143)
		(layer "In5.Cu")
		(net "SEB_AB_TX-")
	)
	(arc
		(start 33.885886 -387.27126)
		(mid 33.911041 -387.16635)
		(end 33.979866 -387.0833)
		(width 0.1143)
		(layer "In5.Cu")
		(net "SEB_AB_TX-")
	)
	(arc
		(start 34.073846 -385.1148)
		(mid 34.048691 -385.00989)
		(end 33.979866 -384.92684)
		(width 0.1143)
		(layer "In5.Cu")
		(net "SEB_AB_TX-")
	)
	(arc
		(start 34.073846 -362.855002)
		(mid 34.048691 -362.750092)
		(end 33.979866 -362.667042)
		(width 0.1143)
		(layer "In5.Cu")
		(net "SEB_AB_TX-")
	)
	(arc
		(start 11.239754 -436.689754)
		(mid 11.647615 -436.417107)
		(end 12.128754 -436.3212)
		(width 0.1143)
		(layer "In5.Cu")
		(net "SEB_AB_TX-")
	)
	(arc
		(start 10.985754 -439.991246)
		(mid 10.656732 -439.499013)
		(end 10.541 -438.91835)
		(width 0.1143)
		(layer "In5.Cu")
		(net "SEB_AB_TX-")
	)
	(arc
		(start 33.979866 -384.92684)
		(mid 33.91113 -384.843746)
		(end 33.885886 -384.73888)
		(width 0.1143)
		(layer "In5.Cu")
		(net "SEB_AB_TX-")
	)
	(arc
		(start 33.979866 -385.64566)
		(mid 34.048602 -385.562566)
		(end 34.073846 -385.4577)
		(width 0.1143)
		(layer "In5.Cu")
		(net "SEB_AB_TX-")
	)
	(arc
		(start 33.979866 -364.823502)
		(mid 34.048691 -364.740427)
		(end 34.073846 -364.635542)
		(width 0.1143)
		(layer "In5.Cu")
		(net "SEB_AB_TX-")
	)
	(arc
		(start 33.885886 -359.260902)
		(mid 33.911041 -359.155992)
		(end 33.979866 -359.072942)
		(width 0.1143)
		(layer "In5.Cu")
		(net "SEB_AB_TX-")
	)
	(arc
		(start 33.979866 -360.510582)
		(mid 34.048691 -360.427507)
		(end 34.073846 -360.322622)
		(width 0.1143)
		(layer "In5.Cu")
		(net "SEB_AB_TX-")
	)
	(arc
		(start 34.073846 -361.417362)
		(mid 34.048691 -361.312452)
		(end 33.979866 -361.229402)
		(width 0.1143)
		(layer "In5.Cu")
		(net "SEB_AB_TX-")
	)
	(arc
		(start 33.979866 -362.667042)
		(mid 33.911041 -362.583967)
		(end 33.885886 -362.479082)
		(width 0.1143)
		(layer "In5.Cu")
		(net "SEB_AB_TX-")
	)
	(segment
		(start 28.754578 -341.577422)
		(end 28.829 -341.503)
		(width 0.09525)
		(layer "F.Cu")
		(net "SEB_AB_TX+")
	)
	(segment
		(start 5.969 -423.9387)
		(end 5.969 -423.938446)
		(width 0.09525)
		(layer "F.Cu")
		(net "SEB_AB_TX+")
	)
	(segment
		(start 9.479026 -427.12132)
		(end 6.527038 -424.169332)
		(width 0.09525)
		(layer "F.Cu")
		(net "SEB_AB_TX+")
	)
	(segment
		(start 11.6078 -440.7154)
		(end 11.6078 -440.5884)
		(width 0.09525)
		(layer "F.Cu")
		(net "SEB_AB_TX+")
	)
	(segment
		(start 3.19405 -423.500296)
		(end 3.192526 -423.498772)
		(width 0.09525)
		(layer "F.Cu")
		(net "SEB_AB_TX+")
	)
	(segment
		(start 28.288742 -341.757)
		(end 28.321 -341.757)
		(width 0.09525)
		(layer "F.Cu")
		(net "SEB_AB_TX+")
	)
	(segment
		(start 5.470144 -423.827702)
		(end 5.266182 -423.62374)
		(width 0.09525)
		(layer "F.Cu")
		(net "SEB_AB_TX+")
	)
	(segment
		(start 11.1506 -440.1312)
		(end 10.796778 -440.1312)
		(width 0.09525)
		(layer "F.Cu")
		(net "SEB_AB_TX+")
	)
	(segment
		(start 9.8552 -438.9882)
		(end 9.8552 -428.029624)
		(width 0.09525)
		(layer "F.Cu")
		(net "SEB_AB_TX+")
	)
	(segment
		(start 5.969 -423.938446)
		(end 5.737606 -423.938446)
		(width 0.09525)
		(layer "F.Cu")
		(net "SEB_AB_TX+")
	)
	(segment
		(start 10.4902 -440.0042)
		(end 10.124694 -439.63844)
		(width 0.09525)
		(layer "F.Cu")
		(net "SEB_AB_TX+")
	)
	(segment
		(start 11.938 -441.2234)
		(end 11.73353 -441.01893)
		(width 0.09525)
		(layer "F.Cu")
		(net "SEB_AB_TX+")
	)
	(segment
		(start 4.96824 -423.500296)
		(end 3.19405 -423.500296)
		(width 0.09525)
		(layer "F.Cu")
		(net "SEB_AB_TX+")
	)
	(via
		(at 11.938 -441.2234)
		(size 0.5588)
		(drill 0.3048)
		(layers "F.Cu" "B.Cu")
		(net "SEB_AB_TX+")
	)
	(via
		(at 28.829 -341.503)
		(size 0.5588)
		(drill 0.3048)
		(layers "F.Cu" "B.Cu")
		(net "SEB_AB_TX+")
	)
	(arc
		(start 11.73353 -441.01893)
		(mid 11.640479 -440.879669)
		(end 11.6078 -440.7154)
		(width 0.09525)
		(layer "F.Cu")
		(net "SEB_AB_TX+")
	)
	(arc
		(start 10.124694 -439.63844)
		(mid 9.925272 -439.340122)
		(end 9.8552 -438.9882)
		(width 0.09525)
		(layer "F.Cu")
		(net "SEB_AB_TX+")
	)
	(arc
		(start 6.527038 -424.169332)
		(mid 6.270935 -423.998585)
		(end 5.969 -423.9387)
		(width 0.09525)
		(layer "F.Cu")
		(net "SEB_AB_TX+")
	)
	(arc
		(start 11.6078 -440.5884)
		(mid 11.473889 -440.265111)
		(end 11.1506 -440.1312)
		(width 0.09525)
		(layer "F.Cu")
		(net "SEB_AB_TX+")
	)
	(arc
		(start 28.321 -341.757)
		(mid 28.555645 -341.710326)
		(end 28.754578 -341.577422)
		(width 0.09525)
		(layer "F.Cu")
		(net "SEB_AB_TX+")
	)
	(arc
		(start 9.8552 -428.029624)
		(mid 9.757493 -427.538036)
		(end 9.479026 -427.12132)
		(width 0.09525)
		(layer "F.Cu")
		(net "SEB_AB_TX+")
	)
	(arc
		(start 27.7368 -341.5284)
		(mid 27.990033 -341.697605)
		(end 28.288742 -341.757)
		(width 0.09525)
		(layer "F.Cu")
		(net "SEB_AB_TX+")
	)
	(arc
		(start 10.796778 -440.1312)
		(mid 10.630855 -440.098196)
		(end 10.4902 -440.0042)
		(width 0.09525)
		(layer "F.Cu")
		(net "SEB_AB_TX+")
	)
	(arc
		(start 5.266182 -423.62374)
		(mid 5.129485 -423.532402)
		(end 4.96824 -423.500296)
		(width 0.09525)
		(layer "F.Cu")
		(net "SEB_AB_TX+")
	)
	(arc
		(start 5.737606 -423.938446)
		(mid 5.692318 -423.935694)
		(end 5.64769 -423.927524)
		(width 0.09525)
		(layer "F.Cu")
		(net "SEB_AB_TX+")
	)
	(arc
		(start 5.64769 -423.927524)
		(mid 5.552068 -423.889795)
		(end 5.470144 -423.827702)
		(width 0.09525)
		(layer "F.Cu")
		(net "SEB_AB_TX+")
	)
	(segment
		(start 37.3888 -432.104292)
		(end 37.3888 -426.258736)
		(width 0.1143)
		(layer "In5.Cu")
		(net "SEB_AB_TX+")
	)
	(segment
		(start 20.574254 -438.7342)
		(end 30.753812 -438.7342)
		(width 0.1143)
		(layer "In5.Cu")
		(net "SEB_AB_TX+")
	)
	(segment
		(start 32.870394 -341.814658)
		(end 29.581348 -341.814658)
		(width 0.1143)
		(layer "In5.Cu")
		(net "SEB_AB_TX+")
	)
	(segment
		(start 18.008854 -437.032146)
		(end 19.101054 -438.124346)
		(width 0.1143)
		(layer "In5.Cu")
		(net "SEB_AB_TX+")
	)
	(segment
		(start 11.115548 -437.244744)
		(end 11.455146 -436.905146)
		(width 0.1143)
		(layer "In5.Cu")
		(net "SEB_AB_TX+")
	)
	(segment
		(start 10.8458 -438.918096)
		(end 10.8458 -437.896)
		(width 0.1143)
		(layer "In5.Cu")
		(net "SEB_AB_TX+")
	)
	(segment
		(start 42.7228 -419.397942)
		(end 42.7228 -405.764746)
		(width 0.1143)
		(layer "In5.Cu")
		(net "SEB_AB_TX+")
	)
	(segment
		(start 11.938 -441.2234)
		(end 11.754612 -441.040012)
		(width 0.1143)
		(layer "In5.Cu")
		(net "SEB_AB_TX+")
	)
	(segment
		(start 41.915334 -403.815042)
		(end 35.124136 -397.023844)
		(width 0.1143)
		(layer "In5.Cu")
		(net "SEB_AB_TX+")
	)
	(segment
		(start 32.410146 -438.048146)
		(end 36.70681 -433.751482)
		(width 0.1143)
		(layer "In5.Cu")
		(net "SEB_AB_TX+")
	)
	(segment
		(start 34.378646 -395.224)
		(end 34.378646 -343.534746)
		(width 0.1143)
		(layer "In5.Cu")
		(net "SEB_AB_TX+")
	)
	(segment
		(start 11.557 -440.563)
		(end 11.557 -440.303158)
		(width 0.1143)
		(layer "In5.Cu")
		(net "SEB_AB_TX+")
	)
	(segment
		(start 12.129008 -436.626)
		(end 17.028414 -436.626)
		(width 0.1143)
		(layer "In5.Cu")
		(net "SEB_AB_TX+")
	)
	(segment
		(start 37.871146 -425.094146)
		(end 42.125646 -420.839646)
		(width 0.1143)
		(layer "In5.Cu")
		(net "SEB_AB_TX+")
	)
	(segment
		(start 11.435842 -440.01055)
		(end 11.201146 -439.775854)
		(width 0.1143)
		(layer "In5.Cu")
		(net "SEB_AB_TX+")
	)
	(segment
		(start 42.125646 -420.839646)
		(end 42.125392 -420.839392)
		(width 0.1143)
		(layer "In5.Cu")
		(net "SEB_AB_TX+")
	)
	(segment
		(start 33.867344 -342.300052)
		(end 33.743646 -342.176354)
		(width 0.1143)
		(layer "In5.Cu")
		(net "SEB_AB_TX+")
	)
	(segment
		(start 32.409892 -438.047892)
		(end 32.410146 -438.048146)
		(width 0.1143)
		(layer "In5.Cu")
		(net "SEB_AB_TX+")
	)
	(arc
		(start 10.8458 -437.896)
		(mid 10.915907 -437.543547)
		(end 11.115548 -437.244744)
		(width 0.1143)
		(layer "In5.Cu")
		(net "SEB_AB_TX+")
	)
	(arc
		(start 17.028414 -436.626)
		(mid 17.559037 -436.731548)
		(end 18.008854 -437.032146)
		(width 0.1143)
		(layer "In5.Cu")
		(net "SEB_AB_TX+")
	)
	(arc
		(start 42.125392 -420.839392)
		(mid 42.567399 -420.178065)
		(end 42.7228 -419.397942)
		(width 0.1143)
		(layer "In5.Cu")
		(net "SEB_AB_TX+")
	)
	(arc
		(start 36.70681 -433.751482)
		(mid 37.211665 -432.995729)
		(end 37.3888 -432.104292)
		(width 0.1143)
		(layer "In5.Cu")
		(net "SEB_AB_TX+")
	)
	(arc
		(start 37.3888 -426.258736)
		(mid 37.514166 -425.628481)
		(end 37.871146 -425.094146)
		(width 0.1143)
		(layer "In5.Cu")
		(net "SEB_AB_TX+")
	)
	(arc
		(start 30.753812 -438.7342)
		(mid 31.650112 -438.555745)
		(end 32.409892 -438.047892)
		(width 0.1143)
		(layer "In5.Cu")
		(net "SEB_AB_TX+")
	)
	(arc
		(start 33.743646 -342.176354)
		(mid 33.34298 -341.908701)
		(end 32.870394 -341.814658)
		(width 0.1143)
		(layer "In5.Cu")
		(net "SEB_AB_TX+")
	)
	(arc
		(start 11.201146 -439.775854)
		(mid 10.938189 -439.382311)
		(end 10.8458 -438.918096)
		(width 0.1143)
		(layer "In5.Cu")
		(net "SEB_AB_TX+")
	)
	(arc
		(start 35.124136 -397.023844)
		(mid 34.57237 -396.198069)
		(end 34.378646 -395.224)
		(width 0.1143)
		(layer "In5.Cu")
		(net "SEB_AB_TX+")
	)
	(arc
		(start 42.7228 -405.764746)
		(mid 42.512953 -404.709594)
		(end 41.915334 -403.815042)
		(width 0.1143)
		(layer "In5.Cu")
		(net "SEB_AB_TX+")
	)
	(arc
		(start 29.581348 -341.814658)
		(mid 29.174171 -341.733665)
		(end 28.829 -341.503)
		(width 0.1143)
		(layer "In5.Cu")
		(net "SEB_AB_TX+")
	)
	(arc
		(start 19.101054 -438.124346)
		(mid 19.776994 -438.575809)
		(end 20.574254 -438.7342)
		(width 0.1143)
		(layer "In5.Cu")
		(net "SEB_AB_TX+")
	)
	(arc
		(start 34.378646 -343.534746)
		(mid 34.24577 -342.866554)
		(end 33.867344 -342.300052)
		(width 0.1143)
		(layer "In5.Cu")
		(net "SEB_AB_TX+")
	)
	(arc
		(start 11.455146 -436.905146)
		(mid 11.764317 -436.698565)
		(end 12.129008 -436.626)
		(width 0.1143)
		(layer "In5.Cu")
		(net "SEB_AB_TX+")
	)
	(arc
		(start 11.754612 -441.040012)
		(mid 11.608378 -440.821157)
		(end 11.557 -440.563)
		(width 0.1143)
		(layer "In5.Cu")
		(net "SEB_AB_TX+")
	)
	(arc
		(start 11.557 -440.303158)
		(mid 11.525504 -440.144817)
		(end 11.435842 -440.01055)
		(width 0.1143)
		(layer "In5.Cu")
		(net "SEB_AB_TX+")
	)
	(segment
		(start 7.80669 -423.180256)
		(end 7.822946 -423.164)
		(width 0.09525)
		(layer "F.Cu")
		(net "SEB_BA_RX-")
	)
	(segment
		(start 34.736786 -274.43684)
		(end 34.919158 -274.618958)
		(width 0.09525)
		(layer "F.Cu")
		(net "SEB_BA_RX-")
	)
	(segment
		(start 10.795 -425.387008)
		(end 10.795 -437.995822)
		(width 0.09525)
		(layer "F.Cu")
		(net "SEB_BA_RX-")
	)
	(segment
		(start 11.167364 -438.404)
		(end 11.176 -438.404)
		(width 0.09525)
		(layer "F.Cu")
		(net "SEB_BA_RX-")
	)
	(segment
		(start 34.3535 -274.32)
		(end 34.4551 -274.32)
		(width 0.09525)
		(layer "F.Cu")
		(net "SEB_BA_RX-")
	)
	(segment
		(start 7.6454 -423.6974)
		(end 7.6454 -423.570146)
		(width 0.09525)
		(layer "F.Cu")
		(net "SEB_BA_RX-")
	)
	(segment
		(start 11.47953 -438.27827)
		(end 11.652758 -438.105042)
		(width 0.09525)
		(layer "F.Cu")
		(net "SEB_BA_RX-")
	)
	(segment
		(start 7.3914 -424.053)
		(end 7.573518 -423.870882)
		(width 0.09525)
		(layer "F.Cu")
		(net "SEB_BA_RX-")
	)
	(segment
		(start 8.314436 -422.9608)
		(end 8.584946 -422.9608)
		(width 0.09525)
		(layer "F.Cu")
		(net "SEB_BA_RX-")
	)
	(segment
		(start 33.7058 -274.5994)
		(end 33.724596 -274.58035)
		(width 0.09525)
		(layer "F.Cu")
		(net "SEB_BA_RX-")
	)
	(segment
		(start 9.339072 -423.272712)
		(end 10.329926 -424.263566)
		(width 0.09525)
		(layer "F.Cu")
		(net "SEB_BA_RX-")
	)
	(segment
		(start 7.822946 -423.164)
		(end 7.8232 -423.164254)
		(width 0.09525)
		(layer "F.Cu")
		(net "SEB_BA_RX-")
	)
	(segment
		(start 10.329926 -424.263566)
		(end 10.329926 -424.264074)
		(width 0.09525)
		(layer "F.Cu")
		(net "SEB_BA_RX-")
	)
	(via
		(at 11.652758 -438.105042)
		(size 0.5588)
		(drill 0.3048)
		(layers "F.Cu" "B.Cu")
		(net "SEB_BA_RX-")
	)
	(via
		(at 34.919158 -274.618958)
		(size 0.5588)
		(drill 0.3048)
		(layers "F.Cu" "B.Cu")
		(net "SEB_BA_RX-")
	)
	(via
		(at 7.3914 -424.053)
		(size 0.5588)
		(drill 0.3048)
		(layers "F.Cu" "B.Cu")
		(net "SEB_BA_RX-")
	)
	(arc
		(start 7.573518 -423.870882)
		(mid 7.626701 -423.791288)
		(end 7.6454 -423.6974)
		(width 0.09525)
		(layer "F.Cu")
		(net "SEB_BA_RX-")
	)
	(arc
		(start 33.724596 -274.58035)
		(mid 34.013155 -274.387634)
		(end 34.3535 -274.32)
		(width 0.09525)
		(layer "F.Cu")
		(net "SEB_BA_RX-")
	)
	(arc
		(start 8.584946 -422.9608)
		(mid 8.993023 -423.041766)
		(end 9.339072 -423.272712)
		(width 0.09525)
		(layer "F.Cu")
		(net "SEB_BA_RX-")
	)
	(arc
		(start 34.4551 -274.32)
		(mid 34.607556 -274.350419)
		(end 34.736786 -274.43684)
		(width 0.09525)
		(layer "F.Cu")
		(net "SEB_BA_RX-")
	)
	(arc
		(start 10.922 -438.3024)
		(mid 11.034574 -438.37762)
		(end 11.167364 -438.404)
		(width 0.09525)
		(layer "F.Cu")
		(net "SEB_BA_RX-")
	)
	(arc
		(start 10.329926 -424.264074)
		(mid 10.674147 -424.779281)
		(end 10.795 -425.387008)
		(width 0.09525)
		(layer "F.Cu")
		(net "SEB_BA_RX-")
	)
	(arc
		(start 7.6454 -423.570146)
		(mid 7.687311 -423.359176)
		(end 7.80669 -423.180256)
		(width 0.09525)
		(layer "F.Cu")
		(net "SEB_BA_RX-")
	)
	(arc
		(start 11.176 -438.404)
		(mid 11.340271 -438.371325)
		(end 11.47953 -438.27827)
		(width 0.09525)
		(layer "F.Cu")
		(net "SEB_BA_RX-")
	)
	(arc
		(start 10.795 -437.995822)
		(mid 10.828004 -438.161745)
		(end 10.922 -438.3024)
		(width 0.09525)
		(layer "F.Cu")
		(net "SEB_BA_RX-")
	)
	(arc
		(start 7.8232 -423.164254)
		(mid 8.048582 -423.013689)
		(end 8.314436 -422.9608)
		(width 0.09525)
		(layer "F.Cu")
		(net "SEB_BA_RX-")
	)
	(segment
		(start 5.715 -422.1607)
		(end 5.528564 -422.1607)
		(width 0.09525)
		(layer "B.Cu")
		(net "SEB_BA_RX-")
	)
	(segment
		(start 7.505446 -423.5069)
		(end 6.502146 -422.5036)
		(width 0.09525)
		(layer "B.Cu")
		(net "SEB_BA_RX-")
	)
	(segment
		(start 6.502146 -422.5036)
		(end 6.473698 -422.47439)
		(width 0.09525)
		(layer "B.Cu")
		(net "SEB_BA_RX-")
	)
	(segment
		(start 4.707128 -422.498774)
		(end 2.811526 -422.498774)
		(width 0.09525)
		(layer "B.Cu")
		(net "SEB_BA_RX-")
	)
	(segment
		(start 4.708652 -422.500298)
		(end 4.707128 -422.498774)
		(width 0.09525)
		(layer "B.Cu")
		(net "SEB_BA_RX-")
	)
	(arc
		(start 5.22986 -422.284398)
		(mid 4.990728 -422.444181)
		(end 4.708652 -422.500298)
		(width 0.09525)
		(layer "B.Cu")
		(net "SEB_BA_RX-")
	)
	(arc
		(start 6.407912 -422.414192)
		(mid 6.083925 -422.226032)
		(end 5.715 -422.1607)
		(width 0.09525)
		(layer "B.Cu")
		(net "SEB_BA_RX-")
	)
	(arc
		(start 5.528564 -422.1607)
		(mid 5.366918 -422.192853)
		(end 5.22986 -422.284398)
		(width 0.09525)
		(layer "B.Cu")
		(net "SEB_BA_RX-")
	)
	(arc
		(start 6.473698 -422.47439)
		(mid 6.441428 -422.44361)
		(end 6.407912 -422.414192)
		(width 0.09525)
		(layer "B.Cu")
		(net "SEB_BA_RX-")
	)
	(arc
		(start 7.3914 -424.053)
		(mid 7.596073 -423.810775)
		(end 7.505446 -423.5069)
		(width 0.09525)
		(layer "B.Cu")
		(net "SEB_BA_RX-")
	)
	(segment
		(start 25.278588 -439.63844)
		(end 24.935688 -439.63844)
		(width 0.1143)
		(layer "In5.Cu")
		(net "SEB_BA_RX-")
	)
	(segment
		(start 21.684488 -439.8264)
		(end 21.341588 -439.8264)
		(width 0.1143)
		(layer "In5.Cu")
		(net "SEB_BA_RX-")
	)
	(segment
		(start 46.594268 -442.086746)
		(end 31.065978 -442.086746)
		(width 0.1143)
		(layer "In5.Cu")
		(net "SEB_BA_RX-")
	)
	(segment
		(start 47.836836 -396.971774)
		(end 47.836836 -397.314674)
		(width 0.1143)
		(layer "In5.Cu")
		(net "SEB_BA_RX-")
	)
	(segment
		(start 27.961844 -439.8264)
		(end 25.654508 -439.8264)
		(width 0.1143)
		(layer "In5.Cu")
		(net "SEB_BA_RX-")
	)
	(segment
		(start 35.659822 -274.312126)
		(end 37.084 -274.312126)
		(width 0.1143)
		(layer "In5.Cu")
		(net "SEB_BA_RX-")
	)
	(segment
		(start 23.840948 -439.63844)
		(end 23.498048 -439.63844)
		(width 0.1143)
		(layer "In5.Cu")
		(net "SEB_BA_RX-")
	)
	(segment
		(start 20.965668 -439.63844)
		(end 20.622768 -439.63844)
		(width 0.1143)
		(layer "In5.Cu")
		(net "SEB_BA_RX-")
	)
	(segment
		(start 23.122128 -439.8264)
		(end 22.779228 -439.8264)
		(width 0.1143)
		(layer "In5.Cu")
		(net "SEB_BA_RX-")
	)
	(segment
		(start 30.328362 -441.781184)
		(end 28.664662 -440.117484)
		(width 0.1143)
		(layer "In5.Cu")
		(net "SEB_BA_RX-")
	)
	(segment
		(start 28.664662 -440.117484)
		(end 28.664408 -440.117738)
		(width 0.1143)
		(layer "In5.Cu")
		(net "SEB_BA_RX-")
	)
	(segment
		(start 48.024796 -406.993852)
		(end 48.024796 -440.665108)
		(width 0.1143)
		(layer "In5.Cu")
		(net "SEB_BA_RX-")
	)
	(segment
		(start 47.836836 -404.837392)
		(end 47.836836 -405.180292)
		(width 0.1143)
		(layer "In5.Cu")
		(net "SEB_BA_RX-")
	)
	(segment
		(start 22.403308 -439.63844)
		(end 22.060408 -439.63844)
		(width 0.1143)
		(layer "In5.Cu")
		(net "SEB_BA_RX-")
	)
	(segment
		(start 16.838168 -438.4167)
		(end 12.405106 -438.4167)
		(width 0.1143)
		(layer "In5.Cu")
		(net "SEB_BA_RX-")
	)
	(segment
		(start 18.4277 -439.3057)
		(end 18.034 -438.912)
		(width 0.1143)
		(layer "In5.Cu")
		(net "SEB_BA_RX-")
	)
	(segment
		(start 24.559768 -439.8264)
		(end 24.216868 -439.8264)
		(width 0.1143)
		(layer "In5.Cu")
		(net "SEB_BA_RX-")
	)
	(segment
		(start 48.024796 -405.556212)
		(end 48.024796 -405.899112)
		(width 0.1143)
		(layer "In5.Cu")
		(net "SEB_BA_RX-")
	)
	(segment
		(start 47.78883 -441.23483)
		(end 47.17923 -441.84443)
		(width 0.1143)
		(layer "In5.Cu")
		(net "SEB_BA_RX-")
	)
	(segment
		(start 37.937694 -274.665694)
		(end 47.6123 -284.3403)
		(width 0.1143)
		(layer "In5.Cu")
		(net "SEB_BA_RX-")
	)
	(segment
		(start 48.024796 -404.118572)
		(end 48.024796 -404.461472)
		(width 0.1143)
		(layer "In5.Cu")
		(net "SEB_BA_RX-")
	)
	(segment
		(start 20.246848 -439.8264)
		(end 19.685 -439.8264)
		(width 0.1143)
		(layer "In5.Cu")
		(net "SEB_BA_RX-")
	)
	(segment
		(start 48.024796 -397.690594)
		(end 48.024796 -401.586192)
		(width 0.1143)
		(layer "In5.Cu")
		(net "SEB_BA_RX-")
	)
	(segment
		(start 47.836836 -406.275032)
		(end 47.836836 -406.617932)
		(width 0.1143)
		(layer "In5.Cu")
		(net "SEB_BA_RX-")
	)
	(segment
		(start 48.024796 -285.336234)
		(end 48.024796 -396.595854)
		(width 0.1143)
		(layer "In5.Cu")
		(net "SEB_BA_RX-")
	)
	(segment
		(start 47.836836 -401.962112)
		(end 47.836836 -402.305012)
		(width 0.1143)
		(layer "In5.Cu")
		(net "SEB_BA_RX-")
	)
	(segment
		(start 47.836836 -403.399752)
		(end 47.836836 -403.742652)
		(width 0.1143)
		(layer "In5.Cu")
		(net "SEB_BA_RX-")
	)
	(segment
		(start 48.024796 -402.680932)
		(end 48.024796 -403.023832)
		(width 0.1143)
		(layer "In5.Cu")
		(net "SEB_BA_RX-")
	)
	(arc
		(start 19.685 -439.8264)
		(mid 19.004575 -439.691073)
		(end 18.4277 -439.3057)
		(width 0.1143)
		(layer "In5.Cu")
		(net "SEB_BA_RX-")
	)
	(arc
		(start 48.024796 -396.595854)
		(mid 47.999552 -396.700694)
		(end 47.930816 -396.783814)
		(width 0.1143)
		(layer "In5.Cu")
		(net "SEB_BA_RX-")
	)
	(arc
		(start 20.434808 -439.73242)
		(mid 20.351714 -439.801156)
		(end 20.246848 -439.8264)
		(width 0.1143)
		(layer "In5.Cu")
		(net "SEB_BA_RX-")
	)
	(arc
		(start 48.024796 -404.461472)
		(mid 47.999552 -404.566312)
		(end 47.930816 -404.649432)
		(width 0.1143)
		(layer "In5.Cu")
		(net "SEB_BA_RX-")
	)
	(arc
		(start 47.930816 -404.649432)
		(mid 47.86208 -404.732526)
		(end 47.836836 -404.837392)
		(width 0.1143)
		(layer "In5.Cu")
		(net "SEB_BA_RX-")
	)
	(arc
		(start 22.779228 -439.8264)
		(mid 22.674388 -439.801156)
		(end 22.591268 -439.73242)
		(width 0.1143)
		(layer "In5.Cu")
		(net "SEB_BA_RX-")
	)
	(arc
		(start 47.836836 -405.180292)
		(mid 47.86208 -405.285132)
		(end 47.930816 -405.368252)
		(width 0.1143)
		(layer "In5.Cu")
		(net "SEB_BA_RX-")
	)
	(arc
		(start 47.836836 -402.305012)
		(mid 47.86208 -402.409852)
		(end 47.930816 -402.492972)
		(width 0.1143)
		(layer "In5.Cu")
		(net "SEB_BA_RX-")
	)
	(arc
		(start 21.872448 -439.73242)
		(mid 21.789354 -439.801156)
		(end 21.684488 -439.8264)
		(width 0.1143)
		(layer "In5.Cu")
		(net "SEB_BA_RX-")
	)
	(arc
		(start 18.034 -438.912)
		(mid 17.485348 -438.545402)
		(end 16.838168 -438.4167)
		(width 0.1143)
		(layer "In5.Cu")
		(net "SEB_BA_RX-")
	)
	(arc
		(start 28.664408 -440.117738)
		(mid 28.342085 -439.902246)
		(end 27.961844 -439.8264)
		(width 0.1143)
		(layer "In5.Cu")
		(net "SEB_BA_RX-")
	)
	(arc
		(start 34.919158 -274.618958)
		(mid 35.258978 -274.391898)
		(end 35.659822 -274.312126)
		(width 0.1143)
		(layer "In5.Cu")
		(net "SEB_BA_RX-")
	)
	(arc
		(start 47.17923 -441.84443)
		(mid 46.910847 -442.023758)
		(end 46.594268 -442.086746)
		(width 0.1143)
		(layer "In5.Cu")
		(net "SEB_BA_RX-")
	)
	(arc
		(start 47.930816 -406.805892)
		(mid 47.999552 -406.888986)
		(end 48.024796 -406.993852)
		(width 0.1143)
		(layer "In5.Cu")
		(net "SEB_BA_RX-")
	)
	(arc
		(start 37.084 -274.312126)
		(mid 37.546013 -274.404008)
		(end 37.937694 -274.665694)
		(width 0.1143)
		(layer "In5.Cu")
		(net "SEB_BA_RX-")
	)
	(arc
		(start 20.622768 -439.63844)
		(mid 20.517928 -439.663684)
		(end 20.434808 -439.73242)
		(width 0.1143)
		(layer "In5.Cu")
		(net "SEB_BA_RX-")
	)
	(arc
		(start 48.024796 -401.586192)
		(mid 47.999552 -401.691032)
		(end 47.930816 -401.774152)
		(width 0.1143)
		(layer "In5.Cu")
		(net "SEB_BA_RX-")
	)
	(arc
		(start 31.065978 -442.086746)
		(mid 30.666771 -442.007339)
		(end 30.328362 -441.781184)
		(width 0.1143)
		(layer "In5.Cu")
		(net "SEB_BA_RX-")
	)
	(arc
		(start 24.935688 -439.63844)
		(mid 24.830848 -439.663684)
		(end 24.747728 -439.73242)
		(width 0.1143)
		(layer "In5.Cu")
		(net "SEB_BA_RX-")
	)
	(arc
		(start 47.836836 -406.617932)
		(mid 47.86208 -406.722772)
		(end 47.930816 -406.805892)
		(width 0.1143)
		(layer "In5.Cu")
		(net "SEB_BA_RX-")
	)
	(arc
		(start 47.6123 -284.3403)
		(mid 47.917616 -284.797238)
		(end 48.024796 -285.336234)
		(width 0.1143)
		(layer "In5.Cu")
		(net "SEB_BA_RX-")
	)
	(arc
		(start 48.024796 -405.899112)
		(mid 47.999552 -406.003952)
		(end 47.930816 -406.087072)
		(width 0.1143)
		(layer "In5.Cu")
		(net "SEB_BA_RX-")
	)
	(arc
		(start 24.747728 -439.73242)
		(mid 24.664634 -439.801156)
		(end 24.559768 -439.8264)
		(width 0.1143)
		(layer "In5.Cu")
		(net "SEB_BA_RX-")
	)
	(arc
		(start 47.836836 -403.742652)
		(mid 47.86208 -403.847492)
		(end 47.930816 -403.930612)
		(width 0.1143)
		(layer "In5.Cu")
		(net "SEB_BA_RX-")
	)
	(arc
		(start 23.498048 -439.63844)
		(mid 23.393208 -439.663684)
		(end 23.310088 -439.73242)
		(width 0.1143)
		(layer "In5.Cu")
		(net "SEB_BA_RX-")
	)
	(arc
		(start 47.930816 -401.774152)
		(mid 47.86208 -401.857246)
		(end 47.836836 -401.962112)
		(width 0.1143)
		(layer "In5.Cu")
		(net "SEB_BA_RX-")
	)
	(arc
		(start 25.466548 -439.73242)
		(mid 25.383454 -439.663684)
		(end 25.278588 -439.63844)
		(width 0.1143)
		(layer "In5.Cu")
		(net "SEB_BA_RX-")
	)
	(arc
		(start 47.930816 -396.783814)
		(mid 47.86208 -396.866908)
		(end 47.836836 -396.971774)
		(width 0.1143)
		(layer "In5.Cu")
		(net "SEB_BA_RX-")
	)
	(arc
		(start 12.405106 -438.4167)
		(mid 11.997929 -438.335707)
		(end 11.652758 -438.105042)
		(width 0.1143)
		(layer "In5.Cu")
		(net "SEB_BA_RX-")
	)
	(arc
		(start 48.024796 -403.023832)
		(mid 47.999552 -403.128672)
		(end 47.930816 -403.211792)
		(width 0.1143)
		(layer "In5.Cu")
		(net "SEB_BA_RX-")
	)
	(arc
		(start 48.024796 -440.665108)
		(mid 47.963467 -440.973431)
		(end 47.78883 -441.23483)
		(width 0.1143)
		(layer "In5.Cu")
		(net "SEB_BA_RX-")
	)
	(arc
		(start 24.028908 -439.73242)
		(mid 23.945814 -439.663684)
		(end 23.840948 -439.63844)
		(width 0.1143)
		(layer "In5.Cu")
		(net "SEB_BA_RX-")
	)
	(arc
		(start 21.153628 -439.73242)
		(mid 21.070534 -439.663684)
		(end 20.965668 -439.63844)
		(width 0.1143)
		(layer "In5.Cu")
		(net "SEB_BA_RX-")
	)
	(arc
		(start 47.930816 -403.211792)
		(mid 47.86208 -403.294886)
		(end 47.836836 -403.399752)
		(width 0.1143)
		(layer "In5.Cu")
		(net "SEB_BA_RX-")
	)
	(arc
		(start 47.930816 -406.087072)
		(mid 47.86208 -406.170166)
		(end 47.836836 -406.275032)
		(width 0.1143)
		(layer "In5.Cu")
		(net "SEB_BA_RX-")
	)
	(arc
		(start 24.216868 -439.8264)
		(mid 24.112028 -439.801156)
		(end 24.028908 -439.73242)
		(width 0.1143)
		(layer "In5.Cu")
		(net "SEB_BA_RX-")
	)
	(arc
		(start 47.930816 -405.368252)
		(mid 47.999552 -405.451346)
		(end 48.024796 -405.556212)
		(width 0.1143)
		(layer "In5.Cu")
		(net "SEB_BA_RX-")
	)
	(arc
		(start 22.591268 -439.73242)
		(mid 22.508174 -439.663684)
		(end 22.403308 -439.63844)
		(width 0.1143)
		(layer "In5.Cu")
		(net "SEB_BA_RX-")
	)
	(arc
		(start 47.930816 -397.502634)
		(mid 47.999552 -397.585728)
		(end 48.024796 -397.690594)
		(width 0.1143)
		(layer "In5.Cu")
		(net "SEB_BA_RX-")
	)
	(arc
		(start 47.930816 -403.930612)
		(mid 47.999552 -404.013706)
		(end 48.024796 -404.118572)
		(width 0.1143)
		(layer "In5.Cu")
		(net "SEB_BA_RX-")
	)
	(arc
		(start 22.060408 -439.63844)
		(mid 21.955568 -439.663684)
		(end 21.872448 -439.73242)
		(width 0.1143)
		(layer "In5.Cu")
		(net "SEB_BA_RX-")
	)
	(arc
		(start 47.930816 -402.492972)
		(mid 47.999552 -402.576066)
		(end 48.024796 -402.680932)
		(width 0.1143)
		(layer "In5.Cu")
		(net "SEB_BA_RX-")
	)
	(arc
		(start 25.654508 -439.8264)
		(mid 25.549668 -439.801156)
		(end 25.466548 -439.73242)
		(width 0.1143)
		(layer "In5.Cu")
		(net "SEB_BA_RX-")
	)
	(arc
		(start 23.310088 -439.73242)
		(mid 23.226994 -439.801156)
		(end 23.122128 -439.8264)
		(width 0.1143)
		(layer "In5.Cu")
		(net "SEB_BA_RX-")
	)
	(arc
		(start 47.836836 -397.314674)
		(mid 47.86208 -397.419514)
		(end 47.930816 -397.502634)
		(width 0.1143)
		(layer "In5.Cu")
		(net "SEB_BA_RX-")
	)
	(arc
		(start 21.341588 -439.8264)
		(mid 21.236748 -439.801156)
		(end 21.153628 -439.73242)
		(width 0.1143)
		(layer "In5.Cu")
		(net "SEB_BA_RX-")
	)
	(segment
		(start 9.105392 -423.506392)
		(end 10.0965 -424.4975)
		(width 0.09525)
		(layer "F.Cu")
		(net "SEB_BA_RX+")
	)
	(segment
		(start 34.3535 -273.9898)
		(end 34.4551 -273.9898)
		(width 0.09525)
		(layer "F.Cu")
		(net "SEB_BA_RX+")
	)
	(segment
		(start 8.314182 -423.291)
		(end 8.5852 -423.291)
		(width 0.09525)
		(layer "F.Cu")
		(net "SEB_BA_RX+")
	)
	(segment
		(start 8.253476 -424.105324)
		(end 8.067548 -423.919396)
		(width 0.09525)
		(layer "F.Cu")
		(net "SEB_BA_RX+")
	)
	(segment
		(start 34.75355 -273.866356)
		(end 34.920174 -273.699478)
		(width 0.09525)
		(layer "F.Cu")
		(net "SEB_BA_RX+")
	)
	(segment
		(start 11.47953 -438.85993)
		(end 11.652758 -439.033158)
		(width 0.09525)
		(layer "F.Cu")
		(net "SEB_BA_RX+")
	)
	(segment
		(start 8.04037 -423.413936)
		(end 8.056626 -423.39768)
		(width 0.09525)
		(layer "F.Cu")
		(net "SEB_BA_RX+")
	)
	(segment
		(start 11.167364 -438.7342)
		(end 11.176 -438.7342)
		(width 0.09525)
		(layer "F.Cu")
		(net "SEB_BA_RX+")
	)
	(segment
		(start 7.9756 -423.6974)
		(end 7.9756 -423.5704)
		(width 0.09525)
		(layer "F.Cu")
		(net "SEB_BA_RX+")
	)
	(segment
		(start 33.7058 -273.7104)
		(end 33.724596 -273.72945)
		(width 0.09525)
		(layer "F.Cu")
		(net "SEB_BA_RX+")
	)
	(segment
		(start 10.4648 -425.386754)
		(end 10.4648 -437.996076)
		(width 0.09525)
		(layer "F.Cu")
		(net "SEB_BA_RX+")
	)
	(via
		(at 8.253476 -424.105324)
		(size 0.5588)
		(drill 0.3048)
		(layers "F.Cu" "B.Cu")
		(net "SEB_BA_RX+")
	)
	(via
		(at 11.652758 -439.033158)
		(size 0.5588)
		(drill 0.3048)
		(layers "F.Cu" "B.Cu")
		(net "SEB_BA_RX+")
	)
	(via
		(at 34.920174 -273.699478)
		(size 0.5588)
		(drill 0.3048)
		(layers "F.Cu" "B.Cu")
		(net "SEB_BA_RX+")
	)
	(arc
		(start 10.68832 -438.535826)
		(mid 10.908107 -438.682683)
		(end 11.167364 -438.7342)
		(width 0.09525)
		(layer "F.Cu")
		(net "SEB_BA_RX+")
	)
	(arc
		(start 8.5852 -423.291)
		(mid 8.86671 -423.346978)
		(end 9.105392 -423.506392)
		(width 0.09525)
		(layer "F.Cu")
		(net "SEB_BA_RX+")
	)
	(arc
		(start 8.067548 -423.919396)
		(mid 7.999492 -423.817543)
		(end 7.9756 -423.6974)
		(width 0.09525)
		(layer "F.Cu")
		(net "SEB_BA_RX+")
	)
	(arc
		(start 10.4648 -437.996076)
		(mid 10.5229 -438.288167)
		(end 10.68832 -438.535826)
		(width 0.09525)
		(layer "F.Cu")
		(net "SEB_BA_RX+")
	)
	(arc
		(start 11.176 -438.7342)
		(mid 11.340271 -438.766875)
		(end 11.47953 -438.85993)
		(width 0.09525)
		(layer "F.Cu")
		(net "SEB_BA_RX+")
	)
	(arc
		(start 8.056626 -423.39768)
		(mid 8.174794 -423.318723)
		(end 8.314182 -423.291)
		(width 0.09525)
		(layer "F.Cu")
		(net "SEB_BA_RX+")
	)
	(arc
		(start 7.9756 -423.5704)
		(mid 7.992425 -423.485723)
		(end 8.04037 -423.413936)
		(width 0.09525)
		(layer "F.Cu")
		(net "SEB_BA_RX+")
	)
	(arc
		(start 10.0965 -424.4975)
		(mid 10.369112 -424.905493)
		(end 10.4648 -425.386754)
		(width 0.09525)
		(layer "F.Cu")
		(net "SEB_BA_RX+")
	)
	(arc
		(start 34.4551 -273.9898)
		(mid 34.616606 -273.957768)
		(end 34.75355 -273.866356)
		(width 0.09525)
		(layer "F.Cu")
		(net "SEB_BA_RX+")
	)
	(arc
		(start 33.724596 -273.72945)
		(mid 34.013155 -273.922166)
		(end 34.3535 -273.9898)
		(width 0.09525)
		(layer "F.Cu")
		(net "SEB_BA_RX+")
	)
	(segment
		(start 7.828026 -423.36212)
		(end 6.736842 -422.270936)
		(width 0.09525)
		(layer "B.Cu")
		(net "SEB_BA_RX+")
	)
	(segment
		(start 6.736842 -422.270936)
		(end 6.70814 -422.241726)
		(width 0.09525)
		(layer "B.Cu")
		(net "SEB_BA_RX+")
	)
	(segment
		(start 4.837176 -421.498776)
		(end 2.811526 -421.498776)
		(width 0.09525)
		(layer "B.Cu")
		(net "SEB_BA_RX+")
	)
	(segment
		(start 5.715 -421.830754)
		(end 5.715 -421.8305)
		(width 0.09525)
		(layer "B.Cu")
		(net "SEB_BA_RX+")
	)
	(segment
		(start 4.8387 -421.5003)
		(end 4.837176 -421.498776)
		(width 0.09525)
		(layer "B.Cu")
		(net "SEB_BA_RX+")
	)
	(segment
		(start 8.253476 -424.105324)
		(end 8.052562 -423.904664)
		(width 0.09525)
		(layer "B.Cu")
		(net "SEB_BA_RX+")
	)
	(segment
		(start 5.715 -421.8305)
		(end 5.635752 -421.8305)
		(width 0.09525)
		(layer "B.Cu")
		(net "SEB_BA_RX+")
	)
	(segment
		(start 7.9248 -423.596308)
		(end 7.9248 -423.5958)
		(width 0.09525)
		(layer "B.Cu")
		(net "SEB_BA_RX+")
	)
	(arc
		(start 5.635752 -421.8305)
		(mid 5.520957 -421.807666)
		(end 5.423662 -421.742616)
		(width 0.09525)
		(layer "B.Cu")
		(net "SEB_BA_RX+")
	)
	(arc
		(start 8.052562 -423.904664)
		(mid 7.958031 -423.763189)
		(end 7.9248 -423.596308)
		(width 0.09525)
		(layer "B.Cu")
		(net "SEB_BA_RX+")
	)
	(arc
		(start 5.423662 -421.742616)
		(mid 5.155279 -421.563288)
		(end 4.8387 -421.5003)
		(width 0.09525)
		(layer "B.Cu")
		(net "SEB_BA_RX+")
	)
	(arc
		(start 7.9248 -423.5958)
		(mid 7.899646 -423.469341)
		(end 7.828026 -423.36212)
		(width 0.09525)
		(layer "B.Cu")
		(net "SEB_BA_RX+")
	)
	(arc
		(start 6.70814 -422.241726)
		(mid 6.252481 -421.937354)
		(end 5.715 -421.830754)
		(width 0.09525)
		(layer "B.Cu")
		(net "SEB_BA_RX+")
	)
	(segment
		(start 47.827946 -284.124654)
		(end 38.15334 -274.450048)
		(width 0.1143)
		(layer "In5.Cu")
		(net "SEB_BA_RX+")
	)
	(segment
		(start 12.405106 -438.7215)
		(end 16.838422 -438.7215)
		(width 0.1143)
		(layer "In5.Cu")
		(net "SEB_BA_RX+")
	)
	(segment
		(start 47.394622 -442.059822)
		(end 47.394876 -442.060076)
		(width 0.1143)
		(layer "In5.Cu")
		(net "SEB_BA_RX+")
	)
	(segment
		(start 28.449016 -440.33313)
		(end 30.112716 -441.99683)
		(width 0.1143)
		(layer "In5.Cu")
		(net "SEB_BA_RX+")
	)
	(segment
		(start 48.329596 -440.665108)
		(end 48.329596 -285.336488)
		(width 0.1143)
		(layer "In5.Cu")
		(net "SEB_BA_RX+")
	)
	(segment
		(start 19.685254 -440.1312)
		(end 27.96159 -440.1312)
		(width 0.1143)
		(layer "In5.Cu")
		(net "SEB_BA_RX+")
	)
	(segment
		(start 47.394876 -442.060076)
		(end 48.004476 -441.450476)
		(width 0.1143)
		(layer "In5.Cu")
		(net "SEB_BA_RX+")
	)
	(segment
		(start 30.112716 -441.99683)
		(end 30.11297 -441.996576)
		(width 0.1143)
		(layer "In5.Cu")
		(net "SEB_BA_RX+")
	)
	(segment
		(start 37.084254 -274.007326)
		(end 35.663378 -274.007326)
		(width 0.1143)
		(layer "In5.Cu")
		(net "SEB_BA_RX+")
	)
	(segment
		(start 47.827692 -284.124908)
		(end 47.827946 -284.124654)
		(width 0.1143)
		(layer "In5.Cu")
		(net "SEB_BA_RX+")
	)
	(segment
		(start 17.818354 -439.127646)
		(end 18.212054 -439.521346)
		(width 0.1143)
		(layer "In5.Cu")
		(net "SEB_BA_RX+")
	)
	(segment
		(start 31.065724 -442.391546)
		(end 46.594522 -442.391546)
		(width 0.1143)
		(layer "In5.Cu")
		(net "SEB_BA_RX+")
	)
	(segment
		(start 17.818608 -439.127392)
		(end 17.818354 -439.127646)
		(width 0.1143)
		(layer "In5.Cu")
		(net "SEB_BA_RX+")
	)
	(arc
		(start 11.652758 -439.033158)
		(mid 11.997938 -438.802516)
		(end 12.405106 -438.7215)
		(width 0.1143)
		(layer "In5.Cu")
		(net "SEB_BA_RX+")
	)
	(arc
		(start 27.96159 -440.1312)
		(mid 28.225395 -440.183674)
		(end 28.449016 -440.33313)
		(width 0.1143)
		(layer "In5.Cu")
		(net "SEB_BA_RX+")
	)
	(arc
		(start 18.212054 -439.521346)
		(mid 18.887994 -439.972809)
		(end 19.685254 -440.1312)
		(width 0.1143)
		(layer "In5.Cu")
		(net "SEB_BA_RX+")
	)
	(arc
		(start 30.11297 -441.996576)
		(mid 30.550081 -442.288767)
		(end 31.065724 -442.391546)
		(width 0.1143)
		(layer "In5.Cu")
		(net "SEB_BA_RX+")
	)
	(arc
		(start 48.004476 -441.450476)
		(mid 48.245158 -441.090131)
		(end 48.329596 -440.665108)
		(width 0.1143)
		(layer "In5.Cu")
		(net "SEB_BA_RX+")
	)
	(arc
		(start 48.329596 -285.336488)
		(mid 48.19915 -284.68078)
		(end 47.827692 -284.124908)
		(width 0.1143)
		(layer "In5.Cu")
		(net "SEB_BA_RX+")
	)
	(arc
		(start 35.663378 -274.007326)
		(mid 35.261158 -273.927319)
		(end 34.920174 -273.699478)
		(width 0.1143)
		(layer "In5.Cu")
		(net "SEB_BA_RX+")
	)
	(arc
		(start 16.838422 -438.7215)
		(mid 17.368865 -438.826994)
		(end 17.818608 -439.127392)
		(width 0.1143)
		(layer "In5.Cu")
		(net "SEB_BA_RX+")
	)
	(arc
		(start 38.15334 -274.450048)
		(mid 37.662811 -274.122413)
		(end 37.084254 -274.007326)
		(width 0.1143)
		(layer "In5.Cu")
		(net "SEB_BA_RX+")
	)
	(arc
		(start 46.594522 -442.391546)
		(mid 47.027559 -442.30524)
		(end 47.394622 -442.059822)
		(width 0.1143)
		(layer "In5.Cu")
		(net "SEB_BA_RX+")
	)
	(segment
		(start 226.0092 -433.8955)
		(end 226.0092 -434.721)
		(width 0.508)
		(layer "F.Cu")
		(net "P3V3_FB_R")
	)
	(segment
		(start 226.0092 -435.7624)
		(end 226.1616 -435.9148)
		(width 0.508)
		(layer "F.Cu")
		(net "P3V3_FB_R")
	)
	(segment
		(start 226.0092 -434.721)
		(end 226.0092 -435.7624)
		(width 0.508)
		(layer "F.Cu")
		(net "P3V3_FB_R")
	)
	(segment
		(start 225.9838 -433.8701)
		(end 226.0092 -433.8955)
		(width 0.508)
		(layer "F.Cu")
		(net "P3V3_FB_R")
	)
	(via
		(at 226.699318 -435.411118)
		(size 0.7112)
		(drill 0.3556)
		(layers "F.Cu" "B.Cu")
		(net "P3V3_FB_R")
	)
	(via
		(at 226.0092 -434.721)
		(size 0.5588)
		(drill 0.3048)
		(layers "F.Cu" "B.Cu")
		(net "P3V3_FB_R")
	)
	(segment
		(start 226.0092 -434.721)
		(end 226.699318 -435.411118)
		(width 0.508)
		(layer "B.Cu")
		(net "P3V3_FB_R")
	)
	(segment
		(start 20.637754 -155.3083)
		(end 20.637754 -154.241246)
		(width 0.508)
		(layer "F.Cu")
		(net "P5VC_HDD13_LED")
	)
	(segment
		(start 35.8902 -143.7386)
		(end 36.0934 -143.7386)
		(width 0.4064)
		(layer "F.Cu")
		(net "P5VC_HDD13_LED")
	)
	(segment
		(start 36.0934 -143.7386)
		(end 37.09924 -142.73276)
		(width 0.4064)
		(layer "F.Cu")
		(net "P5VC_HDD13_LED")
	)
	(segment
		(start 37.09924 -142.73276)
		(end 37.09924 -141.6558)
		(width 0.4064)
		(layer "F.Cu")
		(net "P5VC_HDD13_LED")
	)
	(via
		(at 34.8234 -144.907)
		(size 0.7112)
		(drill 0.3556)
		(layers "F.Cu" "B.Cu")
		(net "P5VC_HDD13_LED")
	)
	(via
		(at 35.8902 -143.7386)
		(size 0.5588)
		(drill 0.3048)
		(layers "F.Cu" "B.Cu")
		(net "P5VC_HDD13_LED")
	)
	(via
		(at 20.637754 -154.241246)
		(size 0.5588)
		(drill 0.3048)
		(layers "F.Cu" "B.Cu")
		(net "P5VC_HDD13_LED")
	)
	(segment
		(start 35.8902 -143.8148)
		(end 34.8234 -144.8816)
		(width 0.508)
		(layer "B.Cu")
		(net "P5VC_HDD13_LED")
	)
	(segment
		(start 34.8234 -144.8816)
		(end 34.8234 -144.907)
		(width 0.508)
		(layer "B.Cu")
		(net "P5VC_HDD13_LED")
	)
	(segment
		(start 35.8902 -143.7386)
		(end 35.8902 -143.8148)
		(width 0.508)
		(layer "B.Cu")
		(net "P5VC_HDD13_LED")
	)
	(segment
		(start 39.369746 -162.96513)
		(end 39.4462 -163.041584)
		(width 0.508)
		(layer "In5.Cu")
		(net "P5VC_HDD13_LED")
	)
	(segment
		(start 39.4462 -163.041584)
		(end 39.4462 -165.809676)
		(width 0.508)
		(layer "In5.Cu")
		(net "P5VC_HDD13_LED")
	)
	(segment
		(start 38.944804 -166.311072)
		(end 32.478472 -166.311072)
		(width 0.508)
		(layer "In5.Cu")
		(net "P5VC_HDD13_LED")
	)
	(segment
		(start 36.956746 -144.398746)
		(end 36.956746 -152.02535)
		(width 0.508)
		(layer "In5.Cu")
		(net "P5VC_HDD13_LED")
	)
	(segment
		(start 36.956746 -152.02535)
		(end 39.369746 -154.43835)
		(width 0.508)
		(layer "In5.Cu")
		(net "P5VC_HDD13_LED")
	)
	(segment
		(start 39.369746 -154.43835)
		(end 39.369746 -162.96513)
		(width 0.508)
		(layer "In5.Cu")
		(net "P5VC_HDD13_LED")
	)
	(segment
		(start 36.2966 -143.7386)
		(end 36.956746 -144.398746)
		(width 0.508)
		(layer "In5.Cu")
		(net "P5VC_HDD13_LED")
	)
	(segment
		(start 32.478472 -166.311072)
		(end 20.637754 -154.470354)
		(width 0.508)
		(layer "In5.Cu")
		(net "P5VC_HDD13_LED")
	)
	(segment
		(start 39.4462 -165.809676)
		(end 38.944804 -166.311072)
		(width 0.508)
		(layer "In5.Cu")
		(net "P5VC_HDD13_LED")
	)
	(segment
		(start 20.637754 -154.470354)
		(end 20.637754 -154.241246)
		(width 0.508)
		(layer "In5.Cu")
		(net "P5VC_HDD13_LED")
	)
	(segment
		(start 35.8902 -143.7386)
		(end 36.2966 -143.7386)
		(width 0.508)
		(layer "In5.Cu")
		(net "P5VC_HDD13_LED")
	)
	(segment
		(start 35.336226 -139.212574)
		(end 36.1188 -138.43)
		(width 0.111252)
		(layer "F.Cu")
		(net "HDD13_LED_G")
	)
	(segment
		(start 34.965894 -139.573)
		(end 35.32632 -139.212574)
		(width 0.111252)
		(layer "F.Cu")
		(net "HDD13_LED_G")
	)
	(segment
		(start 36.5125 -138.43)
		(end 36.5125 -139.7127)
		(width 0.111252)
		(layer "F.Cu")
		(net "HDD13_LED_G")
	)
	(segment
		(start 36.5125 -139.7127)
		(end 36.449 -139.7762)
		(width 0.111252)
		(layer "F.Cu")
		(net "HDD13_LED_G")
	)
	(segment
		(start 36.449 -141.6558)
		(end 36.449 -139.7762)
		(width 0.111252)
		(layer "F.Cu")
		(net "HDD13_LED_G")
	)
	(segment
		(start 34.3662 -139.573)
		(end 34.965894 -139.573)
		(width 0.111252)
		(layer "F.Cu")
		(net "HDD13_LED_G")
	)
	(segment
		(start 35.32632 -139.212574)
		(end 35.336226 -139.212574)
		(width 0.111252)
		(layer "F.Cu")
		(net "HDD13_LED_G")
	)
	(segment
		(start 36.83 -136.9187)
		(end 36.83 -138.1125)
		(width 0.111252)
		(layer "F.Cu")
		(net "HDD13_LED_G")
	)
	(segment
		(start 36.1188 -138.43)
		(end 36.5125 -138.43)
		(width 0.111252)
		(layer "F.Cu")
		(net "HDD13_LED_G")
	)
	(segment
		(start 36.83 -138.1125)
		(end 36.5125 -138.43)
		(width 0.111252)
		(layer "F.Cu")
		(net "HDD13_LED_G")
	)
	(via
		(at 34.3662 -139.573)
		(size 0.7112)
		(drill 0.3556)
		(layers "F.Cu" "B.Cu")
		(net "HDD13_LED_G")
	)
	(segment
		(start 34.569146 -136.398)
		(end 34.264346 -136.7028)
		(width 0.111252)
		(layer "F.Cu")
		(net "HDD13_LED_B")
	)
	(segment
		(start 34.5694 -135.675878)
		(end 34.569146 -135.676132)
		(width 0.111252)
		(layer "F.Cu")
		(net "HDD13_LED_B")
	)
	(segment
		(start 34.569146 -135.676132)
		(end 34.569146 -136.398)
		(width 0.111252)
		(layer "F.Cu")
		(net "HDD13_LED_B")
	)
	(segment
		(start 34.7218 -135.0137)
		(end 34.544 -135.1915)
		(width 0.111252)
		(layer "F.Cu")
		(net "HDD13_LED_B")
	)
	(segment
		(start 35.84575 -135.0137)
		(end 34.7218 -135.0137)
		(width 0.111252)
		(layer "F.Cu")
		(net "HDD13_LED_B")
	)
	(segment
		(start 34.5694 -135.3058)
		(end 34.5694 -135.675878)
		(width 0.111252)
		(layer "F.Cu")
		(net "HDD13_LED_B")
	)
	(segment
		(start 34.544 -135.1915)
		(end 34.5694 -135.3058)
		(width 0.111252)
		(layer "F.Cu")
		(net "HDD13_LED_B")
	)
	(via
		(at 34.264346 -136.7028)
		(size 0.7112)
		(drill 0.3556)
		(layers "F.Cu" "B.Cu")
		(net "HDD13_LED_B")
	)
	(segment
		(start 224.303082 -247.876568)
		(end 224.303082 -248.712482)
		(width 0.508)
		(layer "F.Cu")
		(net "P5VA_HDD2_LED")
	)
	(segment
		(start 209.25536 -271.86636)
		(end 208.3562 -271.86636)
		(width 0.4064)
		(layer "F.Cu")
		(net "P5VA_HDD2_LED")
	)
	(segment
		(start 209.7532 -272.3642)
		(end 209.25536 -271.86636)
		(width 0.4064)
		(layer "F.Cu")
		(net "P5VA_HDD2_LED")
	)
	(via
		(at 209.677 -273.3802)
		(size 0.7112)
		(drill 0.3556)
		(layers "F.Cu" "B.Cu")
		(net "P5VA_HDD2_LED")
	)
	(via
		(at 224.303082 -248.712482)
		(size 0.5588)
		(drill 0.3048)
		(layers "F.Cu" "B.Cu")
		(net "P5VA_HDD2_LED")
	)
	(via
		(at 209.7532 -272.3642)
		(size 0.5588)
		(drill 0.3048)
		(layers "F.Cu" "B.Cu")
		(net "P5VA_HDD2_LED")
	)
	(segment
		(start 209.677 -272.4404)
		(end 209.677 -273.3802)
		(width 0.508)
		(layer "B.Cu")
		(net "P5VA_HDD2_LED")
	)
	(segment
		(start 209.7532 -272.3642)
		(end 209.677 -272.4404)
		(width 0.508)
		(layer "B.Cu")
		(net "P5VA_HDD2_LED")
	)
	(segment
		(start 209.7532 -261.43331)
		(end 209.7532 -272.3642)
		(width 0.508)
		(layer "In2.Cu")
		(net "P5VA_HDD2_LED")
	)
	(segment
		(start 222.474028 -248.712482)
		(end 209.7532 -261.43331)
		(width 0.508)
		(layer "In2.Cu")
		(net "P5VA_HDD2_LED")
	)
	(segment
		(start 224.303082 -248.712482)
		(end 222.474028 -248.712482)
		(width 0.508)
		(layer "In2.Cu")
		(net "P5VA_HDD2_LED")
	)
	(segment
		(start 208.8134 -373.5578)
		(end 208.8134 -372.5672)
		(width 0.4064)
		(layer "F.Cu")
		(net "P5VA_HDD1_LED")
	)
	(segment
		(start 208.8134 -375.42216)
		(end 208.8134 -373.5578)
		(width 0.4064)
		(layer "F.Cu")
		(net "P5VA_HDD1_LED")
	)
	(segment
		(start 220.999558 -350.468184)
		(end 220.1418 -350.468184)
		(width 0.508)
		(layer "F.Cu")
		(net "P5VA_HDD1_LED")
	)
	(via
		(at 208.8134 -372.5672)
		(size 0.5588)
		(drill 0.3048)
		(layers "F.Cu" "B.Cu")
		(net "P5VA_HDD1_LED")
	)
	(via
		(at 220.1418 -350.468184)
		(size 0.5588)
		(drill 0.3048)
		(layers "F.Cu" "B.Cu")
		(net "P5VA_HDD1_LED")
	)
	(via
		(at 208.8134 -373.5578)
		(size 0.7112)
		(drill 0.3556)
		(layers "F.Cu" "B.Cu")
		(net "P5VA_HDD1_LED")
	)
	(segment
		(start 220.1418 -350.4692)
		(end 208.8134 -361.7976)
		(width 0.508)
		(layer "In2.Cu")
		(net "P5VA_HDD1_LED")
	)
	(segment
		(start 220.1418 -350.468184)
		(end 220.1418 -350.4692)
		(width 0.508)
		(layer "In2.Cu")
		(net "P5VA_HDD1_LED")
	)
	(segment
		(start 208.8134 -361.7976)
		(end 208.8134 -372.5672)
		(width 0.508)
		(layer "In2.Cu")
		(net "P5VA_HDD1_LED")
	)
	(segment
		(start 213.07425 -275.1455)
		(end 213.08695 -275.1328)
		(width 0.111252)
		(layer "F.Cu")
		(net "HDD2_LED_B")
	)
	(segment
		(start 214.3887 -275.1328)
		(end 214.3887 -272.9611)
		(width 0.111252)
		(layer "F.Cu")
		(net "HDD2_LED_B")
	)
	(segment
		(start 213.08695 -275.1328)
		(end 214.3887 -275.1328)
		(width 0.111252)
		(layer "F.Cu")
		(net "HDD2_LED_B")
	)
	(segment
		(start 214.3887 -272.9611)
		(end 214.6808 -272.669)
		(width 0.111252)
		(layer "F.Cu")
		(net "HDD2_LED_B")
	)
	(segment
		(start 214.6808 -272.669)
		(end 215.011 -272.669)
		(width 0.111252)
		(layer "F.Cu")
		(net "HDD2_LED_B")
	)
	(via
		(at 215.011 -272.669)
		(size 0.7112)
		(drill 0.3556)
		(layers "F.Cu" "B.Cu")
		(net "HDD2_LED_B")
	)
	(segment
		(start 209.7278 -273.2405)
		(end 212.09 -273.2405)
		(width 0.111252)
		(layer "F.Cu")
		(net "HDD2_LED_G")
	)
	(segment
		(start 212.09 -273.2405)
		(end 212.09 -271.2974)
		(width 0.111252)
		(layer "F.Cu")
		(net "HDD2_LED_G")
	)
	(segment
		(start 206.4766 -272.5166)
		(end 208.3562 -272.5166)
		(width 0.111252)
		(layer "F.Cu")
		(net "HDD2_LED_G")
	)
	(segment
		(start 208.3562 -272.5166)
		(end 209.0039 -272.5166)
		(width 0.111252)
		(layer "F.Cu")
		(net "HDD2_LED_G")
	)
	(segment
		(start 209.0039 -272.5166)
		(end 209.7278 -273.2405)
		(width 0.111252)
		(layer "F.Cu")
		(net "HDD2_LED_G")
	)
	(segment
		(start 212.09 -271.2974)
		(end 211.963 -271.1704)
		(width 0.111252)
		(layer "F.Cu")
		(net "HDD2_LED_G")
	)
	(via
		(at 211.963 -271.1704)
		(size 0.7112)
		(drill 0.3556)
		(layers "F.Cu" "B.Cu")
		(net "HDD2_LED_G")
	)
	(via
		(at 246.775732 -418.211)
		(size 0.5588)
		(drill 0.3048)
		(layers "F.Cu" "B.Cu")
		(net "SELF_TRAY_PRESENT")
	)
	(via
		(at 18.379948 -215.7857)
		(size 0.5588)
		(drill 0.3048)
		(layers "F.Cu" "B.Cu")
		(net "SELF_TRAY_PRESENT")
	)
	(via
		(at 10.083546 -465.7979)
		(size 0.5588)
		(drill 0.3048)
		(layers "F.Cu" "B.Cu")
		(net "SELF_TRAY_PRESENT")
	)
	(via
		(at 11.9888 -215.501474)
		(size 0.7112)
		(drill 0.3556)
		(layers "F.Cu" "B.Cu")
		(net "SELF_TRAY_PRESENT")
	)
	(segment
		(start 12.098274 -215.392)
		(end 11.9888 -215.501474)
		(width 0.111252)
		(layer "B.Cu")
		(net "SELF_TRAY_PRESENT")
	)
	(segment
		(start 3.10896 -465.7979)
		(end 2.812542 -465.501482)
		(width 0.111252)
		(layer "B.Cu")
		(net "SELF_TRAY_PRESENT")
	)
	(segment
		(start 10.083546 -465.7979)
		(end 3.10896 -465.7979)
		(width 0.111252)
		(layer "B.Cu")
		(net "SELF_TRAY_PRESENT")
	)
	(segment
		(start 2.812542 -215.501474)
		(end 11.9888 -215.501474)
		(width 0.111252)
		(layer "B.Cu")
		(net "SELF_TRAY_PRESENT")
	)
	(segment
		(start 18.379948 -215.7857)
		(end 17.986248 -215.392)
		(width 0.111252)
		(layer "B.Cu")
		(net "SELF_TRAY_PRESENT")
	)
	(segment
		(start 252.246892 -418.109908)
		(end 251.810774 -418.546026)
		(width 0.111252)
		(layer "B.Cu")
		(net "SELF_TRAY_PRESENT")
	)
	(segment
		(start 17.986248 -215.392)
		(end 12.098274 -215.392)
		(width 0.111252)
		(layer "B.Cu")
		(net "SELF_TRAY_PRESENT")
	)
	(segment
		(start 2.812542 -465.501482)
		(end 2.80924 -465.504784)
		(width 0.111252)
		(layer "B.Cu")
		(net "SELF_TRAY_PRESENT")
	)
	(segment
		(start 250.806966 -418.211)
		(end 246.775732 -418.211)
		(width 0.111252)
		(layer "B.Cu")
		(net "SELF_TRAY_PRESENT")
	)
	(segment
		(start 251.141992 -418.546026)
		(end 250.806966 -418.211)
		(width 0.111252)
		(layer "B.Cu")
		(net "SELF_TRAY_PRESENT")
	)
	(segment
		(start 2.80924 -215.504776)
		(end 2.812542 -215.501474)
		(width 0.111252)
		(layer "B.Cu")
		(net "SELF_TRAY_PRESENT")
	)
	(segment
		(start 251.810774 -418.546026)
		(end 251.141992 -418.546026)
		(width 0.111252)
		(layer "B.Cu")
		(net "SELF_TRAY_PRESENT")
	)
	(segment
		(start 255.093978 -418.109908)
		(end 252.246892 -418.109908)
		(width 0.111252)
		(layer "B.Cu")
		(net "SELF_TRAY_PRESENT")
	)
	(segment
		(start 13.63345 -462.247996)
		(end 13.63345 -450.00799)
		(width 0.14605)
		(layer "In2.Cu")
		(net "SELF_TRAY_PRESENT")
	)
	(segment
		(start 19.157696 -377.351798)
		(end 19.15795 -377.351544)
		(width 0.14605)
		(layer "In2.Cu")
		(net "SELF_TRAY_PRESENT")
	)
	(segment
		(start 22.45995 -421.287956)
		(end 22.45995 -419.832282)
		(width 0.14605)
		(layer "In2.Cu")
		(net "SELF_TRAY_PRESENT")
	)
	(segment
		(start 19.783552 -364.188248)
		(end 19.783552 -360.976418)
		(width 0.14605)
		(layer "In2.Cu")
		(net "SELF_TRAY_PRESENT")
	)
	(segment
		(start 19.15795 -377.351544)
		(end 19.15795 -364.81385)
		(width 0.14605)
		(layer "In2.Cu")
		(net "SELF_TRAY_PRESENT")
	)
	(segment
		(start 10.083546 -465.7979)
		(end 13.63345 -462.247996)
		(width 0.14605)
		(layer "In2.Cu")
		(net "SELF_TRAY_PRESENT")
	)
	(segment
		(start 19.27098 -348.799404)
		(end 19.27098 -344.66784)
		(width 0.14605)
		(layer "In2.Cu")
		(net "SELF_TRAY_PRESENT")
	)
	(segment
		(start 22.45995 -419.832282)
		(end 22.507702 -419.592506)
		(width 0.14605)
		(layer "In2.Cu")
		(net "SELF_TRAY_PRESENT")
	)
	(segment
		(start 19.27098 -344.66784)
		(end 19.619468 -344.319352)
		(width 0.14605)
		(layer "In2.Cu")
		(net "SELF_TRAY_PRESENT")
	)
	(segment
		(start 19.157696 -377.411234)
		(end 19.157696 -377.351798)
		(width 0.14605)
		(layer "In2.Cu")
		(net "SELF_TRAY_PRESENT")
	)
	(segment
		(start 22.507702 -419.067742)
		(end 22.45995 -418.827966)
		(width 0.14605)
		(layer "In2.Cu")
		(net "SELF_TRAY_PRESENT")
	)
	(segment
		(start 22.45995 -418.827966)
		(end 22.45995 -417.38423)
		(width 0.14605)
		(layer "In2.Cu")
		(net "SELF_TRAY_PRESENT")
	)
	(segment
		(start 22.056852 -335.472024)
		(end 22.056852 -257.179826)
		(width 0.14605)
		(layer "In2.Cu")
		(net "SELF_TRAY_PRESENT")
	)
	(segment
		(start 20.025868 -337.503008)
		(end 22.056852 -335.472024)
		(width 0.14605)
		(layer "In2.Cu")
		(net "SELF_TRAY_PRESENT")
	)
	(segment
		(start 20.155916 -343.533476)
		(end 20.025868 -343.403428)
		(width 0.14605)
		(layer "In2.Cu")
		(net "SELF_TRAY_PRESENT")
	)
	(segment
		(start 18.372328 -247.368822)
		(end 18.372328 -215.79332)
		(width 0.14605)
		(layer "In2.Cu")
		(net "SELF_TRAY_PRESENT")
	)
	(segment
		(start 19.783552 -360.976418)
		(end 22.958552 -357.801418)
		(width 0.14605)
		(layer "In2.Cu")
		(net "SELF_TRAY_PRESENT")
	)
	(segment
		(start 22.45995 -417.38423)
		(end 18.027396 -412.951676)
		(width 0.14605)
		(layer "In2.Cu")
		(net "SELF_TRAY_PRESENT")
	)
	(segment
		(start 19.619468 -344.319352)
		(end 19.830288 -344.319352)
		(width 0.14605)
		(layer "In2.Cu")
		(net "SELF_TRAY_PRESENT")
	)
	(segment
		(start 18.027396 -412.951676)
		(end 18.027396 -398.2466)
		(width 0.14605)
		(layer "In2.Cu")
		(net "SELF_TRAY_PRESENT")
	)
	(segment
		(start 22.056852 -257.179826)
		(end 21.421598 -256.544572)
		(width 0.14605)
		(layer "In2.Cu")
		(net "SELF_TRAY_PRESENT")
	)
	(segment
		(start 17.969738 -445.671702)
		(end 17.969738 -425.778168)
		(width 0.14605)
		(layer "In2.Cu")
		(net "SELF_TRAY_PRESENT")
	)
	(segment
		(start 18.119598 -398.154398)
		(end 18.119598 -396.311628)
		(width 0.14605)
		(layer "In2.Cu")
		(net "SELF_TRAY_PRESENT")
	)
	(segment
		(start 21.421598 -256.544572)
		(end 21.421598 -255.773428)
		(width 0.14605)
		(layer "In2.Cu")
		(net "SELF_TRAY_PRESENT")
	)
	(segment
		(start 18.874994 -395.556232)
		(end 18.874994 -377.693936)
		(width 0.14605)
		(layer "In2.Cu")
		(net "SELF_TRAY_PRESENT")
	)
	(segment
		(start 18.372328 -215.79332)
		(end 18.379948 -215.7857)
		(width 0.14605)
		(layer "In2.Cu")
		(net "SELF_TRAY_PRESENT")
	)
	(segment
		(start 18.119598 -396.311628)
		(end 18.874994 -395.556232)
		(width 0.14605)
		(layer "In2.Cu")
		(net "SELF_TRAY_PRESENT")
	)
	(segment
		(start 22.958552 -352.486976)
		(end 19.27098 -348.799404)
		(width 0.14605)
		(layer "In2.Cu")
		(net "SELF_TRAY_PRESENT")
	)
	(segment
		(start 21.421598 -255.773428)
		(end 21.878798 -255.316228)
		(width 0.14605)
		(layer "In2.Cu")
		(net "SELF_TRAY_PRESENT")
	)
	(segment
		(start 22.507702 -419.592506)
		(end 22.507702 -419.067742)
		(width 0.14605)
		(layer "In2.Cu")
		(net "SELF_TRAY_PRESENT")
	)
	(segment
		(start 20.155916 -343.993724)
		(end 20.155916 -343.533476)
		(width 0.14605)
		(layer "In2.Cu")
		(net "SELF_TRAY_PRESENT")
	)
	(segment
		(start 18.874994 -377.693936)
		(end 19.157696 -377.411234)
		(width 0.14605)
		(layer "In2.Cu")
		(net "SELF_TRAY_PRESENT")
	)
	(segment
		(start 21.878798 -255.316228)
		(end 21.878798 -250.875292)
		(width 0.14605)
		(layer "In2.Cu")
		(net "SELF_TRAY_PRESENT")
	)
	(segment
		(start 19.15795 -364.81385)
		(end 19.783552 -364.188248)
		(width 0.14605)
		(layer "In2.Cu")
		(net "SELF_TRAY_PRESENT")
	)
	(segment
		(start 19.830288 -344.319352)
		(end 20.155916 -343.993724)
		(width 0.14605)
		(layer "In2.Cu")
		(net "SELF_TRAY_PRESENT")
	)
	(segment
		(start 17.969738 -425.778168)
		(end 22.45995 -421.287956)
		(width 0.14605)
		(layer "In2.Cu")
		(net "SELF_TRAY_PRESENT")
	)
	(segment
		(start 22.958552 -357.801418)
		(end 22.958552 -352.486976)
		(width 0.14605)
		(layer "In2.Cu")
		(net "SELF_TRAY_PRESENT")
	)
	(segment
		(start 21.878798 -250.875292)
		(end 18.372328 -247.368822)
		(width 0.14605)
		(layer "In2.Cu")
		(net "SELF_TRAY_PRESENT")
	)
	(segment
		(start 20.025868 -343.403428)
		(end 20.025868 -337.503008)
		(width 0.14605)
		(layer "In2.Cu")
		(net "SELF_TRAY_PRESENT")
	)
	(segment
		(start 13.63345 -450.00799)
		(end 17.969738 -445.671702)
		(width 0.14605)
		(layer "In2.Cu")
		(net "SELF_TRAY_PRESENT")
	)
	(segment
		(start 18.027396 -398.2466)
		(end 18.119598 -398.154398)
		(width 0.14605)
		(layer "In2.Cu")
		(net "SELF_TRAY_PRESENT")
	)
	(segment
		(start 35.070288 -470.434162)
		(end 203.799948 -470.434162)
		(width 0.14605)
		(layer "In5.Cu")
		(net "SELF_TRAY_PRESENT")
	)
	(segment
		(start 34.71545 -470.789)
		(end 35.070288 -470.434162)
		(width 0.14605)
		(layer "In5.Cu")
		(net "SELF_TRAY_PRESENT")
	)
	(segment
		(start 203.799948 -470.434162)
		(end 246.775732 -427.458378)
		(width 0.14605)
		(layer "In5.Cu")
		(net "SELF_TRAY_PRESENT")
	)
	(segment
		(start 10.083546 -465.7979)
		(end 10.083546 -466.072474)
		(width 0.14605)
		(layer "In5.Cu")
		(net "SELF_TRAY_PRESENT")
	)
	(segment
		(start 11.049762 -467.03869)
		(end 11.049762 -467.716108)
		(width 0.14605)
		(layer "In5.Cu")
		(net "SELF_TRAY_PRESENT")
	)
	(segment
		(start 10.083546 -466.072474)
		(end 11.049762 -467.03869)
		(width 0.14605)
		(layer "In5.Cu")
		(net "SELF_TRAY_PRESENT")
	)
	(segment
		(start 14.122654 -470.789)
		(end 34.71545 -470.789)
		(width 0.14605)
		(layer "In5.Cu")
		(net "SELF_TRAY_PRESENT")
	)
	(segment
		(start 246.775732 -427.458378)
		(end 246.775732 -418.211)
		(width 0.14605)
		(layer "In5.Cu")
		(net "SELF_TRAY_PRESENT")
	)
	(segment
		(start 11.049762 -467.716108)
		(end 14.122654 -470.789)
		(width 0.14605)
		(layer "In5.Cu")
		(net "SELF_TRAY_PRESENT")
	)
	(via
		(at 10.947146 -465.7979)
		(size 0.5588)
		(drill 0.3048)
		(layers "F.Cu" "B.Cu")
		(net "PEER_TRAY_PRESENT")
	)
	(via
		(at 15.6464 -216.034874)
		(size 0.7112)
		(drill 0.3556)
		(layers "F.Cu" "B.Cu")
		(net "PEER_TRAY_PRESENT")
	)
	(via
		(at 18.85188 -216.9541)
		(size 0.5588)
		(drill 0.3048)
		(layers "F.Cu" "B.Cu")
		(net "PEER_TRAY_PRESENT")
	)
	(via
		(at 246.2784 -416.1282)
		(size 0.5588)
		(drill 0.3048)
		(layers "F.Cu" "B.Cu")
		(net "PEER_TRAY_PRESENT")
	)
	(segment
		(start 5.070602 -216.174574)
		(end 4.740402 -216.504774)
		(width 0.111252)
		(layer "B.Cu")
		(net "PEER_TRAY_PRESENT")
	)
	(segment
		(start 9.766046 -466.979)
		(end 5.446776 -466.979)
		(width 0.111252)
		(layer "B.Cu")
		(net "PEER_TRAY_PRESENT")
	)
	(segment
		(start 18.85188 -216.9541)
		(end 17.932654 -216.034874)
		(width 0.111252)
		(layer "B.Cu")
		(net "PEER_TRAY_PRESENT")
	)
	(segment
		(start 246.836692 -415.569908)
		(end 255.093978 -415.569908)
		(width 0.111252)
		(layer "B.Cu")
		(net "PEER_TRAY_PRESENT")
	)
	(segment
		(start 4.972558 -466.504782)
		(end 2.80924 -466.504782)
		(width 0.111252)
		(layer "B.Cu")
		(net "PEER_TRAY_PRESENT")
	)
	(segment
		(start 15.5067 -216.174574)
		(end 5.070602 -216.174574)
		(width 0.111252)
		(layer "B.Cu")
		(net "PEER_TRAY_PRESENT")
	)
	(segment
		(start 10.947146 -465.7979)
		(end 9.766046 -466.979)
		(width 0.111252)
		(layer "B.Cu")
		(net "PEER_TRAY_PRESENT")
	)
	(segment
		(start 17.932654 -216.034874)
		(end 15.6464 -216.034874)
		(width 0.111252)
		(layer "B.Cu")
		(net "PEER_TRAY_PRESENT")
	)
	(segment
		(start 5.446776 -466.979)
		(end 4.972558 -466.504782)
		(width 0.111252)
		(layer "B.Cu")
		(net "PEER_TRAY_PRESENT")
	)
	(segment
		(start 15.6464 -216.034874)
		(end 15.5067 -216.174574)
		(width 0.111252)
		(layer "B.Cu")
		(net "PEER_TRAY_PRESENT")
	)
	(segment
		(start 4.740402 -216.504774)
		(end 2.80924 -216.504774)
		(width 0.111252)
		(layer "B.Cu")
		(net "PEER_TRAY_PRESENT")
	)
	(segment
		(start 246.2784 -416.1282)
		(end 246.836692 -415.569908)
		(width 0.111252)
		(layer "B.Cu")
		(net "PEER_TRAY_PRESENT")
	)
	(segment
		(start 14.0843 -462.660492)
		(end 14.0843 -450.194934)
		(width 0.14605)
		(layer "In2.Cu")
		(net "PEER_TRAY_PRESENT")
	)
	(segment
		(start 20.372578 -361.025186)
		(end 23.409402 -357.988362)
		(width 0.14605)
		(layer "In2.Cu")
		(net "PEER_TRAY_PRESENT")
	)
	(segment
		(start 23.409402 -357.988362)
		(end 23.409402 -352.300032)
		(width 0.14605)
		(layer "In2.Cu")
		(net "PEER_TRAY_PRESENT")
	)
	(segment
		(start 22.507702 -336.054192)
		(end 22.507702 -256.992882)
		(width 0.14605)
		(layer "In2.Cu")
		(net "PEER_TRAY_PRESENT")
	)
	(segment
		(start 18.570448 -396.498572)
		(end 19.586448 -395.482572)
		(width 0.14605)
		(layer "In2.Cu")
		(net "PEER_TRAY_PRESENT")
	)
	(segment
		(start 23.409402 -352.300032)
		(end 23.174452 -352.065082)
		(width 0.14605)
		(layer "In2.Cu")
		(net "PEER_TRAY_PRESENT")
	)
	(segment
		(start 14.0843 -450.194934)
		(end 18.420588 -445.858646)
		(width 0.14605)
		(layer "In2.Cu")
		(net "PEER_TRAY_PRESENT")
	)
	(segment
		(start 10.947146 -465.7979)
		(end 14.0843 -462.660492)
		(width 0.14605)
		(layer "In2.Cu")
		(net "PEER_TRAY_PRESENT")
	)
	(segment
		(start 23.174452 -352.065082)
		(end 23.174452 -345.914218)
		(width 0.14605)
		(layer "In2.Cu")
		(net "PEER_TRAY_PRESENT")
	)
	(segment
		(start 18.478246 -412.764732)
		(end 18.478246 -398.435068)
		(width 0.14605)
		(layer "In2.Cu")
		(net "PEER_TRAY_PRESENT")
	)
	(segment
		(start 20.476718 -338.085176)
		(end 22.507702 -336.054192)
		(width 0.14605)
		(layer "In2.Cu")
		(net "PEER_TRAY_PRESENT")
	)
	(segment
		(start 21.872448 -256.357628)
		(end 21.872448 -255.960372)
		(width 0.14605)
		(layer "In2.Cu")
		(net "PEER_TRAY_PRESENT")
	)
	(segment
		(start 22.9108 -419.876986)
		(end 22.958552 -419.63721)
		(width 0.14605)
		(layer "In2.Cu")
		(net "PEER_TRAY_PRESENT")
	)
	(segment
		(start 18.420588 -425.965112)
		(end 22.9108 -421.4749)
		(width 0.14605)
		(layer "In2.Cu")
		(net "PEER_TRAY_PRESENT")
	)
	(segment
		(start 22.958552 -419.63721)
		(end 22.958552 -419.023038)
		(width 0.14605)
		(layer "In2.Cu")
		(net "PEER_TRAY_PRESENT")
	)
	(segment
		(start 20.372578 -391.631678)
		(end 20.372578 -361.025186)
		(width 0.14605)
		(layer "In2.Cu")
		(net "PEER_TRAY_PRESENT")
	)
	(segment
		(start 21.872448 -255.960372)
		(end 22.329648 -255.503172)
		(width 0.14605)
		(layer "In2.Cu")
		(net "PEER_TRAY_PRESENT")
	)
	(segment
		(start 18.420588 -445.858646)
		(end 18.420588 -425.965112)
		(width 0.14605)
		(layer "In2.Cu")
		(net "PEER_TRAY_PRESENT")
	)
	(segment
		(start 19.586448 -392.417808)
		(end 20.372578 -391.631678)
		(width 0.14605)
		(layer "In2.Cu")
		(net "PEER_TRAY_PRESENT")
	)
	(segment
		(start 18.478246 -398.435068)
		(end 18.570448 -398.342866)
		(width 0.14605)
		(layer "In2.Cu")
		(net "PEER_TRAY_PRESENT")
	)
	(segment
		(start 22.329648 -255.503172)
		(end 22.329648 -250.688348)
		(width 0.14605)
		(layer "In2.Cu")
		(net "PEER_TRAY_PRESENT")
	)
	(segment
		(start 22.507702 -256.992882)
		(end 21.872448 -256.357628)
		(width 0.14605)
		(layer "In2.Cu")
		(net "PEER_TRAY_PRESENT")
	)
	(segment
		(start 22.9108 -421.4749)
		(end 22.9108 -419.876986)
		(width 0.14605)
		(layer "In2.Cu")
		(net "PEER_TRAY_PRESENT")
	)
	(segment
		(start 23.174452 -345.914218)
		(end 20.476718 -343.216484)
		(width 0.14605)
		(layer "In2.Cu")
		(net "PEER_TRAY_PRESENT")
	)
	(segment
		(start 22.9108 -418.783262)
		(end 22.9108 -417.197286)
		(width 0.14605)
		(layer "In2.Cu")
		(net "PEER_TRAY_PRESENT")
	)
	(segment
		(start 18.85188 -247.21058)
		(end 18.85188 -216.9541)
		(width 0.14605)
		(layer "In2.Cu")
		(net "PEER_TRAY_PRESENT")
	)
	(segment
		(start 20.476718 -343.216484)
		(end 20.476718 -338.085176)
		(width 0.14605)
		(layer "In2.Cu")
		(net "PEER_TRAY_PRESENT")
	)
	(segment
		(start 22.958552 -419.023038)
		(end 22.9108 -418.783262)
		(width 0.14605)
		(layer "In2.Cu")
		(net "PEER_TRAY_PRESENT")
	)
	(segment
		(start 22.9108 -417.197286)
		(end 18.478246 -412.764732)
		(width 0.14605)
		(layer "In2.Cu")
		(net "PEER_TRAY_PRESENT")
	)
	(segment
		(start 19.586448 -395.482572)
		(end 19.586448 -392.417808)
		(width 0.14605)
		(layer "In2.Cu")
		(net "PEER_TRAY_PRESENT")
	)
	(segment
		(start 22.329648 -250.688348)
		(end 18.85188 -247.21058)
		(width 0.14605)
		(layer "In2.Cu")
		(net "PEER_TRAY_PRESENT")
	)
	(segment
		(start 18.570448 -398.342866)
		(end 18.570448 -396.498572)
		(width 0.14605)
		(layer "In2.Cu")
		(net "PEER_TRAY_PRESENT")
	)
	(segment
		(start 246.2784 -416.1282)
		(end 246.2784 -427.317916)
		(width 0.14605)
		(layer "In5.Cu")
		(net "PEER_TRAY_PRESENT")
	)
	(segment
		(start 11.500612 -467.529164)
		(end 11.500612 -466.851746)
		(width 0.14605)
		(layer "In5.Cu")
		(net "PEER_TRAY_PRESENT")
	)
	(segment
		(start 246.2784 -427.317916)
		(end 203.620116 -469.9762)
		(width 0.14605)
		(layer "In5.Cu")
		(net "PEER_TRAY_PRESENT")
	)
	(segment
		(start 10.947146 -466.29828)
		(end 10.947146 -465.7979)
		(width 0.14605)
		(layer "In5.Cu")
		(net "PEER_TRAY_PRESENT")
	)
	(segment
		(start 34.680906 -470.119202)
		(end 14.09065 -470.119202)
		(width 0.14605)
		(layer "In5.Cu")
		(net "PEER_TRAY_PRESENT")
	)
	(segment
		(start 34.823908 -469.9762)
		(end 34.680906 -470.119202)
		(width 0.14605)
		(layer "In5.Cu")
		(net "PEER_TRAY_PRESENT")
	)
	(segment
		(start 11.500612 -466.851746)
		(end 10.947146 -466.29828)
		(width 0.14605)
		(layer "In5.Cu")
		(net "PEER_TRAY_PRESENT")
	)
	(segment
		(start 203.620116 -469.9762)
		(end 34.823908 -469.9762)
		(width 0.14605)
		(layer "In5.Cu")
		(net "PEER_TRAY_PRESENT")
	)
	(segment
		(start 14.09065 -470.119202)
		(end 11.500612 -467.529164)
		(width 0.14605)
		(layer "In5.Cu")
		(net "PEER_TRAY_PRESENT")
	)
	(segment
		(start 44.3992 -234.315)
		(end 44.3992 -235.0262)
		(width 0.111252)
		(layer "F.Cu")
		(net "HDD12_LED_B")
	)
	(segment
		(start 44.59605 -234.3658)
		(end 44.3865 -234.3658)
		(width 0.111252)
		(layer "F.Cu")
		(net "HDD12_LED_B")
	)
	(segment
		(start 44.3865 -234.3658)
		(end 44.3992 -234.315)
		(width 0.111252)
		(layer "F.Cu")
		(net "HDD12_LED_B")
	)
	(segment
		(start 45.72635 -233.2355)
		(end 44.59605 -234.3658)
		(width 0.111252)
		(layer "F.Cu")
		(net "HDD12_LED_B")
	)
	(segment
		(start 44.3992 -235.0262)
		(end 43.9674 -235.458)
		(width 0.111252)
		(layer "F.Cu")
		(net "HDD12_LED_B")
	)
	(segment
		(start 43.9674 -235.458)
		(end 43.434 -235.458)
		(width 0.111252)
		(layer "F.Cu")
		(net "HDD12_LED_B")
	)
	(via
		(at 43.434 -235.458)
		(size 0.7112)
		(drill 0.3556)
		(layers "F.Cu" "B.Cu")
		(net "HDD12_LED_B")
	)
	(segment
		(start 46.6979 -236.6264)
		(end 46.7106 -236.6137)
		(width 0.111252)
		(layer "F.Cu")
		(net "HDD12_LED_G")
	)
	(segment
		(start 46.7106 -235.1405)
		(end 46.7614 -235.077)
		(width 0.111252)
		(layer "F.Cu")
		(net "HDD12_LED_G")
	)
	(segment
		(start 46.7106 -238.0234)
		(end 46.6979 -238.0107)
		(width 0.111252)
		(layer "F.Cu")
		(net "HDD12_LED_G")
	)
	(segment
		(start 46.7106 -236.6137)
		(end 46.7106 -235.1405)
		(width 0.111252)
		(layer "F.Cu")
		(net "HDD12_LED_G")
	)
	(segment
		(start 46.7614 -235.077)
		(end 49.4792 -235.077)
		(width 0.111252)
		(layer "F.Cu")
		(net "HDD12_LED_G")
	)
	(segment
		(start 46.6979 -238.0107)
		(end 46.6979 -236.6264)
		(width 0.111252)
		(layer "F.Cu")
		(net "HDD12_LED_G")
	)
	(segment
		(start 46.7106 -239.903)
		(end 46.7106 -238.0234)
		(width 0.111252)
		(layer "F.Cu")
		(net "HDD12_LED_G")
	)
	(via
		(at 49.4792 -235.077)
		(size 0.7112)
		(drill 0.3556)
		(layers "F.Cu" "B.Cu")
		(net "HDD12_LED_G")
	)
	(segment
		(start 47.371 -240.919)
		(end 47.371 -239.91316)
		(width 0.4064)
		(layer "F.Cu")
		(net "P5VC_HDD12_LED")
	)
	(segment
		(start 47.371 -239.91316)
		(end 47.36084 -239.903)
		(width 0.4064)
		(layer "F.Cu")
		(net "P5VC_HDD12_LED")
	)
	(segment
		(start 43.2435 -240.919)
		(end 43.4975 -241.173)
		(width 0.4064)
		(layer "F.Cu")
		(net "P5VC_HDD12_LED")
	)
	(segment
		(start 21.5265 -256.159)
		(end 22.352 -256.159)
		(width 0.508)
		(layer "F.Cu")
		(net "P5VC_HDD12_LED")
	)
	(segment
		(start 43.4975 -241.173)
		(end 47.117 -241.173)
		(width 0.4064)
		(layer "F.Cu")
		(net "P5VC_HDD12_LED")
	)
	(segment
		(start 47.117 -241.173)
		(end 47.371 -240.919)
		(width 0.4064)
		(layer "F.Cu")
		(net "P5VC_HDD12_LED")
	)
	(via
		(at 22.352 -256.159)
		(size 0.5588)
		(drill 0.3048)
		(layers "F.Cu" "B.Cu")
		(net "P5VC_HDD12_LED")
	)
	(via
		(at 43.2435 -240.919)
		(size 0.5588)
		(drill 0.3048)
		(layers "F.Cu" "B.Cu")
		(net "P5VC_HDD12_LED")
	)
	(via
		(at 25.1968 -252.5268)
		(size 0.7112)
		(drill 0.3556)
		(layers "F.Cu" "B.Cu")
		(net "P5VC_HDD12_LED")
	)
	(via
		(at 26.2128 -250.282456)
		(size 0.5588)
		(drill 0.3048)
		(layers "F.Cu" "B.Cu")
		(net "P5VC_HDD12_LED")
	)
	(segment
		(start 25.1968 -252.5268)
		(end 25.1968 -251.298456)
		(width 0.508)
		(layer "B.Cu")
		(net "P5VC_HDD12_LED")
	)
	(segment
		(start 23.1394 -256.159)
		(end 25.1968 -254.1016)
		(width 0.508)
		(layer "B.Cu")
		(net "P5VC_HDD12_LED")
	)
	(segment
		(start 22.352 -256.159)
		(end 23.1394 -256.159)
		(width 0.508)
		(layer "B.Cu")
		(net "P5VC_HDD12_LED")
	)
	(segment
		(start 25.1968 -254.1016)
		(end 25.1968 -252.5268)
		(width 0.508)
		(layer "B.Cu")
		(net "P5VC_HDD12_LED")
	)
	(segment
		(start 25.1968 -251.298456)
		(end 26.2128 -250.282456)
		(width 0.508)
		(layer "B.Cu")
		(net "P5VC_HDD12_LED")
	)
	(segment
		(start 28.997148 -250.282456)
		(end 36.963604 -242.316)
		(width 0.508)
		(layer "In5.Cu")
		(net "P5VC_HDD12_LED")
	)
	(segment
		(start 41.407334 -242.316)
		(end 42.804334 -240.919)
		(width 0.508)
		(layer "In5.Cu")
		(net "P5VC_HDD12_LED")
	)
	(segment
		(start 36.963604 -242.316)
		(end 41.407334 -242.316)
		(width 0.508)
		(layer "In5.Cu")
		(net "P5VC_HDD12_LED")
	)
	(segment
		(start 26.2128 -250.282456)
		(end 28.997148 -250.282456)
		(width 0.508)
		(layer "In5.Cu")
		(net "P5VC_HDD12_LED")
	)
	(segment
		(start 42.804334 -240.919)
		(end 43.2435 -240.919)
		(width 0.508)
		(layer "In5.Cu")
		(net "P5VC_HDD12_LED")
	)
	(segment
		(start 213.95055 -377.9774)
		(end 213.55685 -377.5837)
		(width 0.111252)
		(layer "F.Cu")
		(net "HDD1_LED_B")
	)
	(segment
		(start 214.8967 -377.9774)
		(end 213.95055 -377.9774)
		(width 0.111252)
		(layer "F.Cu")
		(net "HDD1_LED_B")
	)
	(segment
		(start 213.55685 -377.5837)
		(end 213.55685 -376.43435)
		(width 0.111252)
		(layer "F.Cu")
		(net "HDD1_LED_B")
	)
	(segment
		(start 213.55685 -376.43435)
		(end 214.8078 -375.1834)
		(width 0.111252)
		(layer "F.Cu")
		(net "HDD1_LED_B")
	)
	(via
		(at 214.8078 -375.1834)
		(size 0.7112)
		(drill 0.3556)
		(layers "F.Cu" "B.Cu")
		(net "HDD1_LED_B")
	)
	(segment
		(start 210.2358 -376.0851)
		(end 210.6422 -375.6787)
		(width 0.111252)
		(layer "F.Cu")
		(net "HDD1_LED_G")
	)
	(segment
		(start 212.5726 -373.7356)
		(end 212.4964 -373.6594)
		(width 0.111252)
		(layer "F.Cu")
		(net "HDD1_LED_G")
	)
	(segment
		(start 210.2231 -376.0724)
		(end 210.2358 -376.0851)
		(width 0.111252)
		(layer "F.Cu")
		(net "HDD1_LED_G")
	)
	(segment
		(start 210.6422 -375.6787)
		(end 212.5726 -375.6787)
		(width 0.111252)
		(layer "F.Cu")
		(net "HDD1_LED_G")
	)
	(segment
		(start 206.9338 -376.0724)
		(end 208.8134 -376.0724)
		(width 0.111252)
		(layer "F.Cu")
		(net "HDD1_LED_G")
	)
	(segment
		(start 208.8134 -376.0724)
		(end 210.2231 -376.0724)
		(width 0.111252)
		(layer "F.Cu")
		(net "HDD1_LED_G")
	)
	(segment
		(start 212.5726 -375.6787)
		(end 212.5726 -373.7356)
		(width 0.111252)
		(layer "F.Cu")
		(net "HDD1_LED_G")
	)
	(via
		(at 212.4964 -373.6594)
		(size 0.7112)
		(drill 0.3556)
		(layers "F.Cu" "B.Cu")
		(net "HDD1_LED_G")
	)
	(segment
		(start 229.616 -436.499)
		(end 228.981 -435.864)
		(width 0.508)
		(layer "F.Cu")
		(net "P3V3_LX_COOPER")
	)
	(segment
		(start 228.3968 -435.864)
		(end 228.981 -435.864)
		(width 0.508)
		(layer "F.Cu")
		(net "P3V3_LX_COOPER")
	)
	(segment
		(start 219.456 -441.452)
		(end 222.504 -444.5)
		(width 0.508)
		(layer "F.Cu")
		(net "P3V3_LX_COOPER")
	)
	(segment
		(start 222.504 -444.5)
		(end 226.949 -444.5)
		(width 0.508)
		(layer "F.Cu")
		(net "P3V3_LX_COOPER")
	)
	(segment
		(start 226.949 -444.5)
		(end 229.616 -441.833)
		(width 0.508)
		(layer "F.Cu")
		(net "P3V3_LX_COOPER")
	)
	(segment
		(start 219.456 -441.071)
		(end 219.456 -441.452)
		(width 0.508)
		(layer "F.Cu")
		(net "P3V3_LX_COOPER")
	)
	(segment
		(start 227.2792 -434.34)
		(end 227.5332 -434.594)
		(width 0.508)
		(layer "F.Cu")
		(net "P3V3_LX_COOPER")
	)
	(segment
		(start 228.346 -435.9148)
		(end 228.3968 -435.864)
		(width 0.508)
		(layer "F.Cu")
		(net "P3V3_LX_COOPER")
	)
	(segment
		(start 227.6856 -435.9148)
		(end 228.346 -435.9148)
		(width 0.508)
		(layer "F.Cu")
		(net "P3V3_LX_COOPER")
	)
	(segment
		(start 227.5332 -435.7624)
		(end 227.6856 -435.9148)
		(width 0.508)
		(layer "F.Cu")
		(net "P3V3_LX_COOPER")
	)
	(segment
		(start 229.616 -441.833)
		(end 229.616 -436.499)
		(width 0.508)
		(layer "F.Cu")
		(net "P3V3_LX_COOPER")
	)
	(segment
		(start 227.5332 -434.594)
		(end 227.5332 -435.7624)
		(width 0.508)
		(layer "F.Cu")
		(net "P3V3_LX_COOPER")
	)
	(via
		(at 228.981 -435.864)
		(size 0.7112)
		(drill 0.3556)
		(layers "F.Cu" "B.Cu")
		(net "P3V3_LX_COOPER")
	)
	(segment
		(start 212.712046 -478.7265)
		(end 210.312 -478.7265)
		(width 0.111252)
		(layer "F.Cu")
		(net "HDD0_LED_G")
	)
	(segment
		(start 212.724746 -478.7392)
		(end 212.712046 -478.7265)
		(width 0.111252)
		(layer "F.Cu")
		(net "HDD0_LED_G")
	)
	(segment
		(start 210.312 -478.7265)
		(end 210.2485 -478.79)
		(width 0.111252)
		(layer "F.Cu")
		(net "HDD0_LED_G")
	)
	(segment
		(start 207.0862 -478.79)
		(end 208.9658 -478.79)
		(width 0.111252)
		(layer "F.Cu")
		(net "HDD0_LED_G")
	)
	(segment
		(start 212.724746 -476.7326)
		(end 212.724746 -478.7392)
		(width 0.111252)
		(layer "F.Cu")
		(net "HDD0_LED_G")
	)
	(segment
		(start 210.2485 -478.79)
		(end 208.9658 -478.79)
		(width 0.111252)
		(layer "F.Cu")
		(net "HDD0_LED_G")
	)
	(via
		(at 212.724746 -476.7326)
		(size 0.7112)
		(drill 0.3556)
		(layers "F.Cu" "B.Cu")
		(net "HDD0_LED_G")
	)
	(segment
		(start 32.5247 -335.2546)
		(end 32.5374 -335.2419)
		(width 0.111252)
		(layer "F.Cu")
		(net "HDD11_LED_B")
	)
	(segment
		(start 32.5374 -335.2419)
		(end 32.5374 -334.478376)
		(width 0.111252)
		(layer "F.Cu")
		(net "HDD11_LED_B")
	)
	(segment
		(start 32.852106 -334.16367)
		(end 32.943546 -334.16367)
		(width 0.111252)
		(layer "F.Cu")
		(net "HDD11_LED_B")
	)
	(segment
		(start 32.5374 -334.478376)
		(end 32.852106 -334.16367)
		(width 0.111252)
		(layer "F.Cu")
		(net "HDD11_LED_B")
	)
	(segment
		(start 31.93415 -335.84515)
		(end 32.5247 -335.2546)
		(width 0.111252)
		(layer "F.Cu")
		(net "HDD11_LED_B")
	)
	(segment
		(start 31.93415 -336.9945)
		(end 31.93415 -335.84515)
		(width 0.111252)
		(layer "F.Cu")
		(net "HDD11_LED_B")
	)
	(via
		(at 32.943546 -334.16367)
		(size 0.7112)
		(drill 0.3556)
		(layers "F.Cu" "B.Cu")
		(net "HDD11_LED_B")
	)
	(segment
		(start 214.102696 -481.0379)
		(end 213.708996 -480.6442)
		(width 0.111252)
		(layer "F.Cu")
		(net "HDD0_LED_B")
	)
	(segment
		(start 213.708996 -480.6442)
		(end 213.708996 -480.371404)
		(width 0.111252)
		(layer "F.Cu")
		(net "HDD0_LED_B")
	)
	(segment
		(start 215.3158 -478.7646)
		(end 215.3158 -478.0026)
		(width 0.111252)
		(layer "F.Cu")
		(net "HDD0_LED_B")
	)
	(segment
		(start 213.708996 -480.371404)
		(end 215.3158 -478.7646)
		(width 0.111252)
		(layer "F.Cu")
		(net "HDD0_LED_B")
	)
	(segment
		(start 215.023446 -481.0379)
		(end 214.102696 -481.0379)
		(width 0.111252)
		(layer "F.Cu")
		(net "HDD0_LED_B")
	)
	(via
		(at 215.3158 -478.0026)
		(size 0.7112)
		(drill 0.3556)
		(layers "F.Cu" "B.Cu")
		(net "HDD0_LED_B")
	)
	(segment
		(start 35.2171 -338.9503)
		(end 34.7472 -338.4804)
		(width 0.111252)
		(layer "F.Cu")
		(net "HDD11_LED_G")
	)
	(segment
		(start 34.7472 -337.2612)
		(end 34.925 -337.0834)
		(width 0.111252)
		(layer "F.Cu")
		(net "HDD11_LED_G")
	)
	(segment
		(start 32.9184 -338.8995)
		(end 33.3121 -339.2932)
		(width 0.111252)
		(layer "F.Cu")
		(net "HDD11_LED_G")
	)
	(segment
		(start 34.7472 -338.4804)
		(end 34.7472 -337.2612)
		(width 0.111252)
		(layer "F.Cu")
		(net "HDD11_LED_G")
	)
	(segment
		(start 35.2171 -339.2932)
		(end 35.2171 -338.9503)
		(width 0.111252)
		(layer "F.Cu")
		(net "HDD11_LED_G")
	)
	(segment
		(start 38.8874 -337.0834)
		(end 37.4396 -337.0834)
		(width 0.111252)
		(layer "F.Cu")
		(net "HDD11_LED_G")
	)
	(segment
		(start 33.3121 -339.2932)
		(end 35.2171 -339.2932)
		(width 0.111252)
		(layer "F.Cu")
		(net "HDD11_LED_G")
	)
	(segment
		(start 34.925 -337.0834)
		(end 35.56 -337.0834)
		(width 0.111252)
		(layer "F.Cu")
		(net "HDD11_LED_G")
	)
	(segment
		(start 37.4396 -337.0834)
		(end 35.56 -337.0834)
		(width 0.111252)
		(layer "F.Cu")
		(net "HDD11_LED_G")
	)
	(segment
		(start 38.989 -336.9818)
		(end 38.8874 -337.0834)
		(width 0.111252)
		(layer "F.Cu")
		(net "HDD11_LED_G")
	)
	(via
		(at 38.989 -336.9818)
		(size 0.7112)
		(drill 0.3556)
		(layers "F.Cu" "B.Cu")
		(net "HDD11_LED_G")
	)
	(segment
		(start 33.4645 -345.694)
		(end 33.4645 -345.1225)
		(width 0.508)
		(layer "F.Cu")
		(net "P5VC_HDD11_LED")
	)
	(segment
		(start 35.56 -337.73364)
		(end 35.56 -338.4804)
		(width 0.4064)
		(layer "F.Cu")
		(net "P5VC_HDD11_LED")
	)
	(segment
		(start 32.893 -344.551)
		(end 32.766 -344.551)
		(width 0.508)
		(layer "F.Cu")
		(net "P5VC_HDD11_LED")
	)
	(segment
		(start 33.4645 -345.1225)
		(end 32.893 -344.551)
		(width 0.508)
		(layer "F.Cu")
		(net "P5VC_HDD11_LED")
	)
	(via
		(at 32.766 -344.551)
		(size 0.5588)
		(drill 0.3048)
		(layers "F.Cu" "B.Cu")
		(net "P5VC_HDD11_LED")
	)
	(via
		(at 34.742882 -339.221318)
		(size 0.7112)
		(drill 0.3556)
		(layers "F.Cu" "B.Cu")
		(net "P5VC_HDD11_LED")
	)
	(via
		(at 35.56 -338.4804)
		(size 0.5588)
		(drill 0.3048)
		(layers "F.Cu" "B.Cu")
		(net "P5VC_HDD11_LED")
	)
	(segment
		(start 35.4076 -338.5566)
		(end 34.742882 -339.221318)
		(width 0.508)
		(layer "B.Cu")
		(net "P5VC_HDD11_LED")
	)
	(segment
		(start 35.56 -338.4804)
		(end 35.4076 -338.5566)
		(width 0.508)
		(layer "B.Cu")
		(net "P5VC_HDD11_LED")
	)
	(segment
		(start 33.502346 -343.814654)
		(end 32.766 -344.551)
		(width 0.508)
		(layer "In2.Cu")
		(net "P5VC_HDD11_LED")
	)
	(segment
		(start 33.502346 -340.538054)
		(end 33.502346 -343.814654)
		(width 0.508)
		(layer "In2.Cu")
		(net "P5VC_HDD11_LED")
	)
	(segment
		(start 35.56 -338.4804)
		(end 33.502346 -340.538054)
		(width 0.508)
		(layer "In2.Cu")
		(net "P5VC_HDD11_LED")
	)
	(segment
		(start 208.9658 -475.2594)
		(end 208.9658 -476.2754)
		(width 0.4064)
		(layer "F.Cu")
		(net "P5VA_HDD0_LED")
	)
	(segment
		(start 223.4438 -453.7202)
		(end 224.2439 -453.7202)
		(width 0.508)
		(layer "F.Cu")
		(net "P5VA_HDD0_LED")
	)
	(segment
		(start 208.9658 -476.2754)
		(end 208.9658 -478.13976)
		(width 0.4064)
		(layer "F.Cu")
		(net "P5VA_HDD0_LED")
	)
	(via
		(at 208.9658 -475.2594)
		(size 0.5588)
		(drill 0.3048)
		(layers "F.Cu" "B.Cu")
		(net "P5VA_HDD0_LED")
	)
	(via
		(at 208.9658 -476.2754)
		(size 0.7112)
		(drill 0.3556)
		(layers "F.Cu" "B.Cu")
		(net "P5VA_HDD0_LED")
	)
	(via
		(at 223.4438 -453.7202)
		(size 0.5588)
		(drill 0.3048)
		(layers "F.Cu" "B.Cu")
		(net "P5VA_HDD0_LED")
	)
	(segment
		(start 208.9658 -468.1982)
		(end 208.9658 -475.2594)
		(width 0.508)
		(layer "In2.Cu")
		(net "P5VA_HDD0_LED")
	)
	(segment
		(start 223.4438 -453.7202)
		(end 208.9658 -468.1982)
		(width 0.508)
		(layer "In2.Cu")
		(net "P5VA_HDD0_LED")
	)
	(segment
		(start 22.678898 -464.467702)
		(end 22.86 -464.2866)
		(width 0.508)
		(layer "F.Cu")
		(net "P5VC_HDD10_LED")
	)
	(segment
		(start 45.1866 -429.3616)
		(end 45.04944 -429.22444)
		(width 0.4064)
		(layer "F.Cu")
		(net "P5VC_HDD10_LED")
	)
	(segment
		(start 45.04944 -429.22444)
		(end 45.04944 -428.1932)
		(width 0.4064)
		(layer "F.Cu")
		(net "P5VC_HDD10_LED")
	)
	(segment
		(start 21.843746 -464.467702)
		(end 22.678898 -464.467702)
		(width 0.508)
		(layer "F.Cu")
		(net "P5VC_HDD10_LED")
	)
	(via
		(at 22.86 -464.2866)
		(size 0.5588)
		(drill 0.3048)
		(layers "F.Cu" "B.Cu")
		(net "P5VC_HDD10_LED")
	)
	(via
		(at 45.1866 -429.3616)
		(size 0.5588)
		(drill 0.3048)
		(layers "F.Cu" "B.Cu")
		(net "P5VC_HDD10_LED")
	)
	(via
		(at 22.6568 -465.328)
		(size 0.7112)
		(drill 0.3556)
		(layers "F.Cu" "B.Cu")
		(net "P5VC_HDD10_LED")
	)
	(segment
		(start 22.6568 -464.4898)
		(end 22.86 -464.2866)
		(width 0.508)
		(layer "B.Cu")
		(net "P5VC_HDD10_LED")
	)
	(segment
		(start 22.6568 -465.328)
		(end 22.6568 -464.4898)
		(width 0.508)
		(layer "B.Cu")
		(net "P5VC_HDD10_LED")
	)
	(segment
		(start 40.3098 -450.114162)
		(end 40.3098 -433.418742)
		(width 0.508)
		(layer "In2.Cu")
		(net "P5VC_HDD10_LED")
	)
	(segment
		(start 22.86 -464.547204)
		(end 23.589996 -465.2772)
		(width 0.508)
		(layer "In2.Cu")
		(net "P5VC_HDD10_LED")
	)
	(segment
		(start 22.86 -464.2866)
		(end 22.86 -464.547204)
		(width 0.508)
		(layer "In2.Cu")
		(net "P5VC_HDD10_LED")
	)
	(segment
		(start 40.3098 -433.418742)
		(end 44.366942 -429.3616)
		(width 0.508)
		(layer "In2.Cu")
		(net "P5VC_HDD10_LED")
	)
	(segment
		(start 25.146762 -465.2772)
		(end 40.3098 -450.114162)
		(width 0.508)
		(layer "In2.Cu")
		(net "P5VC_HDD10_LED")
	)
	(segment
		(start 23.589996 -465.2772)
		(end 25.146762 -465.2772)
		(width 0.508)
		(layer "In2.Cu")
		(net "P5VC_HDD10_LED")
	)
	(segment
		(start 44.366942 -429.3616)
		(end 45.1866 -429.3616)
		(width 0.508)
		(layer "In2.Cu")
		(net "P5VC_HDD10_LED")
	)
	(segment
		(start 7.746746 -403.50694)
		(end 7.740142 -403.500336)
		(width 0.111252)
		(layer "F.Cu")
		(net "TEMP_SENSOR_A_ADDR0&ID")
	)
	(segment
		(start 10.782046 -403.5044)
		(end 8.788146 -403.5044)
		(width 0.111252)
		(layer "F.Cu")
		(net "TEMP_SENSOR_A_ADDR0&ID")
	)
	(segment
		(start 8.788146 -403.5044)
		(end 7.749286 -403.5044)
		(width 0.111252)
		(layer "F.Cu")
		(net "TEMP_SENSOR_A_ADDR0&ID")
	)
	(segment
		(start 7.749286 -403.5044)
		(end 7.746746 -403.50694)
		(width 0.111252)
		(layer "F.Cu")
		(net "TEMP_SENSOR_A_ADDR0&ID")
	)
	(segment
		(start 7.740142 -403.500336)
		(end 3.19405 -403.500336)
		(width 0.111252)
		(layer "F.Cu")
		(net "TEMP_SENSOR_A_ADDR0&ID")
	)
	(segment
		(start 3.19405 -403.500336)
		(end 3.192526 -403.498812)
		(width 0.111252)
		(layer "F.Cu")
		(net "TEMP_SENSOR_A_ADDR0&ID")
	)
	(via
		(at 10.782046 -403.5044)
		(size 0.7112)
		(drill 0.3556)
		(layers "F.Cu" "B.Cu")
		(net "TEMP_SENSOR_A_ADDR0&ID")
	)
	(segment
		(start 7.937246 -156.4767)
		(end 8.407146 -156.0068)
		(width 0.111252)
		(layer "F.Cu")
		(net "TEMP_SENSOR_B_ADDR0&ID")
	)
	(segment
		(start 7.937246 -155.3337)
		(end 7.937246 -155.181046)
		(width 0.111252)
		(layer "F.Cu")
		(net "TEMP_SENSOR_B_ADDR0&ID")
	)
	(segment
		(start 7.937246 -155.3337)
		(end 7.937246 -156.4767)
		(width 0.111252)
		(layer "F.Cu")
		(net "TEMP_SENSOR_B_ADDR0&ID")
	)
	(segment
		(start 7.937246 -155.181046)
		(end 6.256528 -153.500328)
		(width 0.111252)
		(layer "F.Cu")
		(net "TEMP_SENSOR_B_ADDR0&ID")
	)
	(segment
		(start 3.19405 -153.500328)
		(end 3.192526 -153.498804)
		(width 0.111252)
		(layer "F.Cu")
		(net "TEMP_SENSOR_B_ADDR0&ID")
	)
	(segment
		(start 8.407146 -156.0068)
		(end 9.689846 -156.0068)
		(width 0.111252)
		(layer "F.Cu")
		(net "TEMP_SENSOR_B_ADDR0&ID")
	)
	(segment
		(start 9.689846 -156.0068)
		(end 10.032746 -156.3497)
		(width 0.111252)
		(layer "F.Cu")
		(net "TEMP_SENSOR_B_ADDR0&ID")
	)
	(segment
		(start 6.256528 -153.500328)
		(end 3.19405 -153.500328)
		(width 0.111252)
		(layer "F.Cu")
		(net "TEMP_SENSOR_B_ADDR0&ID")
	)
	(via
		(at 10.032746 -156.3497)
		(size 0.7112)
		(drill 0.3556)
		(layers "F.Cu" "B.Cu")
		(net "TEMP_SENSOR_B_ADDR0&ID")
	)
	(segment
		(start 250.418092 -423.189908)
		(end 255.474978 -423.189908)
		(width 0.111252)
		(layer "F.Cu")
		(net "SELF_1B&2B_HB")
	)
	(segment
		(start 12.3063 -162.4584)
		(end 12.445746 -162.597846)
		(width 0.111252)
		(layer "F.Cu")
		(net "SELF_1B&2B_HB")
	)
	(segment
		(start 6.027928 -149.95906)
		(end 5.644896 -149.95906)
		(width 0.111252)
		(layer "F.Cu")
		(net "SELF_1B&2B_HB")
	)
	(segment
		(start 6.032754 -149.954234)
		(end 6.027928 -149.95906)
		(width 0.111252)
		(layer "F.Cu")
		(net "SELF_1B&2B_HB")
	)
	(segment
		(start 249.989594 -423.545)
		(end 250.063 -423.545)
		(width 0.111252)
		(layer "F.Cu")
		(net "SELF_1B&2B_HB")
	)
	(segment
		(start 5.1562 -149.954234)
		(end 4.702302 -149.500336)
		(width 0.111252)
		(layer "F.Cu")
		(net "SELF_1B&2B_HB")
	)
	(segment
		(start 7.070598 -149.5298)
		(end 6.646164 -149.954234)
		(width 0.111252)
		(layer "F.Cu")
		(net "SELF_1B&2B_HB")
	)
	(segment
		(start 3.19405 -149.500336)
		(end 3.192526 -149.498812)
		(width 0.111252)
		(layer "F.Cu")
		(net "SELF_1B&2B_HB")
	)
	(segment
		(start 250.063 -423.545)
		(end 250.418092 -423.189908)
		(width 0.111252)
		(layer "F.Cu")
		(net "SELF_1B&2B_HB")
	)
	(segment
		(start 14.097 -157.099)
		(end 14.101826 -157.103826)
		(width 0.111252)
		(layer "F.Cu")
		(net "SELF_1B&2B_HB")
	)
	(segment
		(start 12.445746 -162.597846)
		(end 12.445746 -163.2966)
		(width 0.111252)
		(layer "F.Cu")
		(net "SELF_1B&2B_HB")
	)
	(segment
		(start 5.644896 -149.95906)
		(end 5.64007 -149.954234)
		(width 0.111252)
		(layer "F.Cu")
		(net "SELF_1B&2B_HB")
	)
	(segment
		(start 14.097 -157.099)
		(end 13.97 -156.972)
		(width 0.111252)
		(layer "F.Cu")
		(net "SELF_1B&2B_HB")
	)
	(segment
		(start 6.646164 -149.954234)
		(end 6.032754 -149.954234)
		(width 0.111252)
		(layer "F.Cu")
		(net "SELF_1B&2B_HB")
	)
	(segment
		(start 4.702302 -149.500336)
		(end 3.19405 -149.500336)
		(width 0.111252)
		(layer "F.Cu")
		(net "SELF_1B&2B_HB")
	)
	(segment
		(start 14.101826 -157.103826)
		(end 14.101826 -160.523174)
		(width 0.111252)
		(layer "F.Cu")
		(net "SELF_1B&2B_HB")
	)
	(segment
		(start 14.101826 -160.523174)
		(end 13.335 -161.29)
		(width 0.111252)
		(layer "F.Cu")
		(net "SELF_1B&2B_HB")
	)
	(segment
		(start 13.97 -156.972)
		(end 13.97 -151.84501)
		(width 0.111252)
		(layer "F.Cu")
		(net "SELF_1B&2B_HB")
	)
	(segment
		(start 11.65479 -149.5298)
		(end 7.070598 -149.5298)
		(width 0.111252)
		(layer "F.Cu")
		(net "SELF_1B&2B_HB")
	)
	(segment
		(start 13.97 -151.84501)
		(end 11.65479 -149.5298)
		(width 0.111252)
		(layer "F.Cu")
		(net "SELF_1B&2B_HB")
	)
	(segment
		(start 5.64007 -149.954234)
		(end 5.1562 -149.954234)
		(width 0.111252)
		(layer "F.Cu")
		(net "SELF_1B&2B_HB")
	)
	(via
		(at 89.916 -402.5646)
		(size 0.5588)
		(drill 0.3048)
		(layers "F.Cu" "B.Cu")
		(net "SELF_1B&2B_HB")
	)
	(via
		(at 13.335 -161.29)
		(size 0.5588)
		(drill 0.3048)
		(layers "F.Cu" "B.Cu")
		(net "SELF_1B&2B_HB")
	)
	(via
		(at 12.445746 -163.2966)
		(size 0.5588)
		(drill 0.3048)
		(layers "F.Cu" "B.Cu")
		(net "SELF_1B&2B_HB")
	)
	(via
		(at 14.097 -157.099)
		(size 0.7112)
		(drill 0.3556)
		(layers "F.Cu" "B.Cu")
		(net "SELF_1B&2B_HB")
	)
	(via
		(at 249.989594 -423.545)
		(size 0.5588)
		(drill 0.3048)
		(layers "F.Cu" "B.Cu")
		(net "SELF_1B&2B_HB")
	)
	(segment
		(start 249.989594 -416.9029)
		(end 249.989594 -423.545)
		(width 0.14605)
		(layer "In2.Cu")
		(net "SELF_1B&2B_HB")
	)
	(segment
		(start 89.916 -402.5646)
		(end 236.923326 -402.5646)
		(width 0.14605)
		(layer "In2.Cu")
		(net "SELF_1B&2B_HB")
	)
	(segment
		(start 247.905016 -413.546544)
		(end 248.443242 -414.08477)
		(width 0.14605)
		(layer "In2.Cu")
		(net "SELF_1B&2B_HB")
	)
	(segment
		(start 248.443242 -414.08477)
		(end 248.689876 -414.331658)
		(width 0.14605)
		(layer "In2.Cu")
		(net "SELF_1B&2B_HB")
	)
	(segment
		(start 237.038134 -402.679408)
		(end 247.905016 -413.546544)
		(width 0.14605)
		(layer "In2.Cu")
		(net "SELF_1B&2B_HB")
	)
	(segment
		(start 248.97842 -414.620456)
		(end 248.97842 -415.891726)
		(width 0.14605)
		(layer "In2.Cu")
		(net "SELF_1B&2B_HB")
	)
	(segment
		(start 248.97842 -415.891726)
		(end 249.989594 -416.9029)
		(width 0.14605)
		(layer "In2.Cu")
		(net "SELF_1B&2B_HB")
	)
	(segment
		(start 236.923326 -402.5646)
		(end 237.038134 -402.679408)
		(width 0.14605)
		(layer "In2.Cu")
		(net "SELF_1B&2B_HB")
	)
	(segment
		(start 248.689876 -414.331658)
		(end 248.97842 -414.620456)
		(width 0.14605)
		(layer "In2.Cu")
		(net "SELF_1B&2B_HB")
	)
	(segment
		(start 20.412456 -166.902384)
		(end 51.953668 -198.443596)
		(width 0.14605)
		(layer "In5.Cu")
		(net "SELF_1B&2B_HB")
	)
	(segment
		(start 51.953668 -198.443596)
		(end 82.933032 -198.443596)
		(width 0.14605)
		(layer "In5.Cu")
		(net "SELF_1B&2B_HB")
	)
	(segment
		(start 20.006056 -166.902384)
		(end 20.412456 -166.902384)
		(width 0.14605)
		(layer "In5.Cu")
		(net "SELF_1B&2B_HB")
	)
	(segment
		(start 89.563448 -388.982204)
		(end 89.563448 -396.311628)
		(width 0.14605)
		(layer "In5.Cu")
		(net "SELF_1B&2B_HB")
	)
	(segment
		(start 12.445746 -162.179254)
		(end 13.335 -161.29)
		(width 0.14605)
		(layer "In5.Cu")
		(net "SELF_1B&2B_HB")
	)
	(segment
		(start 89.601548 -388.944104)
		(end 89.563448 -388.982204)
		(width 0.14605)
		(layer "In5.Cu")
		(net "SELF_1B&2B_HB")
	)
	(segment
		(start 89.938098 -396.686278)
		(end 89.938098 -402.542502)
		(width 0.14605)
		(layer "In5.Cu")
		(net "SELF_1B&2B_HB")
	)
	(segment
		(start 89.601548 -205.112112)
		(end 89.601548 -388.944104)
		(width 0.14605)
		(layer "In5.Cu")
		(net "SELF_1B&2B_HB")
	)
	(segment
		(start 12.788646 -163.6395)
		(end 16.743172 -163.6395)
		(width 0.14605)
		(layer "In5.Cu")
		(net "SELF_1B&2B_HB")
	)
	(segment
		(start 89.938098 -402.542502)
		(end 89.916 -402.5646)
		(width 0.14605)
		(layer "In5.Cu")
		(net "SELF_1B&2B_HB")
	)
	(segment
		(start 12.445746 -163.2966)
		(end 12.788646 -163.6395)
		(width 0.14605)
		(layer "In5.Cu")
		(net "SELF_1B&2B_HB")
	)
	(segment
		(start 12.445746 -163.2966)
		(end 12.445746 -162.179254)
		(width 0.14605)
		(layer "In5.Cu")
		(net "SELF_1B&2B_HB")
	)
	(segment
		(start 89.563448 -396.311628)
		(end 89.938098 -396.686278)
		(width 0.14605)
		(layer "In5.Cu")
		(net "SELF_1B&2B_HB")
	)
	(segment
		(start 82.933032 -198.443596)
		(end 89.601548 -205.112112)
		(width 0.14605)
		(layer "In5.Cu")
		(net "SELF_1B&2B_HB")
	)
	(segment
		(start 16.743172 -163.6395)
		(end 20.006056 -166.902384)
		(width 0.14605)
		(layer "In5.Cu")
		(net "SELF_1B&2B_HB")
	)
	(segment
		(start 8.96239 -400.61134)
		(end 9.90473 -399.669)
		(width 0.111252)
		(layer "F.Cu")
		(net "SELF_1A&2A_HB")
	)
	(segment
		(start 11.4173 -160.7693)
		(end 11.049 -160.401)
		(width 0.111252)
		(layer "F.Cu")
		(net "SELF_1A&2A_HB")
	)
	(segment
		(start 11.4173 -161.417)
		(end 11.4173 -160.7693)
		(width 0.111252)
		(layer "F.Cu")
		(net "SELF_1A&2A_HB")
	)
	(segment
		(start 247.396 -424.3578)
		(end 247.498108 -424.459908)
		(width 0.111252)
		(layer "F.Cu")
		(net "SELF_1A&2A_HB")
	)
	(segment
		(start 5.93217 -400.61134)
		(end 8.96239 -400.61134)
		(width 0.111252)
		(layer "F.Cu")
		(net "SELF_1A&2A_HB")
	)
	(segment
		(start 5.809488 -400.601688)
		(end 5.922518 -400.601688)
		(width 0.111252)
		(layer "F.Cu")
		(net "SELF_1A&2A_HB")
	)
	(segment
		(start 4.70662 -399.49882)
		(end 5.809488 -400.601688)
		(width 0.111252)
		(layer "F.Cu")
		(net "SELF_1A&2A_HB")
	)
	(segment
		(start 5.922518 -400.601688)
		(end 5.93217 -400.61134)
		(width 0.111252)
		(layer "F.Cu")
		(net "SELF_1A&2A_HB")
	)
	(segment
		(start 9.90473 -399.669)
		(end 9.906 -399.669)
		(width 0.111252)
		(layer "F.Cu")
		(net "SELF_1A&2A_HB")
	)
	(segment
		(start 10.668 -161.417)
		(end 11.4173 -161.417)
		(width 0.111252)
		(layer "F.Cu")
		(net "SELF_1A&2A_HB")
	)
	(segment
		(start 247.498108 -424.459908)
		(end 255.474978 -424.459908)
		(width 0.111252)
		(layer "F.Cu")
		(net "SELF_1A&2A_HB")
	)
	(segment
		(start 10.541 -161.29)
		(end 10.668 -161.417)
		(width 0.111252)
		(layer "F.Cu")
		(net "SELF_1A&2A_HB")
	)
	(segment
		(start 3.192526 -399.49882)
		(end 4.70662 -399.49882)
		(width 0.111252)
		(layer "F.Cu")
		(net "SELF_1A&2A_HB")
	)
	(via
		(at 18.9738 -399.9484)
		(size 0.5588)
		(drill 0.3048)
		(layers "F.Cu" "B.Cu")
		(net "SELF_1A&2A_HB")
	)
	(via
		(at 11.049 -160.401)
		(size 0.7112)
		(drill 0.3556)
		(layers "F.Cu" "B.Cu")
		(net "SELF_1A&2A_HB")
	)
	(via
		(at 10.541 -161.29)
		(size 0.5588)
		(drill 0.3048)
		(layers "F.Cu" "B.Cu")
		(net "SELF_1A&2A_HB")
	)
	(via
		(at 247.396 -424.3578)
		(size 0.5588)
		(drill 0.3048)
		(layers "F.Cu" "B.Cu")
		(net "SELF_1A&2A_HB")
	)
	(via
		(at 9.906 -399.669)
		(size 0.5588)
		(drill 0.3048)
		(layers "F.Cu" "B.Cu")
		(net "SELF_1A&2A_HB")
	)
	(segment
		(start 10.2362 -399.9992)
		(end 9.906 -399.669)
		(width 0.111252)
		(layer "B.Cu")
		(net "SELF_1A&2A_HB")
	)
	(segment
		(start 18.923 -399.9992)
		(end 10.2362 -399.9992)
		(width 0.111252)
		(layer "B.Cu")
		(net "SELF_1A&2A_HB")
	)
	(segment
		(start 18.9738 -399.9484)
		(end 18.923 -399.9992)
		(width 0.111252)
		(layer "B.Cu")
		(net "SELF_1A&2A_HB")
	)
	(segment
		(start 84.388452 -404.1267)
		(end 85.645752 -405.384)
		(width 0.14605)
		(layer "In2.Cu")
		(net "SELF_1A&2A_HB")
	)
	(segment
		(start 8.550148 -175.891952)
		(end 6.556248 -173.898052)
		(width 0.14605)
		(layer "In2.Cu")
		(net "SELF_1A&2A_HB")
	)
	(segment
		(start 9.906 -399.669)
		(end 10.184384 -399.390616)
		(width 0.14605)
		(layer "In2.Cu")
		(net "SELF_1A&2A_HB")
	)
	(segment
		(start 11.804396 -260.266942)
		(end 11.804396 -259.719064)
		(width 0.14605)
		(layer "In2.Cu")
		(net "SELF_1A&2A_HB")
	)
	(segment
		(start 9.174988 -212.143594)
		(end 8.689594 -211.6582)
		(width 0.14605)
		(layer "In2.Cu")
		(net "SELF_1A&2A_HB")
	)
	(segment
		(start 8.270748 -189.365382)
		(end 7.937246 -189.03188)
		(width 0.14605)
		(layer "In2.Cu")
		(net "SELF_1A&2A_HB")
	)
	(segment
		(start 6.556248 -173.898052)
		(end 6.556248 -172.316648)
		(width 0.14605)
		(layer "In2.Cu")
		(net "SELF_1A&2A_HB")
	)
	(segment
		(start 22.4409 -400.9009)
		(end 25.6667 -404.1267)
		(width 0.14605)
		(layer "In2.Cu")
		(net "SELF_1A&2A_HB")
	)
	(segment
		(start 11.032236 -264.910824)
		(end 11.80465 -264.13841)
		(width 0.14605)
		(layer "In2.Cu")
		(net "SELF_1A&2A_HB")
	)
	(segment
		(start 10.975848 -390.802368)
		(end 10.975848 -374.750584)
		(width 0.14605)
		(layer "In2.Cu")
		(net "SELF_1A&2A_HB")
	)
	(segment
		(start 10.975848 -374.750584)
		(end 11.4935 -374.232932)
		(width 0.14605)
		(layer "In2.Cu")
		(net "SELF_1A&2A_HB")
	)
	(segment
		(start 11.032236 -268.649196)
		(end 11.032236 -264.910824)
		(width 0.14605)
		(layer "In2.Cu")
		(net "SELF_1A&2A_HB")
	)
	(segment
		(start 10.184384 -395.575536)
		(end 9.870694 -395.261846)
		(width 0.14605)
		(layer "In2.Cu")
		(net "SELF_1A&2A_HB")
	)
	(segment
		(start 8.550148 -178.484784)
		(end 8.550148 -175.891952)
		(width 0.14605)
		(layer "In2.Cu")
		(net "SELF_1A&2A_HB")
	)
	(segment
		(start 11.884152 -166.988744)
		(end 11.884152 -162.633152)
		(width 0.14605)
		(layer "In2.Cu")
		(net "SELF_1A&2A_HB")
	)
	(segment
		(start 11.03249 -366.720882)
		(end 11.03249 -268.64945)
		(width 0.14605)
		(layer "In2.Cu")
		(net "SELF_1A&2A_HB")
	)
	(segment
		(start 18.9738 -400.0754)
		(end 19.7993 -400.9009)
		(width 0.14605)
		(layer "In2.Cu")
		(net "SELF_1A&2A_HB")
	)
	(segment
		(start 11.287252 -257.981704)
		(end 10.724388 -257.41884)
		(width 0.14605)
		(layer "In2.Cu")
		(net "SELF_1A&2A_HB")
	)
	(segment
		(start 11.884152 -162.633152)
		(end 10.541 -161.29)
		(width 0.14605)
		(layer "In2.Cu")
		(net "SELF_1A&2A_HB")
	)
	(segment
		(start 11.4935 -367.181892)
		(end 11.03249 -366.720882)
		(width 0.14605)
		(layer "In2.Cu")
		(net "SELF_1A&2A_HB")
	)
	(segment
		(start 18.9738 -399.9484)
		(end 18.9738 -400.0754)
		(width 0.14605)
		(layer "In2.Cu")
		(net "SELF_1A&2A_HB")
	)
	(segment
		(start 7.75335 -199.79005)
		(end 8.270748 -199.272652)
		(width 0.14605)
		(layer "In2.Cu")
		(net "SELF_1A&2A_HB")
	)
	(segment
		(start 19.7993 -400.9009)
		(end 22.4409 -400.9009)
		(width 0.14605)
		(layer "In2.Cu")
		(net "SELF_1A&2A_HB")
	)
	(segment
		(start 10.724388 -218.981782)
		(end 9.174988 -217.432382)
		(width 0.14605)
		(layer "In2.Cu")
		(net "SELF_1A&2A_HB")
	)
	(segment
		(start 8.981948 -207.92313)
		(end 8.981948 -206.324708)
		(width 0.14605)
		(layer "In2.Cu")
		(net "SELF_1A&2A_HB")
	)
	(segment
		(start 246.29618 -418.254434)
		(end 246.29618 -418.409628)
		(width 0.14605)
		(layer "In2.Cu")
		(net "SELF_1A&2A_HB")
	)
	(segment
		(start 246.3546 -418.468048)
		(end 246.3546 -423.3164)
		(width 0.14605)
		(layer "In2.Cu")
		(net "SELF_1A&2A_HB")
	)
	(segment
		(start 10.184384 -399.390616)
		(end 10.184384 -395.575536)
		(width 0.14605)
		(layer "In2.Cu")
		(net "SELF_1A&2A_HB")
	)
	(segment
		(start 8.270748 -199.272652)
		(end 8.270748 -189.365382)
		(width 0.14605)
		(layer "In2.Cu")
		(net "SELF_1A&2A_HB")
	)
	(segment
		(start 7.937246 -189.03188)
		(end 7.937246 -179.097686)
		(width 0.14605)
		(layer "In2.Cu")
		(net "SELF_1A&2A_HB")
	)
	(segment
		(start 245.347998 -417.306252)
		(end 246.29618 -418.254434)
		(width 0.14605)
		(layer "In2.Cu")
		(net "SELF_1A&2A_HB")
	)
	(segment
		(start 10.724388 -257.41884)
		(end 10.724388 -218.981782)
		(width 0.14605)
		(layer "In2.Cu")
		(net "SELF_1A&2A_HB")
	)
	(segment
		(start 235.915962 -405.384508)
		(end 235.91647 -405.384508)
		(width 0.14605)
		(layer "In2.Cu")
		(net "SELF_1A&2A_HB")
	)
	(segment
		(start 11.287252 -259.164328)
		(end 11.287252 -257.981704)
		(width 0.14605)
		(layer "In2.Cu")
		(net "SELF_1A&2A_HB")
	)
	(segment
		(start 9.174988 -217.432382)
		(end 9.174988 -212.143594)
		(width 0.14605)
		(layer "In2.Cu")
		(net "SELF_1A&2A_HB")
	)
	(segment
		(start 6.556248 -172.316648)
		(end 11.884152 -166.988744)
		(width 0.14605)
		(layer "In2.Cu")
		(net "SELF_1A&2A_HB")
	)
	(segment
		(start 11.804396 -259.719064)
		(end 11.287252 -259.164328)
		(width 0.14605)
		(layer "In2.Cu")
		(net "SELF_1A&2A_HB")
	)
	(segment
		(start 7.75335 -205.09611)
		(end 7.75335 -199.79005)
		(width 0.14605)
		(layer "In2.Cu")
		(net "SELF_1A&2A_HB")
	)
	(segment
		(start 235.91647 -405.384508)
		(end 245.347998 -414.81756)
		(width 0.14605)
		(layer "In2.Cu")
		(net "SELF_1A&2A_HB")
	)
	(segment
		(start 11.4935 -374.232932)
		(end 11.4935 -367.181892)
		(width 0.14605)
		(layer "In2.Cu")
		(net "SELF_1A&2A_HB")
	)
	(segment
		(start 246.29618 -418.409628)
		(end 246.3546 -418.468048)
		(width 0.14605)
		(layer "In2.Cu")
		(net "SELF_1A&2A_HB")
	)
	(segment
		(start 25.6667 -404.1267)
		(end 84.388452 -404.1267)
		(width 0.14605)
		(layer "In2.Cu")
		(net "SELF_1A&2A_HB")
	)
	(segment
		(start 8.689594 -208.215484)
		(end 8.981948 -207.92313)
		(width 0.14605)
		(layer "In2.Cu")
		(net "SELF_1A&2A_HB")
	)
	(segment
		(start 8.689594 -211.6582)
		(end 8.689594 -208.215484)
		(width 0.14605)
		(layer "In2.Cu")
		(net "SELF_1A&2A_HB")
	)
	(segment
		(start 85.645752 -405.384)
		(end 235.915454 -405.384)
		(width 0.14605)
		(layer "In2.Cu")
		(net "SELF_1A&2A_HB")
	)
	(segment
		(start 9.870694 -391.907522)
		(end 10.975848 -390.802368)
		(width 0.14605)
		(layer "In2.Cu")
		(net "SELF_1A&2A_HB")
	)
	(segment
		(start 7.937246 -179.097686)
		(end 8.550148 -178.484784)
		(width 0.14605)
		(layer "In2.Cu")
		(net "SELF_1A&2A_HB")
	)
	(segment
		(start 11.80465 -260.267196)
		(end 11.804396 -260.266942)
		(width 0.14605)
		(layer "In2.Cu")
		(net "SELF_1A&2A_HB")
	)
	(segment
		(start 246.3546 -423.3164)
		(end 247.396 -424.3578)
		(width 0.14605)
		(layer "In2.Cu")
		(net "SELF_1A&2A_HB")
	)
	(segment
		(start 11.80465 -264.13841)
		(end 11.80465 -260.267196)
		(width 0.14605)
		(layer "In2.Cu")
		(net "SELF_1A&2A_HB")
	)
	(segment
		(start 235.915454 -405.384)
		(end 235.915962 -405.384508)
		(width 0.14605)
		(layer "In2.Cu")
		(net "SELF_1A&2A_HB")
	)
	(segment
		(start 8.981948 -206.324708)
		(end 7.75335 -205.09611)
		(width 0.14605)
		(layer "In2.Cu")
		(net "SELF_1A&2A_HB")
	)
	(segment
		(start 245.347998 -414.81756)
		(end 245.347998 -417.306252)
		(width 0.14605)
		(layer "In2.Cu")
		(net "SELF_1A&2A_HB")
	)
	(segment
		(start 11.03249 -268.64945)
		(end 11.032236 -268.649196)
		(width 0.14605)
		(layer "In2.Cu")
		(net "SELF_1A&2A_HB")
	)
	(segment
		(start 9.870694 -395.261846)
		(end 9.870694 -391.907522)
		(width 0.14605)
		(layer "In2.Cu")
		(net "SELF_1A&2A_HB")
	)
	(segment
		(start 59.0931 -72.009)
		(end 60.1472 -72.009)
		(width 0.111252)
		(layer "F.Cu")
		(net "HDD9_LED_B")
	)
	(segment
		(start 59.78525 -71.06285)
		(end 58.9661 -71.882)
		(width 0.111252)
		(layer "F.Cu")
		(net "HDD9_LED_B")
	)
	(segment
		(start 58.9661 -71.882)
		(end 59.0931 -72.009)
		(width 0.111252)
		(layer "F.Cu")
		(net "HDD9_LED_B")
	)
	(segment
		(start 59.78525 -70.3199)
		(end 59.78525 -71.06285)
		(width 0.111252)
		(layer "F.Cu")
		(net "HDD9_LED_B")
	)
	(via
		(at 60.1472 -72.009)
		(size 0.7112)
		(drill 0.3556)
		(layers "F.Cu" "B.Cu")
		(net "HDD9_LED_B")
	)
	(segment
		(start 251.993908 -415.798)
		(end 252.222 -415.569908)
		(width 0.111252)
		(layer "F.Cu")
		(net "PEER_1B&2B_HB")
	)
	(segment
		(start 250.0884 -415.569908)
		(end 250.316492 -415.798)
		(width 0.111252)
		(layer "F.Cu")
		(net "PEER_1B&2B_HB")
	)
	(segment
		(start 244.144292 -415.569908)
		(end 250.0884 -415.569908)
		(width 0.111252)
		(layer "F.Cu")
		(net "PEER_1B&2B_HB")
	)
	(segment
		(start 252.222 -415.569908)
		(end 255.474978 -415.569908)
		(width 0.111252)
		(layer "F.Cu")
		(net "PEER_1B&2B_HB")
	)
	(segment
		(start 244.0686 -415.6456)
		(end 244.144292 -415.569908)
		(width 0.111252)
		(layer "F.Cu")
		(net "PEER_1B&2B_HB")
	)
	(segment
		(start 250.316492 -415.798)
		(end 251.993908 -415.798)
		(width 0.111252)
		(layer "F.Cu")
		(net "PEER_1B&2B_HB")
	)
	(via
		(at 8.3058 -425.0182)
		(size 0.5588)
		(drill 0.3048)
		(layers "F.Cu" "B.Cu")
		(net "PEER_1B&2B_HB")
	)
	(via
		(at 5.4864 -432.5366)
		(size 0.5588)
		(drill 0.3048)
		(layers "F.Cu" "B.Cu")
		(net "PEER_1B&2B_HB")
	)
	(via
		(at 18.923 -429.768)
		(size 0.5588)
		(drill 0.3048)
		(layers "F.Cu" "B.Cu")
		(net "PEER_1B&2B_HB")
	)
	(via
		(at 17.272 -432.054)
		(size 0.7112)
		(drill 0.3556)
		(layers "F.Cu" "B.Cu")
		(net "PEER_1B&2B_HB")
	)
	(via
		(at 244.0686 -415.6456)
		(size 0.5588)
		(drill 0.3048)
		(layers "F.Cu" "B.Cu")
		(net "PEER_1B&2B_HB")
	)
	(via
		(at 9.452864 -205.219554)
		(size 0.5588)
		(drill 0.3048)
		(layers "F.Cu" "B.Cu")
		(net "PEER_1B&2B_HB")
	)
	(via
		(at 7.0358 -173.4058)
		(size 0.5588)
		(drill 0.3048)
		(layers "F.Cu" "B.Cu")
		(net "PEER_1B&2B_HB")
	)
	(segment
		(start 5.4864 -432.5366)
		(end 5.8928 -432.943)
		(width 0.111252)
		(layer "B.Cu")
		(net "PEER_1B&2B_HB")
	)
	(segment
		(start 16.383 -432.943)
		(end 17.272 -432.054)
		(width 0.111252)
		(layer "B.Cu")
		(net "PEER_1B&2B_HB")
	)
	(segment
		(start 7.0358 -173.4058)
		(end 5.941314 -174.500286)
		(width 0.111252)
		(layer "B.Cu")
		(net "PEER_1B&2B_HB")
	)
	(segment
		(start 2.81305 -174.500286)
		(end 2.811526 -174.498762)
		(width 0.111252)
		(layer "B.Cu")
		(net "PEER_1B&2B_HB")
	)
	(segment
		(start 5.8928 -432.943)
		(end 16.383 -432.943)
		(width 0.111252)
		(layer "B.Cu")
		(net "PEER_1B&2B_HB")
	)
	(segment
		(start 5.941314 -174.500286)
		(end 2.81305 -174.500286)
		(width 0.111252)
		(layer "B.Cu")
		(net "PEER_1B&2B_HB")
	)
	(segment
		(start 18.923 -429.768)
		(end 18.923 -430.403)
		(width 0.111252)
		(layer "B.Cu")
		(net "PEER_1B&2B_HB")
	)
	(segment
		(start 6.086094 -424.500294)
		(end 2.81305 -424.500294)
		(width 0.111252)
		(layer "B.Cu")
		(net "PEER_1B&2B_HB")
	)
	(segment
		(start 6.604 -425.0182)
		(end 6.086094 -424.500294)
		(width 0.111252)
		(layer "B.Cu")
		(net "PEER_1B&2B_HB")
	)
	(segment
		(start 8.3058 -425.0182)
		(end 6.604 -425.0182)
		(width 0.111252)
		(layer "B.Cu")
		(net "PEER_1B&2B_HB")
	)
	(segment
		(start 2.81305 -424.500294)
		(end 2.811526 -424.49877)
		(width 0.111252)
		(layer "B.Cu")
		(net "PEER_1B&2B_HB")
	)
	(segment
		(start 18.923 -430.403)
		(end 17.272 -432.054)
		(width 0.111252)
		(layer "B.Cu")
		(net "PEER_1B&2B_HB")
	)
	(segment
		(start 8.388096 -188.844936)
		(end 8.388096 -179.419504)
		(width 0.14605)
		(layer "In2.Cu")
		(net "PEER_1B&2B_HB")
	)
	(segment
		(start 23.409402 -418.978334)
		(end 23.409402 -419.681914)
		(width 0.14605)
		(layer "In2.Cu")
		(net "PEER_1B&2B_HB")
	)
	(segment
		(start 8.2042 -203.191872)
		(end 8.2042 -200.334118)
		(width 0.14605)
		(layer "In2.Cu")
		(net "PEER_1B&2B_HB")
	)
	(segment
		(start 8.810752 -203.798424)
		(end 8.810752 -203.776072)
		(width 0.14605)
		(layer "In2.Cu")
		(net "PEER_1B&2B_HB")
	)
	(segment
		(start 26.549604 -405.028654)
		(end 25.44445 -405.028654)
		(width 0.14605)
		(layer "In2.Cu")
		(net "PEER_1B&2B_HB")
	)
	(segment
		(start 85.271864 -406.2857)
		(end 84.014564 -405.0284)
		(width 0.14605)
		(layer "In2.Cu")
		(net "PEER_1B&2B_HB")
	)
	(segment
		(start 235.542582 -406.286208)
		(end 235.542074 -406.286208)
		(width 0.14605)
		(layer "In2.Cu")
		(net "PEER_1B&2B_HB")
	)
	(segment
		(start 26.549858 -405.0284)
		(end 26.549604 -405.028654)
		(width 0.14605)
		(layer "In2.Cu")
		(net "PEER_1B&2B_HB")
	)
	(segment
		(start 244.0686 -415.6456)
		(end 244.272308 -415.441892)
		(width 0.14605)
		(layer "In2.Cu")
		(net "PEER_1B&2B_HB")
	)
	(segment
		(start 8.388096 -179.419504)
		(end 9.353296 -178.454304)
		(width 0.14605)
		(layer "In2.Cu")
		(net "PEER_1B&2B_HB")
	)
	(segment
		(start 244.272308 -415.441892)
		(end 244.272308 -415.017458)
		(width 0.14605)
		(layer "In2.Cu")
		(net "PEER_1B&2B_HB")
	)
	(segment
		(start 23.36165 -417.010342)
		(end 23.36165 -418.738558)
		(width 0.14605)
		(layer "In2.Cu")
		(net "PEER_1B&2B_HB")
	)
	(segment
		(start 9.353296 -178.454304)
		(end 9.353296 -175.259238)
		(width 0.14605)
		(layer "In2.Cu")
		(net "PEER_1B&2B_HB")
	)
	(segment
		(start 8.529828 -203.495148)
		(end 8.507476 -203.495148)
		(width 0.14605)
		(layer "In2.Cu")
		(net "PEER_1B&2B_HB")
	)
	(segment
		(start 21.713444 -415.361882)
		(end 21.713444 -415.362136)
		(width 0.14605)
		(layer "In2.Cu")
		(net "PEER_1B&2B_HB")
	)
	(segment
		(start 8.810752 -203.776072)
		(end 8.529828 -203.495148)
		(width 0.14605)
		(layer "In2.Cu")
		(net "PEER_1B&2B_HB")
	)
	(segment
		(start 25.444196 -405.0284)
		(end 24.5364 -405.0284)
		(width 0.14605)
		(layer "In2.Cu")
		(net "PEER_1B&2B_HB")
	)
	(segment
		(start 7.499858 -173.4058)
		(end 7.0358 -173.4058)
		(width 0.14605)
		(layer "In2.Cu")
		(net "PEER_1B&2B_HB")
	)
	(segment
		(start 84.014564 -405.0284)
		(end 26.549858 -405.0284)
		(width 0.14605)
		(layer "In2.Cu")
		(net "PEER_1B&2B_HB")
	)
	(segment
		(start 8.731504 -189.188344)
		(end 8.388096 -188.844936)
		(width 0.14605)
		(layer "In2.Cu")
		(net "PEER_1B&2B_HB")
	)
	(segment
		(start 23.36165 -421.661844)
		(end 18.923 -426.100494)
		(width 0.14605)
		(layer "In2.Cu")
		(net "PEER_1B&2B_HB")
	)
	(segment
		(start 23.409402 -419.681914)
		(end 23.36165 -419.92169)
		(width 0.14605)
		(layer "In2.Cu")
		(net "PEER_1B&2B_HB")
	)
	(segment
		(start 9.452864 -204.440536)
		(end 8.810752 -203.798424)
		(width 0.14605)
		(layer "In2.Cu")
		(net "PEER_1B&2B_HB")
	)
	(segment
		(start 24.5364 -405.0284)
		(end 18.929096 -410.635704)
		(width 0.14605)
		(layer "In2.Cu")
		(net "PEER_1B&2B_HB")
	)
	(segment
		(start 23.36165 -419.92169)
		(end 23.36165 -421.661844)
		(width 0.14605)
		(layer "In2.Cu")
		(net "PEER_1B&2B_HB")
	)
	(segment
		(start 18.929096 -412.577534)
		(end 21.713444 -415.361882)
		(width 0.14605)
		(layer "In2.Cu")
		(net "PEER_1B&2B_HB")
	)
	(segment
		(start 8.731504 -199.806814)
		(end 8.731504 -189.188344)
		(width 0.14605)
		(layer "In2.Cu")
		(net "PEER_1B&2B_HB")
	)
	(segment
		(start 18.923 -426.100494)
		(end 18.923 -429.768)
		(width 0.14605)
		(layer "In2.Cu")
		(net "PEER_1B&2B_HB")
	)
	(segment
		(start 9.353296 -175.259238)
		(end 7.499858 -173.4058)
		(width 0.14605)
		(layer "In2.Cu")
		(net "PEER_1B&2B_HB")
	)
	(segment
		(start 8.2042 -200.334118)
		(end 8.731504 -199.806814)
		(width 0.14605)
		(layer "In2.Cu")
		(net "PEER_1B&2B_HB")
	)
	(segment
		(start 235.542074 -406.286208)
		(end 235.541566 -406.2857)
		(width 0.14605)
		(layer "In2.Cu")
		(net "PEER_1B&2B_HB")
	)
	(segment
		(start 8.507476 -203.495148)
		(end 8.2042 -203.191872)
		(width 0.14605)
		(layer "In2.Cu")
		(net "PEER_1B&2B_HB")
	)
	(segment
		(start 9.452864 -205.219554)
		(end 9.452864 -204.440536)
		(width 0.14605)
		(layer "In2.Cu")
		(net "PEER_1B&2B_HB")
	)
	(segment
		(start 244.272308 -415.017458)
		(end 235.542582 -406.286208)
		(width 0.14605)
		(layer "In2.Cu")
		(net "PEER_1B&2B_HB")
	)
	(segment
		(start 25.44445 -405.028654)
		(end 25.444196 -405.0284)
		(width 0.14605)
		(layer "In2.Cu")
		(net "PEER_1B&2B_HB")
	)
	(segment
		(start 235.541566 -406.2857)
		(end 85.271864 -406.2857)
		(width 0.14605)
		(layer "In2.Cu")
		(net "PEER_1B&2B_HB")
	)
	(segment
		(start 18.929096 -410.635704)
		(end 18.929096 -412.577534)
		(width 0.14605)
		(layer "In2.Cu")
		(net "PEER_1B&2B_HB")
	)
	(segment
		(start 23.36165 -418.738558)
		(end 23.409402 -418.978334)
		(width 0.14605)
		(layer "In2.Cu")
		(net "PEER_1B&2B_HB")
	)
	(segment
		(start 21.713444 -415.362136)
		(end 23.36165 -417.010342)
		(width 0.14605)
		(layer "In2.Cu")
		(net "PEER_1B&2B_HB")
	)
	(segment
		(start 16.246602 -415.676842)
		(end 15.99184 -415.931604)
		(width 0.14605)
		(layer "In5.Cu")
		(net "PEER_1B&2B_HB")
	)
	(segment
		(start 9.331198 -206.853028)
		(end 9.331198 -215.504776)
		(width 0.14605)
		(layer "In5.Cu")
		(net "PEER_1B&2B_HB")
	)
	(segment
		(start 7.874 -425.45)
		(end 8.3058 -425.0182)
		(width 0.14605)
		(layer "In5.Cu")
		(net "PEER_1B&2B_HB")
	)
	(segment
		(start 16.134842 -416.871658)
		(end 16.134842 -426.979842)
		(width 0.14605)
		(layer "In5.Cu")
		(net "PEER_1B&2B_HB")
	)
	(segment
		(start 11.740896 -388.658354)
		(end 16.246602 -393.16406)
		(width 0.14605)
		(layer "In5.Cu")
		(net "PEER_1B&2B_HB")
	)
	(segment
		(start 11.740896 -217.914474)
		(end 11.740896 -388.658354)
		(width 0.14605)
		(layer "In5.Cu")
		(net "PEER_1B&2B_HB")
	)
	(segment
		(start 9.452864 -205.219554)
		(end 9.902698 -205.669388)
		(width 0.14605)
		(layer "In5.Cu")
		(net "PEER_1B&2B_HB")
	)
	(segment
		(start 9.331198 -215.504776)
		(end 11.740896 -217.914474)
		(width 0.14605)
		(layer "In5.Cu")
		(net "PEER_1B&2B_HB")
	)
	(segment
		(start 5.4864 -432.5366)
		(end 7.874 -430.149)
		(width 0.14605)
		(layer "In5.Cu")
		(net "PEER_1B&2B_HB")
	)
	(segment
		(start 7.874 -430.149)
		(end 7.874 -425.45)
		(width 0.14605)
		(layer "In5.Cu")
		(net "PEER_1B&2B_HB")
	)
	(segment
		(start 9.902698 -205.669388)
		(end 9.902698 -206.281528)
		(width 0.14605)
		(layer "In5.Cu")
		(net "PEER_1B&2B_HB")
	)
	(segment
		(start 16.246602 -393.16406)
		(end 16.246602 -415.676842)
		(width 0.14605)
		(layer "In5.Cu")
		(net "PEER_1B&2B_HB")
	)
	(segment
		(start 15.99184 -416.728656)
		(end 16.134842 -416.871658)
		(width 0.14605)
		(layer "In5.Cu")
		(net "PEER_1B&2B_HB")
	)
	(segment
		(start 9.902698 -206.281528)
		(end 9.331198 -206.853028)
		(width 0.14605)
		(layer "In5.Cu")
		(net "PEER_1B&2B_HB")
	)
	(segment
		(start 16.134842 -426.979842)
		(end 18.923 -429.768)
		(width 0.14605)
		(layer "In5.Cu")
		(net "PEER_1B&2B_HB")
	)
	(segment
		(start 15.99184 -415.931604)
		(end 15.99184 -416.728656)
		(width 0.14605)
		(layer "In5.Cu")
		(net "PEER_1B&2B_HB")
	)
	(segment
		(start 62.1284 -71.755)
		(end 62.1284 -69.8754)
		(width 0.111252)
		(layer "F.Cu")
		(net "HDD9_LED_G")
	)
	(segment
		(start 62.1284 -69.8754)
		(end 62.1284 -69.5325)
		(width 0.111252)
		(layer "F.Cu")
		(net "HDD9_LED_G")
	)
	(segment
		(start 62.1284 -69.5325)
		(end 61.0997 -68.5038)
		(width 0.111252)
		(layer "F.Cu")
		(net "HDD9_LED_G")
	)
	(segment
		(start 61.0997 -68.5038)
		(end 61.0108 -68.4149)
		(width 0.111252)
		(layer "F.Cu")
		(net "HDD9_LED_G")
	)
	(segment
		(start 58.801 -68.4149)
		(end 58.7756 -68.1482)
		(width 0.111252)
		(layer "F.Cu")
		(net "HDD9_LED_G")
	)
	(segment
		(start 58.7756 -68.1482)
		(end 58.7756 -66.7512)
		(width 0.111252)
		(layer "F.Cu")
		(net "HDD9_LED_G")
	)
	(segment
		(start 61.0108 -68.4149)
		(end 58.801 -68.4149)
		(width 0.111252)
		(layer "F.Cu")
		(net "HDD9_LED_G")
	)
	(via
		(at 58.7756 -66.7512)
		(size 0.7112)
		(drill 0.3556)
		(layers "F.Cu" "B.Cu")
		(net "HDD9_LED_G")
	)
	(segment
		(start 6.8072 -155.321)
		(end 6.627876 -155.500324)
		(width 0.111252)
		(layer "F.Cu")
		(net "PEER_1A&2A_HB")
	)
	(segment
		(start 20.447 -207.518)
		(end 20.447 -208.113884)
		(width 0.111252)
		(layer "F.Cu")
		(net "PEER_1A&2A_HB")
	)
	(segment
		(start 3.19405 -405.500332)
		(end 3.192526 -405.498808)
		(width 0.111252)
		(layer "F.Cu")
		(net "PEER_1A&2A_HB")
	)
	(segment
		(start 251.587 -416.839908)
		(end 255.474978 -416.839908)
		(width 0.111252)
		(layer "F.Cu")
		(net "PEER_1A&2A_HB")
	)
	(segment
		(start 6.956044 -406.4508)
		(end 6.005576 -405.500332)
		(width 0.111252)
		(layer "F.Cu")
		(net "PEER_1A&2A_HB")
	)
	(segment
		(start 15.672054 -208.9277)
		(end 15.532354 -208.788)
		(width 0.111252)
		(layer "F.Cu")
		(net "PEER_1A&2A_HB")
	)
	(segment
		(start 6.627876 -155.500324)
		(end 3.19405 -155.500324)
		(width 0.111252)
		(layer "F.Cu")
		(net "PEER_1A&2A_HB")
	)
	(segment
		(start 251.536708 -416.8902)
		(end 251.587 -416.839908)
		(width 0.111252)
		(layer "F.Cu")
		(net "PEER_1A&2A_HB")
	)
	(segment
		(start 244.856 -416.3568)
		(end 245.0719 -416.3568)
		(width 0.111252)
		(layer "F.Cu")
		(net "PEER_1A&2A_HB")
	)
	(segment
		(start 19.182334 -208.932526)
		(end 19.177508 -208.9277)
		(width 0.111252)
		(layer "F.Cu")
		(net "PEER_1A&2A_HB")
	)
	(segment
		(start 20.447 -208.113884)
		(end 19.628358 -208.932526)
		(width 0.111252)
		(layer "F.Cu")
		(net "PEER_1A&2A_HB")
	)
	(segment
		(start 8.534146 -406.4508)
		(end 6.956044 -406.4508)
		(width 0.111252)
		(layer "F.Cu")
		(net "PEER_1A&2A_HB")
	)
	(segment
		(start 245.6053 -416.8902)
		(end 251.536708 -416.8902)
		(width 0.111252)
		(layer "F.Cu")
		(net "PEER_1A&2A_HB")
	)
	(segment
		(start 6.005576 -405.500332)
		(end 3.19405 -405.500332)
		(width 0.111252)
		(layer "F.Cu")
		(net "PEER_1A&2A_HB")
	)
	(segment
		(start 19.628358 -208.932526)
		(end 19.182334 -208.932526)
		(width 0.111252)
		(layer "F.Cu")
		(net "PEER_1A&2A_HB")
	)
	(segment
		(start 3.19405 -155.500324)
		(end 3.192526 -155.4988)
		(width 0.111252)
		(layer "F.Cu")
		(net "PEER_1A&2A_HB")
	)
	(segment
		(start 19.177508 -208.9277)
		(end 15.672054 -208.9277)
		(width 0.111252)
		(layer "F.Cu")
		(net "PEER_1A&2A_HB")
	)
	(segment
		(start 15.532354 -208.788)
		(end 10.070846 -208.788)
		(width 0.111252)
		(layer "F.Cu")
		(net "PEER_1A&2A_HB")
	)
	(segment
		(start 245.0719 -416.3568)
		(end 245.6053 -416.8902)
		(width 0.111252)
		(layer "F.Cu")
		(net "PEER_1A&2A_HB")
	)
	(via
		(at 20.447 -207.518)
		(size 0.5588)
		(drill 0.3048)
		(layers "F.Cu" "B.Cu")
		(net "PEER_1A&2A_HB")
	)
	(via
		(at 8.534146 -406.4508)
		(size 0.5588)
		(drill 0.3048)
		(layers "F.Cu" "B.Cu")
		(net "PEER_1A&2A_HB")
	)
	(via
		(at 6.8072 -155.321)
		(size 0.5588)
		(drill 0.3048)
		(layers "F.Cu" "B.Cu")
		(net "PEER_1A&2A_HB")
	)
	(via
		(at 244.856 -416.3568)
		(size 0.5588)
		(drill 0.3048)
		(layers "F.Cu" "B.Cu")
		(net "PEER_1A&2A_HB")
	)
	(via
		(at 12.446 -402.717)
		(size 0.7112)
		(drill 0.3556)
		(layers "F.Cu" "B.Cu")
		(net "PEER_1A&2A_HB")
	)
	(via
		(at 18.9992 -402.5138)
		(size 0.5588)
		(drill 0.3048)
		(layers "F.Cu" "B.Cu")
		(net "PEER_1A&2A_HB")
	)
	(via
		(at 10.070846 -208.788)
		(size 0.5588)
		(drill 0.3048)
		(layers "F.Cu" "B.Cu")
		(net "PEER_1A&2A_HB")
	)
	(segment
		(start 12.065 -403.098)
		(end 12.446 -402.717)
		(width 0.111252)
		(layer "B.Cu")
		(net "PEER_1A&2A_HB")
	)
	(segment
		(start 18.9992 -402.5138)
		(end 18.796 -402.717)
		(width 0.111252)
		(layer "B.Cu")
		(net "PEER_1A&2A_HB")
	)
	(segment
		(start 18.796 -402.717)
		(end 12.446 -402.717)
		(width 0.111252)
		(layer "B.Cu")
		(net "PEER_1A&2A_HB")
	)
	(segment
		(start 11.886946 -403.098)
		(end 12.065 -403.098)
		(width 0.111252)
		(layer "B.Cu")
		(net "PEER_1A&2A_HB")
	)
	(segment
		(start 8.534146 -406.4508)
		(end 11.886946 -403.098)
		(width 0.111252)
		(layer "B.Cu")
		(net "PEER_1A&2A_HB")
	)
	(segment
		(start 84.201508 -404.57755)
		(end 85.458808 -405.83485)
		(width 0.14605)
		(layer "In2.Cu")
		(net "PEER_1A&2A_HB")
	)
	(segment
		(start 11.2014 -156.6672)
		(end 8.1534 -156.6672)
		(width 0.14605)
		(layer "In2.Cu")
		(net "PEER_1A&2A_HB")
	)
	(segment
		(start 8.1534 -156.6672)
		(end 6.8072 -155.321)
		(width 0.14605)
		(layer "In2.Cu")
		(net "PEER_1A&2A_HB")
	)
	(segment
		(start 18.9992 -402.5138)
		(end 23.416006 -402.5138)
		(width 0.14605)
		(layer "In2.Cu")
		(net "PEER_1A&2A_HB")
	)
	(segment
		(start 20.447 -207.518)
		(end 21.3106 -206.6544)
		(width 0.14605)
		(layer "In2.Cu")
		(net "PEER_1A&2A_HB")
	)
	(segment
		(start 25.479756 -404.57755)
		(end 25.63114 -404.57755)
		(width 0.14605)
		(layer "In2.Cu")
		(net "PEER_1A&2A_HB")
	)
	(segment
		(start 25.631394 -404.577804)
		(end 26.36266 -404.577804)
		(width 0.14605)
		(layer "In2.Cu")
		(net "PEER_1A&2A_HB")
	)
	(segment
		(start 21.3106 -206.6544)
		(end 21.3106 -166.7764)
		(width 0.14605)
		(layer "In2.Cu")
		(net "PEER_1A&2A_HB")
	)
	(segment
		(start 26.36266 -404.577804)
		(end 26.362914 -404.57755)
		(width 0.14605)
		(layer "In2.Cu")
		(net "PEER_1A&2A_HB")
	)
	(segment
		(start 235.729018 -405.835358)
		(end 235.729526 -405.835358)
		(width 0.14605)
		(layer "In2.Cu")
		(net "PEER_1A&2A_HB")
	)
	(segment
		(start 26.362914 -404.57755)
		(end 84.201508 -404.57755)
		(width 0.14605)
		(layer "In2.Cu")
		(net "PEER_1A&2A_HB")
	)
	(segment
		(start 244.8814 -416.3314)
		(end 244.856 -416.3568)
		(width 0.14605)
		(layer "In2.Cu")
		(net "PEER_1A&2A_HB")
	)
	(segment
		(start 235.72851 -405.83485)
		(end 235.729018 -405.835358)
		(width 0.14605)
		(layer "In2.Cu")
		(net "PEER_1A&2A_HB")
	)
	(segment
		(start 85.458808 -405.83485)
		(end 235.72851 -405.83485)
		(width 0.14605)
		(layer "In2.Cu")
		(net "PEER_1A&2A_HB")
	)
	(segment
		(start 235.729526 -405.835358)
		(end 244.8814 -414.988756)
		(width 0.14605)
		(layer "In2.Cu")
		(net "PEER_1A&2A_HB")
	)
	(segment
		(start 23.416006 -402.5138)
		(end 25.479756 -404.57755)
		(width 0.14605)
		(layer "In2.Cu")
		(net "PEER_1A&2A_HB")
	)
	(segment
		(start 25.63114 -404.57755)
		(end 25.631394 -404.577804)
		(width 0.14605)
		(layer "In2.Cu")
		(net "PEER_1A&2A_HB")
	)
	(segment
		(start 21.3106 -166.7764)
		(end 11.2014 -156.6672)
		(width 0.14605)
		(layer "In2.Cu")
		(net "PEER_1A&2A_HB")
	)
	(segment
		(start 244.8814 -414.988756)
		(end 244.8814 -416.3314)
		(width 0.14605)
		(layer "In2.Cu")
		(net "PEER_1A&2A_HB")
	)
	(segment
		(start 9.782048 -209.076798)
		(end 9.782048 -215.317832)
		(width 0.14605)
		(layer "In5.Cu")
		(net "PEER_1A&2A_HB")
	)
	(segment
		(start 12.191746 -217.72753)
		(end 12.191746 -388.47141)
		(width 0.14605)
		(layer "In5.Cu")
		(net "PEER_1A&2A_HB")
	)
	(segment
		(start 16.697452 -400.212052)
		(end 18.9992 -402.5138)
		(width 0.14605)
		(layer "In5.Cu")
		(net "PEER_1A&2A_HB")
	)
	(segment
		(start 12.191746 -388.47141)
		(end 16.697452 -392.977116)
		(width 0.14605)
		(layer "In5.Cu")
		(net "PEER_1A&2A_HB")
	)
	(segment
		(start 10.070846 -208.788)
		(end 9.782048 -209.076798)
		(width 0.14605)
		(layer "In5.Cu")
		(net "PEER_1A&2A_HB")
	)
	(segment
		(start 9.782048 -215.317832)
		(end 12.191746 -217.72753)
		(width 0.14605)
		(layer "In5.Cu")
		(net "PEER_1A&2A_HB")
	)
	(segment
		(start 16.697452 -392.977116)
		(end 16.697452 -400.212052)
		(width 0.14605)
		(layer "In5.Cu")
		(net "PEER_1A&2A_HB")
	)
	(segment
		(start 96.901 -11.684)
		(end 96.2279 -11.0109)
		(width 0.111252)
		(layer "F.Cu")
		(net "SW_HDD14_G")
	)
	(segment
		(start 96.2279 -10.7442)
		(end 96.6978 -10.7442)
		(width 0.111252)
		(layer "F.Cu")
		(net "SW_HDD14_G")
	)
	(segment
		(start 96.2279 -11.0109)
		(end 96.2279 -10.7442)
		(width 0.111252)
		(layer "F.Cu")
		(net "SW_HDD14_G")
	)
	(segment
		(start 96.6978 -10.7442)
		(end 97.5233 -9.9187)
		(width 0.111252)
		(layer "F.Cu")
		(net "SW_HDD14_G")
	)
	(segment
		(start 97.5233 -9.9187)
		(end 98.246946 -9.9187)
		(width 0.111252)
		(layer "F.Cu")
		(net "SW_HDD14_G")
	)
	(via
		(at 96.901 -11.684)
		(size 0.7112)
		(drill 0.3556)
		(layers "F.Cu" "B.Cu")
		(net "SW_HDD14_G")
	)
	(segment
		(start 39.306246 -41.9227)
		(end 39.1668 -42.062146)
		(width 0.508)
		(layer "F.Cu")
		(net "P5VB_HDD9_LED")
	)
	(segment
		(start 63.6016 -71.9074)
		(end 63.4492 -71.755)
		(width 0.4064)
		(layer "F.Cu")
		(net "P5VB_HDD9_LED")
	)
	(segment
		(start 39.1668 -42.062146)
		(end 39.1668 -42.799)
		(width 0.508)
		(layer "F.Cu")
		(net "P5VB_HDD9_LED")
	)
	(segment
		(start 63.4492 -71.755)
		(end 62.77864 -71.755)
		(width 0.4064)
		(layer "F.Cu")
		(net "P5VB_HDD9_LED")
	)
	(via
		(at 39.1668 -42.799)
		(size 0.5588)
		(drill 0.3048)
		(layers "F.Cu" "B.Cu")
		(net "P5VB_HDD9_LED")
	)
	(via
		(at 63.6016 -71.9074)
		(size 0.5588)
		(drill 0.3048)
		(layers "F.Cu" "B.Cu")
		(net "P5VB_HDD9_LED")
	)
	(via
		(at 39.831518 -42.134282)
		(size 0.7112)
		(drill 0.3556)
		(layers "F.Cu" "B.Cu")
		(net "P5VB_HDD9_LED")
	)
	(segment
		(start 39.1668 -42.799)
		(end 39.831518 -42.134282)
		(width 0.508)
		(layer "B.Cu")
		(net "P5VB_HDD9_LED")
	)
	(segment
		(start 63.6016 -71.7804)
		(end 63.6016 -71.9074)
		(width 0.508)
		(layer "In2.Cu")
		(net "P5VB_HDD9_LED")
	)
	(segment
		(start 43.568366 -43.2308)
		(end 44.94911 -43.2308)
		(width 0.508)
		(layer "In2.Cu")
		(net "P5VB_HDD9_LED")
	)
	(segment
		(start 43.136566 -42.799)
		(end 43.568366 -43.2308)
		(width 0.508)
		(layer "In2.Cu")
		(net "P5VB_HDD9_LED")
	)
	(segment
		(start 61.4807 -59.76239)
		(end 61.4807 -69.6595)
		(width 0.508)
		(layer "In2.Cu")
		(net "P5VB_HDD9_LED")
	)
	(segment
		(start 61.4807 -69.6595)
		(end 63.6016 -71.7804)
		(width 0.508)
		(layer "In2.Cu")
		(net "P5VB_HDD9_LED")
	)
	(segment
		(start 39.1668 -42.799)
		(end 43.136566 -42.799)
		(width 0.508)
		(layer "In2.Cu")
		(net "P5VB_HDD9_LED")
	)
	(segment
		(start 44.94911 -43.2308)
		(end 61.4807 -59.76239)
		(width 0.508)
		(layer "In2.Cu")
		(net "P5VB_HDD9_LED")
	)
	(segment
		(start 41.39692 -110.274354)
		(end 41.768268 -110.645702)
		(width 0.111252)
		(layer "F.Cu")
		(net "SW_HDD13_G")
	)
	(segment
		(start 41.3004 -108.926884)
		(end 41.3004 -110.15726)
		(width 0.111252)
		(layer "F.Cu")
		(net "SW_HDD13_G")
	)
	(segment
		(start 41.685972 -108.541312)
		(end 41.3004 -108.926884)
		(width 0.111252)
		(layer "F.Cu")
		(net "SW_HDD13_G")
	)
	(segment
		(start 41.9227 -107.7722)
		(end 41.148 -106.9975)
		(width 0.111252)
		(layer "F.Cu")
		(net "SW_HDD13_G")
	)
	(segment
		(start 42.3799 -107.7976)
		(end 41.685972 -108.491528)
		(width 0.111252)
		(layer "F.Cu")
		(net "SW_HDD13_G")
	)
	(segment
		(start 41.3004 -110.15726)
		(end 41.39692 -110.25378)
		(width 0.111252)
		(layer "F.Cu")
		(net "SW_HDD13_G")
	)
	(segment
		(start 42.3799 -107.7722)
		(end 41.9227 -107.7722)
		(width 0.111252)
		(layer "F.Cu")
		(net "SW_HDD13_G")
	)
	(segment
		(start 41.39692 -110.25378)
		(end 41.39692 -110.274354)
		(width 0.111252)
		(layer "F.Cu")
		(net "SW_HDD13_G")
	)
	(segment
		(start 41.685972 -108.491528)
		(end 41.685972 -108.541312)
		(width 0.111252)
		(layer "F.Cu")
		(net "SW_HDD13_G")
	)
	(segment
		(start 41.768268 -110.645702)
		(end 42.087546 -110.645702)
		(width 0.111252)
		(layer "F.Cu")
		(net "SW_HDD13_G")
	)
	(segment
		(start 42.3799 -107.7722)
		(end 42.3799 -107.7976)
		(width 0.111252)
		(layer "F.Cu")
		(net "SW_HDD13_G")
	)
	(via
		(at 41.148 -106.9975)
		(size 0.7112)
		(drill 0.3556)
		(layers "F.Cu" "B.Cu")
		(net "SW_HDD13_G")
	)
	(segment
		(start 48.056546 -211.864702)
		(end 48.452024 -211.864702)
		(width 0.111252)
		(layer "F.Cu")
		(net "SW_HDD12_G")
	)
	(segment
		(start 48.814736 -209.659728)
		(end 48.751744 -209.596736)
		(width 0.111252)
		(layer "F.Cu")
		(net "SW_HDD12_G")
	)
	(segment
		(start 48.452024 -211.864702)
		(end 48.814736 -211.501736)
		(width 0.111252)
		(layer "F.Cu")
		(net "SW_HDD12_G")
	)
	(segment
		(start 48.814736 -211.501736)
		(end 48.814736 -209.659728)
		(width 0.111252)
		(layer "F.Cu")
		(net "SW_HDD12_G")
	)
	(segment
		(start 49.30648 -209.042)
		(end 48.751744 -209.596736)
		(width 0.111252)
		(layer "F.Cu")
		(net "SW_HDD12_G")
	)
	(segment
		(start 49.6189 -209.042)
		(end 49.30648 -209.042)
		(width 0.111252)
		(layer "F.Cu")
		(net "SW_HDD12_G")
	)
	(via
		(at 48.751744 -209.596736)
		(size 0.7112)
		(drill 0.3556)
		(layers "F.Cu" "B.Cu")
		(net "SW_HDD12_G")
	)
	(segment
		(start 59.63285 -175.355758)
		(end 59.563 -175.425608)
		(width 0.111252)
		(layer "F.Cu")
		(net "HDD8_LED_B")
	)
	(segment
		(start 58.649108 -175.425608)
		(end 59.563 -175.425608)
		(width 0.111252)
		(layer "F.Cu")
		(net "HDD8_LED_B")
	)
	(segment
		(start 58.3565 -175.133)
		(end 58.649108 -175.425608)
		(width 0.111252)
		(layer "F.Cu")
		(net "HDD8_LED_B")
	)
	(segment
		(start 59.63285 -173.6725)
		(end 59.63285 -175.355758)
		(width 0.111252)
		(layer "F.Cu")
		(net "HDD8_LED_B")
	)
	(via
		(at 59.563 -175.425608)
		(size 0.7112)
		(drill 0.3556)
		(layers "F.Cu" "B.Cu")
		(net "HDD8_LED_B")
	)
	(segment
		(start 61.976 -173.355)
		(end 61.976 -173.0121)
		(width 0.111252)
		(layer "F.Cu")
		(net "HDD8_LED_G")
	)
	(segment
		(start 60.96 -171.8818)
		(end 60.96 -170.2562)
		(width 0.111252)
		(layer "F.Cu")
		(net "HDD8_LED_G")
	)
	(segment
		(start 60.9473 -171.9834)
		(end 60.7314 -171.7675)
		(width 0.111252)
		(layer "F.Cu")
		(net "HDD8_LED_G")
	)
	(segment
		(start 60.9473 -171.9834)
		(end 60.96 -171.8818)
		(width 0.111252)
		(layer "F.Cu")
		(net "HDD8_LED_G")
	)
	(segment
		(start 61.976 -173.0121)
		(end 60.9473 -171.9834)
		(width 0.111252)
		(layer "F.Cu")
		(net "HDD8_LED_G")
	)
	(segment
		(start 60.7314 -171.7675)
		(end 58.6486 -171.7675)
		(width 0.111252)
		(layer "F.Cu")
		(net "HDD8_LED_G")
	)
	(segment
		(start 61.976 -175.2346)
		(end 61.976 -173.355)
		(width 0.111252)
		(layer "F.Cu")
		(net "HDD8_LED_G")
	)
	(segment
		(start 60.96 -170.2562)
		(end 60.7822 -170.0784)
		(width 0.111252)
		(layer "F.Cu")
		(net "HDD8_LED_G")
	)
	(via
		(at 60.7822 -170.0784)
		(size 0.7112)
		(drill 0.3556)
		(layers "F.Cu" "B.Cu")
		(net "HDD8_LED_G")
	)
	(segment
		(start 39.179246 -144.7927)
		(end 39.179246 -145.071846)
		(width 0.508)
		(layer "F.Cu")
		(net "P5VB_HDD8_LED")
	)
	(segment
		(start 62.62624 -175.2346)
		(end 63.4492 -175.2346)
		(width 0.4064)
		(layer "F.Cu")
		(net "P5VB_HDD8_LED")
	)
	(segment
		(start 39.865554 -145.758154)
		(end 39.878 -145.758154)
		(width 0.508)
		(layer "F.Cu")
		(net "P5VB_HDD8_LED")
	)
	(segment
		(start 39.179246 -145.071846)
		(end 39.865554 -145.758154)
		(width 0.508)
		(layer "F.Cu")
		(net "P5VB_HDD8_LED")
	)
	(via
		(at 39.878 -145.758154)
		(size 0.5588)
		(drill 0.3048)
		(layers "F.Cu" "B.Cu")
		(net "P5VB_HDD8_LED")
	)
	(via
		(at 38.862 -145.796)
		(size 0.7112)
		(drill 0.3556)
		(layers "F.Cu" "B.Cu")
		(net "P5VB_HDD8_LED")
	)
	(via
		(at 63.4492 -175.2346)
		(size 0.5588)
		(drill 0.3048)
		(layers "F.Cu" "B.Cu")
		(net "P5VB_HDD8_LED")
	)
	(segment
		(start 39.8018 -145.796)
		(end 38.862 -145.796)
		(width 0.508)
		(layer "B.Cu")
		(net "P5VB_HDD8_LED")
	)
	(segment
		(start 39.878 -145.758154)
		(end 39.8018 -145.796)
		(width 0.508)
		(layer "B.Cu")
		(net "P5VB_HDD8_LED")
	)
	(segment
		(start 54.000146 -154.238452)
		(end 54.000146 -154.056588)
		(width 0.508)
		(layer "In2.Cu")
		(net "P5VB_HDD8_LED")
	)
	(segment
		(start 53.092858 -153.1493)
		(end 52.910994 -153.1493)
		(width 0.508)
		(layer "In2.Cu")
		(net "P5VB_HDD8_LED")
	)
	(segment
		(start 40.499284 -145.758154)
		(end 39.878 -145.758154)
		(width 0.508)
		(layer "In2.Cu")
		(net "P5VB_HDD8_LED")
	)
	(segment
		(start 61.3918 -172.7454)
		(end 61.3918 -161.630106)
		(width 0.508)
		(layer "In2.Cu")
		(net "P5VB_HDD8_LED")
	)
	(segment
		(start 63.4492 -175.2346)
		(end 63.4492 -174.8028)
		(width 0.508)
		(layer "In2.Cu")
		(net "P5VB_HDD8_LED")
	)
	(segment
		(start 45.98289 -146.220942)
		(end 45.507148 -145.7452)
		(width 0.508)
		(layer "In2.Cu")
		(net "P5VB_HDD8_LED")
	)
	(segment
		(start 45.507148 -145.7452)
		(end 40.512238 -145.7452)
		(width 0.508)
		(layer "In2.Cu")
		(net "P5VB_HDD8_LED")
	)
	(segment
		(start 63.4492 -174.8028)
		(end 61.3918 -172.7454)
		(width 0.508)
		(layer "In2.Cu")
		(net "P5VB_HDD8_LED")
	)
	(segment
		(start 61.3918 -161.630106)
		(end 54.000146 -154.238452)
		(width 0.508)
		(layer "In2.Cu")
		(net "P5VB_HDD8_LED")
	)
	(segment
		(start 52.910994 -153.1493)
		(end 45.98289 -146.221196)
		(width 0.508)
		(layer "In2.Cu")
		(net "P5VB_HDD8_LED")
	)
	(segment
		(start 40.512238 -145.7452)
		(end 40.499284 -145.758154)
		(width 0.508)
		(layer "In2.Cu")
		(net "P5VB_HDD8_LED")
	)
	(segment
		(start 45.98289 -146.221196)
		(end 45.98289 -146.220942)
		(width 0.508)
		(layer "In2.Cu")
		(net "P5VB_HDD8_LED")
	)
	(segment
		(start 54.000146 -154.056588)
		(end 53.092858 -153.1493)
		(width 0.508)
		(layer "In2.Cu")
		(net "P5VB_HDD8_LED")
	)
	(segment
		(start 33.3375 -306.324)
		(end 32.766 -306.324)
		(width 0.111252)
		(layer "F.Cu")
		(net "SW_HDD11_G")
	)
	(segment
		(start 32.424624 -308.548024)
		(end 32.424624 -308.441344)
		(width 0.111252)
		(layer "F.Cu")
		(net "SW_HDD11_G")
	)
	(segment
		(start 32.766 -306.324)
		(end 32.385 -306.705)
		(width 0.111252)
		(layer "F.Cu")
		(net "SW_HDD11_G")
	)
	(segment
		(start 32.424624 -308.441344)
		(end 32.385 -308.40172)
		(width 0.111252)
		(layer "F.Cu")
		(net "SW_HDD11_G")
	)
	(segment
		(start 32.769302 -308.892702)
		(end 32.424624 -308.548024)
		(width 0.111252)
		(layer "F.Cu")
		(net "SW_HDD11_G")
	)
	(segment
		(start 32.385 -308.40172)
		(end 32.385 -306.705)
		(width 0.111252)
		(layer "F.Cu")
		(net "SW_HDD11_G")
	)
	(segment
		(start 33.197546 -308.892702)
		(end 32.769302 -308.892702)
		(width 0.111252)
		(layer "F.Cu")
		(net "SW_HDD11_G")
	)
	(via
		(at 32.385 -306.705)
		(size 0.7112)
		(drill 0.3556)
		(layers "F.Cu" "B.Cu")
		(net "SW_HDD11_G")
	)
	(segment
		(start 48.9712 -419.3667)
		(end 48.812958 -419.208458)
		(width 0.111252)
		(layer "F.Cu")
		(net "SW_HDD10_G")
	)
	(segment
		(start 48.812958 -419.208458)
		(end 47.599346 -419.208458)
		(width 0.111252)
		(layer "F.Cu")
		(net "SW_HDD10_G")
	)
	(segment
		(start 50.165 -419.1)
		(end 50.165 -419.1127)
		(width 0.111252)
		(layer "F.Cu")
		(net "SW_HDD10_G")
	)
	(segment
		(start 49.911 -419.3667)
		(end 48.9712 -419.3667)
		(width 0.111252)
		(layer "F.Cu")
		(net "SW_HDD10_G")
	)
	(segment
		(start 50.165 -419.1127)
		(end 49.911 -419.3667)
		(width 0.111252)
		(layer "F.Cu")
		(net "SW_HDD10_G")
	)
	(via
		(at 50.165 -419.1)
		(size 0.7112)
		(drill 0.3556)
		(layers "F.Cu" "B.Cu")
		(net "SW_HDD10_G")
	)
	(segment
		(start 80.8863 -92.8497)
		(end 80.8863 -92.7608)
		(width 0.111252)
		(layer "F.Cu")
		(net "SW_HDD9_G")
	)
	(segment
		(start 80.898746 -92.748354)
		(end 80.898746 -91.3765)
		(width 0.111252)
		(layer "F.Cu")
		(net "SW_HDD9_G")
	)
	(segment
		(start 81.275682 -93.239082)
		(end 80.8863 -92.8497)
		(width 0.111252)
		(layer "F.Cu")
		(net "SW_HDD9_G")
	)
	(segment
		(start 80.8863 -92.7608)
		(end 80.898746 -92.748354)
		(width 0.111252)
		(layer "F.Cu")
		(net "SW_HDD9_G")
	)
	(segment
		(start 82.459576 -93.239082)
		(end 81.275682 -93.239082)
		(width 0.111252)
		(layer "F.Cu")
		(net "SW_HDD9_G")
	)
	(via
		(at 82.459576 -93.239082)
		(size 0.7112)
		(drill 0.3556)
		(layers "F.Cu" "B.Cu")
		(net "SW_HDD9_G")
	)
	(segment
		(start 81.1657 -196.1642)
		(end 81.1403 -196.1388)
		(width 0.111252)
		(layer "F.Cu")
		(net "SW_HDD8_G")
	)
	(segment
		(start 81.152746 -196.126354)
		(end 81.152746 -194.7545)
		(width 0.111252)
		(layer "F.Cu")
		(net "SW_HDD8_G")
	)
	(segment
		(start 81.1403 -196.1388)
		(end 81.152746 -196.126354)
		(width 0.111252)
		(layer "F.Cu")
		(net "SW_HDD8_G")
	)
	(segment
		(start 82.169 -196.1642)
		(end 81.1657 -196.1642)
		(width 0.111252)
		(layer "F.Cu")
		(net "SW_HDD8_G")
	)
	(via
		(at 82.169 -196.1642)
		(size 0.7112)
		(drill 0.3556)
		(layers "F.Cu" "B.Cu")
		(net "SW_HDD8_G")
	)
	(segment
		(start 58.50128 -272.82648)
		(end 59.5884 -272.82648)
		(width 0.4064)
		(layer "F.Cu")
		(net "P5VB_HDD7_LED")
	)
	(segment
		(start 58.3692 -272.6944)
		(end 58.50128 -272.82648)
		(width 0.4064)
		(layer "F.Cu")
		(net "P5VB_HDD7_LED")
	)
	(segment
		(start 39.306246 -247.7897)
		(end 39.306246 -248.703846)
		(width 0.508)
		(layer "F.Cu")
		(net "P5VB_HDD7_LED")
	)
	(via
		(at 58.3692 -272.6944)
		(size 0.5588)
		(drill 0.3048)
		(layers "F.Cu" "B.Cu")
		(net "P5VB_HDD7_LED")
	)
	(via
		(at 39.306246 -248.703846)
		(size 0.5588)
		(drill 0.3048)
		(layers "F.Cu" "B.Cu")
		(net "P5VB_HDD7_LED")
	)
	(via
		(at 58.3692 -273.6342)
		(size 0.7112)
		(drill 0.3556)
		(layers "F.Cu" "B.Cu")
		(net "P5VB_HDD7_LED")
	)
	(segment
		(start 58.3692 -272.6944)
		(end 58.3692 -273.6342)
		(width 0.508)
		(layer "B.Cu")
		(net "P5VB_HDD7_LED")
	)
	(segment
		(start 41.839642 -248.703846)
		(end 39.306246 -248.703846)
		(width 0.508)
		(layer "In2.Cu")
		(net "P5VB_HDD7_LED")
	)
	(segment
		(start 58.3692 -272.6944)
		(end 58.3692 -265.233404)
		(width 0.508)
		(layer "In2.Cu")
		(net "P5VB_HDD7_LED")
	)
	(segment
		(start 58.3692 -265.233404)
		(end 41.839642 -248.703846)
		(width 0.508)
		(layer "In2.Cu")
		(net "P5VB_HDD7_LED")
	)
	(segment
		(start 57.8104 -274.8534)
		(end 57.8104 -274.701)
		(width 0.111252)
		(layer "F.Cu")
		(net "HDD7_LED_B")
	)
	(segment
		(start 59.436 -276.733)
		(end 59.436 -276.479)
		(width 0.111252)
		(layer "F.Cu")
		(net "HDD7_LED_B")
	)
	(segment
		(start 59.436 -276.479)
		(end 57.912 -274.955)
		(width 0.111252)
		(layer "F.Cu")
		(net "HDD7_LED_B")
	)
	(segment
		(start 57.8104 -274.701)
		(end 57.0484 -273.939)
		(width 0.111252)
		(layer "F.Cu")
		(net "HDD7_LED_B")
	)
	(segment
		(start 57.912 -274.955)
		(end 57.8104 -274.8534)
		(width 0.111252)
		(layer "F.Cu")
		(net "HDD7_LED_B")
	)
	(segment
		(start 57.0484 -273.939)
		(end 56.8198 -273.939)
		(width 0.111252)
		(layer "F.Cu")
		(net "HDD7_LED_B")
	)
	(via
		(at 56.8198 -273.939)
		(size 0.7112)
		(drill 0.3556)
		(layers "F.Cu" "B.Cu")
		(net "HDD7_LED_B")
	)
	(segment
		(start 62.865 -273.177)
		(end 61.86424 -272.17624)
		(width 0.111252)
		(layer "F.Cu")
		(net "HDD7_LED_G")
	)
	(segment
		(start 57.76976 -272.17624)
		(end 59.5884 -272.17624)
		(width 0.111252)
		(layer "F.Cu")
		(net "HDD7_LED_G")
	)
	(segment
		(start 61.341 -275.74875)
		(end 61.341 -274.701)
		(width 0.111252)
		(layer "F.Cu")
		(net "HDD7_LED_G")
	)
	(segment
		(start 61.341 -274.701)
		(end 62.0522 -273.9898)
		(width 0.111252)
		(layer "F.Cu")
		(net "HDD7_LED_G")
	)
	(segment
		(start 62.0522 -273.9898)
		(end 62.8142 -273.9898)
		(width 0.111252)
		(layer "F.Cu")
		(net "HDD7_LED_G")
	)
	(segment
		(start 62.8142 -273.9898)
		(end 62.865 -273.939)
		(width 0.111252)
		(layer "F.Cu")
		(net "HDD7_LED_G")
	)
	(segment
		(start 57.665112 -272.071592)
		(end 57.76976 -272.17624)
		(width 0.111252)
		(layer "F.Cu")
		(net "HDD7_LED_G")
	)
	(segment
		(start 59.5884 -272.17624)
		(end 61.468 -272.17624)
		(width 0.111252)
		(layer "F.Cu")
		(net "HDD7_LED_G")
	)
	(segment
		(start 62.865 -273.939)
		(end 62.865 -273.177)
		(width 0.111252)
		(layer "F.Cu")
		(net "HDD7_LED_G")
	)
	(segment
		(start 61.86424 -272.17624)
		(end 61.468 -272.17624)
		(width 0.111252)
		(layer "F.Cu")
		(net "HDD7_LED_G")
	)
	(via
		(at 57.665112 -272.071592)
		(size 0.7112)
		(drill 0.3556)
		(layers "F.Cu" "B.Cu")
		(net "HDD7_LED_G")
	)
	(segment
		(start 27.639772 -280.807668)
		(end 27.639772 -280.814526)
		(width 0.111252)
		(layer "F.Cu")
		(net "SW_HDD7_G")
	)
	(segment
		(start 25.527 -280.3525)
		(end 25.2095 -280.3525)
		(width 0.111252)
		(layer "F.Cu")
		(net "SW_HDD7_G")
	)
	(segment
		(start 27.184604 -280.3525)
		(end 27.639772 -280.807668)
		(width 0.111252)
		(layer "F.Cu")
		(net "SW_HDD7_G")
	)
	(segment
		(start 27.639772 -280.814526)
		(end 27.686 -280.860754)
		(width 0.111252)
		(layer "F.Cu")
		(net "SW_HDD7_G")
	)
	(segment
		(start 27.5082 -281.7368)
		(end 26.949146 -281.7368)
		(width 0.111252)
		(layer "F.Cu")
		(net "SW_HDD7_G")
	)
	(segment
		(start 27.686 -281.559)
		(end 27.5082 -281.7368)
		(width 0.111252)
		(layer "F.Cu")
		(net "SW_HDD7_G")
	)
	(segment
		(start 25.2095 -280.3525)
		(end 24.384 -281.178)
		(width 0.111252)
		(layer "F.Cu")
		(net "SW_HDD7_G")
	)
	(segment
		(start 27.686 -280.860754)
		(end 27.686 -281.559)
		(width 0.111252)
		(layer "F.Cu")
		(net "SW_HDD7_G")
	)
	(segment
		(start 25.527 -280.3525)
		(end 27.184604 -280.3525)
		(width 0.111252)
		(layer "F.Cu")
		(net "SW_HDD7_G")
	)
	(via
		(at 24.384 -281.178)
		(size 0.7112)
		(drill 0.3556)
		(layers "F.Cu" "B.Cu")
		(net "SW_HDD7_G")
	)
	(segment
		(start 182.261256 -458.22743)
		(end 182.035704 -458.452982)
		(width 0.508)
		(layer "F.Cu")
		(net "P12V_SENSE")
	)
	(segment
		(start 175.191674 -459.400656)
		(end 173.405546 -459.400656)
		(width 0.3048)
		(layer "F.Cu")
		(net "P12V_SENSE")
	)
	(segment
		(start 177.113946 -459.393036)
		(end 176.923446 -459.583536)
		(width 0.508)
		(layer "F.Cu")
		(net "P12V_SENSE")
	)
	(segment
		(start 177.113946 -459.132178)
		(end 177.113946 -459.393036)
		(width 0.508)
		(layer "F.Cu")
		(net "P12V_SENSE")
	)
	(segment
		(start 176.923446 -459.583536)
		(end 176.161446 -459.583536)
		(width 0.508)
		(layer "F.Cu")
		(net "P12V_SENSE")
	)
	(segment
		(start 182.035704 -458.452982)
		(end 177.793142 -458.452982)
		(width 0.508)
		(layer "F.Cu")
		(net "P12V_SENSE")
	)
	(segment
		(start 175.374554 -459.583536)
		(end 175.191674 -459.400656)
		(width 0.508)
		(layer "F.Cu")
		(net "P12V_SENSE")
	)
	(segment
		(start 176.161446 -459.583536)
		(end 175.374554 -459.583536)
		(width 0.508)
		(layer "F.Cu")
		(net "P12V_SENSE")
	)
	(segment
		(start 177.793142 -458.452982)
		(end 177.113946 -459.132178)
		(width 0.508)
		(layer "F.Cu")
		(net "P12V_SENSE")
	)
	(via
		(at 182.261256 -458.22743)
		(size 0.7112)
		(drill 0.3556)
		(layers "F.Cu" "B.Cu")
		(net "P12V_SENSE")
	)
	(segment
		(start 10.540746 -54.03215)
		(end 10.540746 -55.6387)
		(width 0.111252)
		(layer "F.Cu")
		(net "FLT_HDD14_B")
	)
	(segment
		(start 11.785346 -55.6387)
		(end 10.540746 -55.6387)
		(width 0.111252)
		(layer "F.Cu")
		(net "FLT_HDD14_B")
	)
	(segment
		(start 10.782046 -53.79085)
		(end 10.540746 -54.03215)
		(width 0.111252)
		(layer "F.Cu")
		(net "FLT_HDD14_B")
	)
	(segment
		(start 12.280646 -55.1434)
		(end 11.785346 -55.6387)
		(width 0.111252)
		(layer "F.Cu")
		(net "FLT_HDD14_B")
	)
	(via
		(at 10.540746 -55.6387)
		(size 0.7112)
		(drill 0.3556)
		(layers "F.Cu" "B.Cu")
		(net "FLT_HDD14_B")
	)
	(segment
		(start 19.240246 -162.1282)
		(end 19.430746 -161.9377)
		(width 0.111252)
		(layer "F.Cu")
		(net "FLT_HDD13_B")
	)
	(segment
		(start 18.808446 -163.6395)
		(end 19.240246 -163.2077)
		(width 0.111252)
		(layer "F.Cu")
		(net "FLT_HDD13_B")
	)
	(segment
		(start 19.240246 -163.2077)
		(end 19.240246 -162.1282)
		(width 0.111252)
		(layer "F.Cu")
		(net "FLT_HDD13_B")
	)
	(segment
		(start 18.808446 -164.59835)
		(end 18.808446 -163.6395)
		(width 0.111252)
		(layer "F.Cu")
		(net "FLT_HDD13_B")
	)
	(via
		(at 19.430746 -161.9377)
		(size 0.7112)
		(drill 0.3556)
		(layers "F.Cu" "B.Cu")
		(net "FLT_HDD13_B")
	)
	(segment
		(start 7.9375 -270.383)
		(end 8.636 -269.6845)
		(width 0.111252)
		(layer "F.Cu")
		(net "FLT_HDD12_B")
	)
	(segment
		(start 6.731 -270.383)
		(end 6.457696 -270.383)
		(width 0.111252)
		(layer "F.Cu")
		(net "FLT_HDD12_B")
	)
	(segment
		(start 6.731 -270.383)
		(end 7.9375 -270.383)
		(width 0.111252)
		(layer "F.Cu")
		(net "FLT_HDD12_B")
	)
	(segment
		(start 6.457696 -270.383)
		(end 5.295646 -269.22095)
		(width 0.111252)
		(layer "F.Cu")
		(net "FLT_HDD12_B")
	)
	(via
		(at 6.731 -270.383)
		(size 0.7112)
		(drill 0.3556)
		(layers "F.Cu" "B.Cu")
		(net "FLT_HDD12_B")
	)
	(segment
		(start 34.861246 -342.30945)
		(end 34.861246 -341.286846)
		(width 0.111252)
		(layer "F.Cu")
		(net "FLT_HDD11_B")
	)
	(segment
		(start 33.337246 -340.8807)
		(end 33.349692 -340.868254)
		(width 0.111252)
		(layer "F.Cu")
		(net "FLT_HDD11_B")
	)
	(segment
		(start 33.349692 -340.868254)
		(end 34.442654 -340.868254)
		(width 0.111252)
		(layer "F.Cu")
		(net "FLT_HDD11_B")
	)
	(segment
		(start 34.861246 -341.286846)
		(end 34.5948 -341.0204)
		(width 0.111252)
		(layer "F.Cu")
		(net "FLT_HDD11_B")
	)
	(segment
		(start 34.442654 -340.868254)
		(end 34.5948 -341.0204)
		(width 0.111252)
		(layer "F.Cu")
		(net "FLT_HDD11_B")
	)
	(via
		(at 34.5948 -341.0204)
		(size 0.7112)
		(drill 0.3556)
		(layers "F.Cu" "B.Cu")
		(net "FLT_HDD11_B")
	)
	(segment
		(start 16.217646 -470.3826)
		(end 16.217646 -469.86825)
		(width 0.111252)
		(layer "F.Cu")
		(net "FLT_HDD10_B")
	)
	(segment
		(start 15.347696 -469.00465)
		(end 15.354046 -469.00465)
		(width 0.111252)
		(layer "F.Cu")
		(net "FLT_HDD10_B")
	)
	(segment
		(start 14.5542 -468.211154)
		(end 15.347696 -469.00465)
		(width 0.111252)
		(layer "F.Cu")
		(net "FLT_HDD10_B")
	)
	(segment
		(start 16.217646 -469.86825)
		(end 15.354046 -469.00465)
		(width 0.111252)
		(layer "F.Cu")
		(net "FLT_HDD10_B")
	)
	(segment
		(start 14.731746 -464.8327)
		(end 14.5542 -465.010246)
		(width 0.111252)
		(layer "F.Cu")
		(net "FLT_HDD10_B")
	)
	(segment
		(start 14.5542 -465.010246)
		(end 14.5542 -468.211154)
		(width 0.111252)
		(layer "F.Cu")
		(net "FLT_HDD10_B")
	)
	(via
		(at 14.731746 -464.8327)
		(size 0.7112)
		(drill 0.3556)
		(layers "F.Cu" "B.Cu")
		(net "FLT_HDD10_B")
	)
	(segment
		(start 49.161446 -39.1414)
		(end 48.628046 -38.608)
		(width 0.111252)
		(layer "F.Cu")
		(net "FLT_HDD9_B")
	)
	(segment
		(start 49.161446 -39.96055)
		(end 49.161446 -39.1414)
		(width 0.111252)
		(layer "F.Cu")
		(net "FLT_HDD9_B")
	)
	(segment
		(start 47.408846 -38.608)
		(end 48.628046 -38.608)
		(width 0.111252)
		(layer "F.Cu")
		(net "FLT_HDD9_B")
	)
	(via
		(at 48.628046 -38.608)
		(size 0.7112)
		(drill 0.3556)
		(layers "F.Cu" "B.Cu")
		(net "FLT_HDD9_B")
	)
	(segment
		(start 49.161446 -143.38935)
		(end 49.402746 -143.14805)
		(width 0.111252)
		(layer "F.Cu")
		(net "FLT_HDD8_B")
	)
	(segment
		(start 47.408846 -142.0622)
		(end 47.726346 -141.7447)
		(width 0.111252)
		(layer "F.Cu")
		(net "FLT_HDD8_B")
	)
	(segment
		(start 49.402746 -143.14805)
		(end 49.402746 -141.8717)
		(width 0.111252)
		(layer "F.Cu")
		(net "FLT_HDD8_B")
	)
	(segment
		(start 49.402746 -141.8717)
		(end 49.275746 -141.7447)
		(width 0.111252)
		(layer "F.Cu")
		(net "FLT_HDD8_B")
	)
	(segment
		(start 47.726346 -141.7447)
		(end 49.275746 -141.7447)
		(width 0.111252)
		(layer "F.Cu")
		(net "FLT_HDD8_B")
	)
	(via
		(at 49.275746 -141.7447)
		(size 0.7112)
		(drill 0.3556)
		(layers "F.Cu" "B.Cu")
		(net "FLT_HDD8_B")
	)
	(segment
		(start 47.535846 -244.6274)
		(end 47.675546 -244.4877)
		(width 0.111252)
		(layer "F.Cu")
		(net "FLT_HDD7_B")
	)
	(segment
		(start 49.161446 -244.4877)
		(end 49.161446 -245.92915)
		(width 0.111252)
		(layer "F.Cu")
		(net "FLT_HDD7_B")
	)
	(segment
		(start 47.675546 -244.4877)
		(end 49.161446 -244.4877)
		(width 0.111252)
		(layer "F.Cu")
		(net "FLT_HDD7_B")
	)
	(via
		(at 49.161446 -244.4877)
		(size 0.7112)
		(drill 0.3556)
		(layers "F.Cu" "B.Cu")
		(net "FLT_HDD7_B")
	)
	(segment
		(start 53.085746 -348.48165)
		(end 53.085746 -347.1037)
		(width 0.111252)
		(layer "F.Cu")
		(net "FLT_HDD6_B")
	)
	(segment
		(start 51.688746 -347.1037)
		(end 53.085746 -347.1037)
		(width 0.111252)
		(layer "F.Cu")
		(net "FLT_HDD6_B")
	)
	(segment
		(start 51.472846 -347.3196)
		(end 51.688746 -347.1037)
		(width 0.111252)
		(layer "F.Cu")
		(net "FLT_HDD6_B")
	)
	(segment
		(start 52.844446 -348.72295)
		(end 53.085746 -348.48165)
		(width 0.111252)
		(layer "F.Cu")
		(net "FLT_HDD6_B")
	)
	(via
		(at 53.085746 -347.1037)
		(size 0.7112)
		(drill 0.3556)
		(layers "F.Cu" "B.Cu")
		(net "FLT_HDD6_B")
	)
	(segment
		(start 49.288446 -451.77075)
		(end 49.288446 -450.2404)
		(width 0.111252)
		(layer "F.Cu")
		(net "FLT_HDD5_B")
	)
	(segment
		(start 47.700946 -449.9737)
		(end 49.021746 -449.9737)
		(width 0.111252)
		(layer "F.Cu")
		(net "FLT_HDD5_B")
	)
	(segment
		(start 47.281846 -450.3928)
		(end 47.700946 -449.9737)
		(width 0.111252)
		(layer "F.Cu")
		(net "FLT_HDD5_B")
	)
	(segment
		(start 49.288446 -450.2404)
		(end 49.021746 -449.9737)
		(width 0.111252)
		(layer "F.Cu")
		(net "FLT_HDD5_B")
	)
	(via
		(at 49.021746 -449.9737)
		(size 0.7112)
		(drill 0.3556)
		(layers "F.Cu" "B.Cu")
		(net "FLT_HDD5_B")
	)
	(segment
		(start 236.511846 -40.259)
		(end 238.124746 -40.259)
		(width 0.111252)
		(layer "F.Cu")
		(net "FLT_HDD4_B")
	)
	(segment
		(start 238.366046 -40.259)
		(end 238.124746 -40.259)
		(width 0.111252)
		(layer "F.Cu")
		(net "FLT_HDD4_B")
	)
	(segment
		(start 238.645446 -40.5384)
		(end 238.366046 -40.259)
		(width 0.111252)
		(layer "F.Cu")
		(net "FLT_HDD4_B")
	)
	(segment
		(start 238.645446 -41.61155)
		(end 238.645446 -40.5384)
		(width 0.111252)
		(layer "F.Cu")
		(net "FLT_HDD4_B")
	)
	(via
		(at 238.124746 -40.259)
		(size 0.7112)
		(drill 0.3556)
		(layers "F.Cu" "B.Cu")
		(net "FLT_HDD4_B")
	)
	(segment
		(start 232.701846 -141.6812)
		(end 232.892346 -141.4907)
		(width 0.111252)
		(layer "F.Cu")
		(net "FLT_HDD3_B")
	)
	(segment
		(start 234.187746 -142.99565)
		(end 234.187746 -141.4907)
		(width 0.111252)
		(layer "F.Cu")
		(net "FLT_HDD3_B")
	)
	(segment
		(start 232.892346 -141.4907)
		(end 234.187746 -141.4907)
		(width 0.111252)
		(layer "F.Cu")
		(net "FLT_HDD3_B")
	)
	(segment
		(start 234.200446 -143.00835)
		(end 234.187746 -142.99565)
		(width 0.111252)
		(layer "F.Cu")
		(net "FLT_HDD3_B")
	)
	(via
		(at 234.187746 -141.4907)
		(size 0.7112)
		(drill 0.3556)
		(layers "F.Cu" "B.Cu")
		(net "FLT_HDD3_B")
	)
	(segment
		(start 233.095546 -244.1067)
		(end 234.200446 -244.1067)
		(width 0.111252)
		(layer "F.Cu")
		(net "FLT_HDD2_B")
	)
	(segment
		(start 234.200446 -245.67515)
		(end 234.200446 -244.1067)
		(width 0.111252)
		(layer "F.Cu")
		(net "FLT_HDD2_B")
	)
	(segment
		(start 232.828846 -244.3734)
		(end 233.095546 -244.1067)
		(width 0.111252)
		(layer "F.Cu")
		(net "FLT_HDD2_B")
	)
	(via
		(at 234.200446 -244.1067)
		(size 0.7112)
		(drill 0.3556)
		(layers "F.Cu" "B.Cu")
		(net "FLT_HDD2_B")
	)
	(segment
		(start 215.34755 -347.13545)
		(end 217.538046 -347.13545)
		(width 0.111252)
		(layer "F.Cu")
		(net "FLT_HDD1_B")
	)
	(segment
		(start 218.020646 -348.5388)
		(end 217.538046 -348.0562)
		(width 0.111252)
		(layer "F.Cu")
		(net "FLT_HDD1_B")
	)
	(segment
		(start 215.265 -347.218)
		(end 215.34755 -347.13545)
		(width 0.111252)
		(layer "F.Cu")
		(net "FLT_HDD1_B")
	)
	(segment
		(start 217.538046 -348.0562)
		(end 217.538046 -347.13545)
		(width 0.111252)
		(layer "F.Cu")
		(net "FLT_HDD1_B")
	)
	(via
		(at 215.265 -347.218)
		(size 0.7112)
		(drill 0.3556)
		(layers "F.Cu" "B.Cu")
		(net "FLT_HDD1_B")
	)
	(segment
		(start 233.120946 -449.5927)
		(end 234.060746 -449.5927)
		(width 0.111252)
		(layer "F.Cu")
		(net "FLT_HDD0_B")
	)
	(segment
		(start 234.060746 -451.37705)
		(end 234.060746 -449.5927)
		(width 0.111252)
		(layer "F.Cu")
		(net "FLT_HDD0_B")
	)
	(segment
		(start 232.701846 -450.0118)
		(end 233.120946 -449.5927)
		(width 0.111252)
		(layer "F.Cu")
		(net "FLT_HDD0_B")
	)
	(segment
		(start 234.073446 -451.38975)
		(end 234.060746 -451.37705)
		(width 0.111252)
		(layer "F.Cu")
		(net "FLT_HDD0_B")
	)
	(via
		(at 234.060746 -449.5927)
		(size 0.7112)
		(drill 0.3556)
		(layers "F.Cu" "B.Cu")
		(net "FLT_HDD0_B")
	)
	(segment
		(start 24.17191 -15.529814)
		(end 21.75002 -15.529814)
		(width 0.111252)
		(layer "F.Cu")
		(net "ACT_HDD14")
	)
	(segment
		(start 26.5938 -8.191246)
		(end 26.5938 -13.107924)
		(width 0.111252)
		(layer "F.Cu")
		(net "ACT_HDD14")
	)
	(segment
		(start 26.161746 -7.3787)
		(end 26.32456 -7.541514)
		(width 0.111252)
		(layer "F.Cu")
		(net "ACT_HDD14")
	)
	(arc
		(start 26.5938 -13.107924)
		(mid 25.884445 -14.820459)
		(end 24.17191 -15.529814)
		(width 0.111252)
		(layer "F.Cu")
		(net "ACT_HDD14")
	)
	(arc
		(start 26.32456 -7.541514)
		(mid 26.523827 -7.839599)
		(end 26.5938 -8.191246)
		(width 0.111252)
		(layer "F.Cu")
		(net "ACT_HDD14")
	)
	(segment
		(start 25.171908 -118.529862)
		(end 21.75002 -118.529862)
		(width 0.111252)
		(layer "F.Cu")
		(net "ACT_HDD13")
	)
	(arc
		(start 25.653746 -119.0117)
		(mid 25.512619 -118.670989)
		(end 25.171908 -118.529862)
		(width 0.111252)
		(layer "F.Cu")
		(net "ACT_HDD13")
	)
	(segment
		(start 27.847036 -221.53499)
		(end 21.7551 -221.53499)
		(width 0.111252)
		(layer "F.Cu")
		(net "ACT_HDD12")
	)
	(segment
		(start 27.939746 -221.6277)
		(end 27.847036 -221.53499)
		(width 0.111252)
		(layer "F.Cu")
		(net "ACT_HDD12")
	)
	(segment
		(start 21.7551 -221.53499)
		(end 21.75002 -221.52991)
		(width 0.111252)
		(layer "F.Cu")
		(net "ACT_HDD12")
	)
	(segment
		(start 32.639 -322.478654)
		(end 32.612838 -322.478654)
		(width 0.111252)
		(layer "F.Cu")
		(net "ACT_HDD11")
	)
	(segment
		(start 32.639254 -322.4784)
		(end 32.639 -322.478654)
		(width 0.111252)
		(layer "F.Cu")
		(net "ACT_HDD11")
	)
	(segment
		(start 23.203408 -324.535038)
		(end 21.7551 -324.535038)
		(width 0.111252)
		(layer "F.Cu")
		(net "ACT_HDD11")
	)
	(segment
		(start 32.612838 -322.478654)
		(end 32.359092 -322.7324)
		(width 0.111252)
		(layer "F.Cu")
		(net "ACT_HDD11")
	)
	(segment
		(start 25.006046 -322.7324)
		(end 23.203408 -324.535038)
		(width 0.111252)
		(layer "F.Cu")
		(net "ACT_HDD11")
	)
	(segment
		(start 21.7551 -324.535038)
		(end 21.75002 -324.529958)
		(width 0.111252)
		(layer "F.Cu")
		(net "ACT_HDD11")
	)
	(segment
		(start 35.940746 -321.8307)
		(end 35.293046 -322.4784)
		(width 0.111252)
		(layer "F.Cu")
		(net "ACT_HDD11")
	)
	(segment
		(start 35.293046 -322.4784)
		(end 32.639254 -322.4784)
		(width 0.111252)
		(layer "F.Cu")
		(net "ACT_HDD11")
	)
	(segment
		(start 32.359092 -322.7324)
		(end 25.006046 -322.7324)
		(width 0.111252)
		(layer "F.Cu")
		(net "ACT_HDD11")
	)
	(segment
		(start 22.123146 -419.4175)
		(end 19.7866 -421.754046)
		(width 0.111252)
		(layer "F.Cu")
		(net "ACT_HDD10")
	)
	(segment
		(start 21.74494 -427.535086)
		(end 21.75002 -427.530006)
		(width 0.111252)
		(layer "F.Cu")
		(net "ACT_HDD10")
	)
	(segment
		(start 22.123146 -418.4142)
		(end 22.123146 -419.4175)
		(width 0.111252)
		(layer "F.Cu")
		(net "ACT_HDD10")
	)
	(segment
		(start 19.7866 -426.847)
		(end 20.474686 -427.535086)
		(width 0.111252)
		(layer "F.Cu")
		(net "ACT_HDD10")
	)
	(segment
		(start 19.7866 -421.754046)
		(end 19.7866 -426.847)
		(width 0.111252)
		(layer "F.Cu")
		(net "ACT_HDD10")
	)
	(segment
		(start 20.474686 -427.535086)
		(end 21.74494 -427.535086)
		(width 0.111252)
		(layer "F.Cu")
		(net "ACT_HDD10")
	)
	(segment
		(start 24.637746 -415.8996)
		(end 22.123146 -418.4142)
		(width 0.111252)
		(layer "F.Cu")
		(net "ACT_HDD10")
	)
	(segment
		(start 24.637746 -414.5407)
		(end 24.637746 -415.8996)
		(width 0.111252)
		(layer "F.Cu")
		(net "ACT_HDD10")
	)
	(segment
		(start 69.9897 -80.9117)
		(end 65.251076 -80.9117)
		(width 0.111252)
		(layer "F.Cu")
		(net "ACT_HDD9")
	)
	(segment
		(start 70.231 -81.153)
		(end 69.9897 -80.9117)
		(width 0.111252)
		(layer "F.Cu")
		(net "ACT_HDD9")
	)
	(segment
		(start 47.46498 -81.13649)
		(end 45.539152 -79.210662)
		(width 0.111252)
		(layer "F.Cu")
		(net "ACT_HDD9")
	)
	(segment
		(start 64.28232 -81.880456)
		(end 49.261014 -81.880456)
		(width 0.111252)
		(layer "F.Cu")
		(net "ACT_HDD9")
	)
	(segment
		(start 65.251076 -80.9117)
		(end 64.28232 -81.880456)
		(width 0.111252)
		(layer "F.Cu")
		(net "ACT_HDD9")
	)
	(segment
		(start 43.743118 -78.466696)
		(end 38.253416 -78.466696)
		(width 0.111252)
		(layer "F.Cu")
		(net "ACT_HDD9")
	)
	(segment
		(start 38.253416 -78.466696)
		(end 38.250114 -78.469998)
		(width 0.111252)
		(layer "F.Cu")
		(net "ACT_HDD9")
	)
	(arc
		(start 49.261014 -81.880456)
		(mid 48.288998 -81.68711)
		(end 47.46498 -81.13649)
		(width 0.111252)
		(layer "F.Cu")
		(net "ACT_HDD9")
	)
	(arc
		(start 45.539152 -79.210662)
		(mid 44.715125 -78.660064)
		(end 43.743118 -78.466696)
		(width 0.111252)
		(layer "F.Cu")
		(net "ACT_HDD9")
	)
	(segment
		(start 56.6547 -185.5597)
		(end 56.5277 -185.4327)
		(width 0.111252)
		(layer "F.Cu")
		(net "ACT_HDD8")
	)
	(segment
		(start 58.406792 -185.5597)
		(end 56.6547 -185.5597)
		(width 0.111252)
		(layer "F.Cu")
		(net "ACT_HDD8")
	)
	(segment
		(start 39.7764 -181.466744)
		(end 39.773098 -181.470046)
		(width 0.111252)
		(layer "F.Cu")
		(net "ACT_HDD8")
	)
	(segment
		(start 58.788046 -185.1914)
		(end 58.775092 -185.1914)
		(width 0.111252)
		(layer "F.Cu")
		(net "ACT_HDD8")
	)
	(segment
		(start 73.405746 -183.7817)
		(end 72.910446 -184.277)
		(width 0.111252)
		(layer "F.Cu")
		(net "ACT_HDD8")
	)
	(segment
		(start 64.9097 -184.277)
		(end 63.9064 -183.2737)
		(width 0.111252)
		(layer "F.Cu")
		(net "ACT_HDD8")
	)
	(segment
		(start 39.773098 -181.470046)
		(end 38.250114 -181.470046)
		(width 0.111252)
		(layer "F.Cu")
		(net "ACT_HDD8")
	)
	(segment
		(start 56.5277 -185.4327)
		(end 50.4317 -185.4327)
		(width 0.111252)
		(layer "F.Cu")
		(net "ACT_HDD8")
	)
	(segment
		(start 72.910446 -184.277)
		(end 64.9097 -184.277)
		(width 0.111252)
		(layer "F.Cu")
		(net "ACT_HDD8")
	)
	(segment
		(start 63.9064 -183.2737)
		(end 60.705746 -183.2737)
		(width 0.111252)
		(layer "F.Cu")
		(net "ACT_HDD8")
	)
	(segment
		(start 58.775092 -185.1914)
		(end 58.406792 -185.5597)
		(width 0.111252)
		(layer "F.Cu")
		(net "ACT_HDD8")
	)
	(segment
		(start 46.465744 -181.466744)
		(end 39.7764 -181.466744)
		(width 0.111252)
		(layer "F.Cu")
		(net "ACT_HDD8")
	)
	(segment
		(start 60.705746 -183.2737)
		(end 58.788046 -185.1914)
		(width 0.111252)
		(layer "F.Cu")
		(net "ACT_HDD8")
	)
	(segment
		(start 50.4317 -185.4327)
		(end 46.465744 -181.466744)
		(width 0.111252)
		(layer "F.Cu")
		(net "ACT_HDD8")
	)
	(segment
		(start 38.250114 -284.470094)
		(end 38.246812 -284.466792)
		(width 0.111252)
		(layer "F.Cu")
		(net "ACT_HDD7")
	)
	(segment
		(start 32.371792 -284.352746)
		(end 32.257746 -284.2387)
		(width 0.111252)
		(layer "F.Cu")
		(net "ACT_HDD7")
	)
	(segment
		(start 38.246812 -284.466792)
		(end 32.647128 -284.466792)
		(width 0.111252)
		(layer "F.Cu")
		(net "ACT_HDD7")
	)
	(arc
		(start 32.647128 -284.466792)
		(mid 32.498118 -284.437152)
		(end 32.371792 -284.352746)
		(width 0.111252)
		(layer "F.Cu")
		(net "ACT_HDD7")
	)
	(segment
		(start 30.248606 -387.46684)
		(end 30.225746 -387.4897)
		(width 0.111252)
		(layer "F.Cu")
		(net "ACT_HDD6")
	)
	(segment
		(start 36.299902 -387.470142)
		(end 36.2966 -387.46684)
		(width 0.111252)
		(layer "F.Cu")
		(net "ACT_HDD6")
	)
	(segment
		(start 38.250114 -387.470142)
		(end 36.299902 -387.470142)
		(width 0.111252)
		(layer "F.Cu")
		(net "ACT_HDD6")
	)
	(segment
		(start 36.2966 -387.46684)
		(end 30.248606 -387.46684)
		(width 0.111252)
		(layer "F.Cu")
		(net "ACT_HDD6")
	)
	(segment
		(start 41.935146 -488.6833)
		(end 53.7972 -488.6833)
		(width 0.111252)
		(layer "F.Cu")
		(net "ACT_HDD5")
	)
	(segment
		(start 53.908706 -488.571794)
		(end 53.921406 -488.571794)
		(width 0.111252)
		(layer "F.Cu")
		(net "ACT_HDD5")
	)
	(segment
		(start 38.250114 -490.47019)
		(end 40.148256 -490.47019)
		(width 0.111252)
		(layer "F.Cu")
		(net "ACT_HDD5")
	)
	(segment
		(start 57.763918 -488.6833)
		(end 59.2074 -490.126782)
		(width 0.111252)
		(layer "F.Cu")
		(net "ACT_HDD5")
	)
	(segment
		(start 59.2074 -490.126782)
		(end 59.2074 -490.1692)
		(width 0.111252)
		(layer "F.Cu")
		(net "ACT_HDD5")
	)
	(segment
		(start 54.017926 -488.475274)
		(end 55.994046 -488.475274)
		(width 0.111252)
		(layer "F.Cu")
		(net "ACT_HDD5")
	)
	(segment
		(start 55.994046 -488.475274)
		(end 56.202072 -488.6833)
		(width 0.111252)
		(layer "F.Cu")
		(net "ACT_HDD5")
	)
	(segment
		(start 40.148256 -490.47019)
		(end 41.935146 -488.6833)
		(width 0.111252)
		(layer "F.Cu")
		(net "ACT_HDD5")
	)
	(segment
		(start 56.202072 -488.6833)
		(end 57.763918 -488.6833)
		(width 0.111252)
		(layer "F.Cu")
		(net "ACT_HDD5")
	)
	(segment
		(start 53.921406 -488.571794)
		(end 54.017926 -488.475274)
		(width 0.111252)
		(layer "F.Cu")
		(net "ACT_HDD5")
	)
	(segment
		(start 53.7972 -488.6833)
		(end 53.908706 -488.571794)
		(width 0.111252)
		(layer "F.Cu")
		(net "ACT_HDD5")
	)
	(segment
		(start 215.259412 -78.466696)
		(end 223.246696 -78.466696)
		(width 0.111252)
		(layer "F.Cu")
		(net "ACT_HDD4")
	)
	(segment
		(start 223.246696 -78.466696)
		(end 223.249998 -78.469998)
		(width 0.111252)
		(layer "F.Cu")
		(net "ACT_HDD4")
	)
	(segment
		(start 214.2998 -79.2988)
		(end 215.041734 -78.556866)
		(width 0.111252)
		(layer "F.Cu")
		(net "ACT_HDD4")
	)
	(arc
		(start 215.041734 -78.556866)
		(mid 215.141606 -78.490134)
		(end 215.259412 -78.466696)
		(width 0.111252)
		(layer "F.Cu")
		(net "ACT_HDD4")
	)
	(segment
		(start 218.86291 -180.1241)
		(end 214.7189 -180.1241)
		(width 0.111252)
		(layer "F.Cu")
		(net "ACT_HDD3")
	)
	(segment
		(start 220.314012 -181.470046)
		(end 219.042488 -180.198522)
		(width 0.111252)
		(layer "F.Cu")
		(net "ACT_HDD3")
	)
	(segment
		(start 214.7189 -180.1241)
		(end 213.741 -181.102)
		(width 0.111252)
		(layer "F.Cu")
		(net "ACT_HDD3")
	)
	(segment
		(start 223.249998 -181.470046)
		(end 220.314012 -181.470046)
		(width 0.111252)
		(layer "F.Cu")
		(net "ACT_HDD3")
	)
	(arc
		(start 219.042488 -180.198522)
		(mid 218.960111 -180.143416)
		(end 218.86291 -180.1241)
		(width 0.111252)
		(layer "F.Cu")
		(net "ACT_HDD3")
	)
	(segment
		(start 208.602326 -285.183326)
		(end 211.847938 -285.183326)
		(width 0.111252)
		(layer "F.Cu")
		(net "ACT_HDD2")
	)
	(segment
		(start 211.847938 -285.183326)
		(end 211.85251 -285.178754)
		(width 0.111252)
		(layer "F.Cu")
		(net "ACT_HDD2")
	)
	(segment
		(start 205.226158 -276.7457)
		(end 206.870046 -278.389588)
		(width 0.111252)
		(layer "F.Cu")
		(net "ACT_HDD2")
	)
	(segment
		(start 206.870046 -283.451046)
		(end 208.602326 -285.183326)
		(width 0.111252)
		(layer "F.Cu")
		(net "ACT_HDD2")
	)
	(segment
		(start 205.104746 -276.7457)
		(end 205.226158 -276.7457)
		(width 0.111252)
		(layer "F.Cu")
		(net "ACT_HDD2")
	)
	(segment
		(start 221.259146 -285.0134)
		(end 221.807786 -284.465014)
		(width 0.111252)
		(layer "F.Cu")
		(net "ACT_HDD2")
	)
	(segment
		(start 212.02904 -285.0134)
		(end 221.259146 -285.0134)
		(width 0.111252)
		(layer "F.Cu")
		(net "ACT_HDD2")
	)
	(segment
		(start 206.870046 -278.389588)
		(end 206.870046 -283.451046)
		(width 0.111252)
		(layer "F.Cu")
		(net "ACT_HDD2")
	)
	(segment
		(start 223.244918 -284.465014)
		(end 223.249998 -284.470094)
		(width 0.111252)
		(layer "F.Cu")
		(net "ACT_HDD2")
	)
	(segment
		(start 211.863686 -285.178754)
		(end 212.02904 -285.0134)
		(width 0.111252)
		(layer "F.Cu")
		(net "ACT_HDD2")
	)
	(segment
		(start 221.807786 -284.465014)
		(end 223.244918 -284.465014)
		(width 0.111252)
		(layer "F.Cu")
		(net "ACT_HDD2")
	)
	(segment
		(start 211.85251 -285.178754)
		(end 211.863686 -285.178754)
		(width 0.111252)
		(layer "F.Cu")
		(net "ACT_HDD2")
	)
	(segment
		(start 219.298774 -387.768592)
		(end 219.602304 -387.465062)
		(width 0.111252)
		(layer "F.Cu")
		(net "ACT_HDD1")
	)
	(segment
		(start 205.2955 -379.9967)
		(end 206.785718 -381.486918)
		(width 0.111252)
		(layer "F.Cu")
		(net "ACT_HDD1")
	)
	(segment
		(start 217.911934 -387.768592)
		(end 219.298774 -387.768592)
		(width 0.111252)
		(layer "F.Cu")
		(net "ACT_HDD1")
	)
	(segment
		(start 223.244918 -387.465062)
		(end 223.249998 -387.470142)
		(width 0.111252)
		(layer "F.Cu")
		(net "ACT_HDD1")
	)
	(segment
		(start 219.602304 -387.465062)
		(end 223.244918 -387.465062)
		(width 0.111252)
		(layer "F.Cu")
		(net "ACT_HDD1")
	)
	(segment
		(start 217.581226 -388.0993)
		(end 217.911934 -387.768592)
		(width 0.111252)
		(layer "F.Cu")
		(net "ACT_HDD1")
	)
	(segment
		(start 206.785718 -381.486918)
		(end 206.785718 -386.503672)
		(width 0.111252)
		(layer "F.Cu")
		(net "ACT_HDD1")
	)
	(segment
		(start 206.785718 -386.503672)
		(end 208.381346 -388.0993)
		(width 0.111252)
		(layer "F.Cu")
		(net "ACT_HDD1")
	)
	(segment
		(start 208.381346 -388.0993)
		(end 217.581226 -388.0993)
		(width 0.111252)
		(layer "F.Cu")
		(net "ACT_HDD1")
	)
	(segment
		(start 204.088746 -379.9967)
		(end 205.2955 -379.9967)
		(width 0.111252)
		(layer "F.Cu")
		(net "ACT_HDD1")
	)
	(segment
		(start 206.714344 -484.45039)
		(end 206.714344 -489.429298)
		(width 0.111252)
		(layer "F.Cu")
		(net "ACT_HDD0")
	)
	(segment
		(start 208.406746 -491.1217)
		(end 219.963746 -491.1217)
		(width 0.111252)
		(layer "F.Cu")
		(net "ACT_HDD0")
	)
	(segment
		(start 204.850746 -483.5017)
		(end 205.765654 -483.5017)
		(width 0.111252)
		(layer "F.Cu")
		(net "ACT_HDD0")
	)
	(segment
		(start 223.244918 -490.46511)
		(end 223.249998 -490.47019)
		(width 0.111252)
		(layer "F.Cu")
		(net "ACT_HDD0")
	)
	(segment
		(start 220.620336 -490.46511)
		(end 223.244918 -490.46511)
		(width 0.111252)
		(layer "F.Cu")
		(net "ACT_HDD0")
	)
	(segment
		(start 206.714344 -489.429298)
		(end 208.406746 -491.1217)
		(width 0.111252)
		(layer "F.Cu")
		(net "ACT_HDD0")
	)
	(segment
		(start 219.963746 -491.1217)
		(end 220.620336 -490.46511)
		(width 0.111252)
		(layer "F.Cu")
		(net "ACT_HDD0")
	)
	(segment
		(start 205.765654 -483.5017)
		(end 206.714344 -484.45039)
		(width 0.111252)
		(layer "F.Cu")
		(net "ACT_HDD0")
	)
	(segment
		(start 235.140246 -43.8277)
		(end 235.198412 -43.769534)
		(width 0.111252)
		(layer "F.Cu")
		(net "DRIVE_ACT_4")
	)
	(segment
		(start 235.198412 -42.779696)
		(end 235.382308 -42.5958)
		(width 0.111252)
		(layer "F.Cu")
		(net "DRIVE_ACT_4")
	)
	(segment
		(start 235.382308 -42.5958)
		(end 236.740446 -42.5958)
		(width 0.111252)
		(layer "F.Cu")
		(net "DRIVE_ACT_4")
	)
	(segment
		(start 235.198412 -43.769534)
		(end 235.198412 -42.779696)
		(width 0.111252)
		(layer "F.Cu")
		(net "DRIVE_ACT_4")
	)
	(segment
		(start 239.991646 -42.5958)
		(end 236.740446 -42.5958)
		(width 0.111252)
		(layer "F.Cu")
		(net "DRIVE_ACT_4")
	)
	(segment
		(start 240.283746 -42.3037)
		(end 239.991646 -42.5958)
		(width 0.111252)
		(layer "F.Cu")
		(net "DRIVE_ACT_4")
	)
	(via
		(at 240.283746 -42.3037)
		(size 0.7112)
		(drill 0.3556)
		(layers "F.Cu" "B.Cu")
		(net "DRIVE_ACT_4")
	)
	(via
		(at 219.836746 -73.1647)
		(size 0.5588)
		(drill 0.3048)
		(layers "F.Cu" "B.Cu")
		(net "5V_PRE_4")
	)
	(via
		(at 220.827346 -73.183496)
		(size 0.7112)
		(drill 0.3556)
		(layers "F.Cu" "B.Cu")
		(net "5V_PRE_4")
	)
	(segment
		(start 219.836746 -73.1647)
		(end 220.80855 -73.1647)
		(width 0.508)
		(layer "B.Cu")
		(net "5V_PRE_4")
	)
	(segment
		(start 220.80855 -73.1647)
		(end 220.827346 -73.183496)
		(width 0.508)
		(layer "B.Cu")
		(net "5V_PRE_4")
	)
	(segment
		(start 215.703912 -70.312788)
		(end 215.703912 -71.354696)
		(width 0.111252)
		(layer "F.Cu")
		(net "HDD_PRSNT_NET4")
	)
	(segment
		(start 215.7095 -70.3072)
		(end 215.703912 -70.312788)
		(width 0.111252)
		(layer "F.Cu")
		(net "HDD_PRSNT_NET4")
	)
	(segment
		(start 216.910412 -71.354696)
		(end 217.989912 -71.354696)
		(width 0.111252)
		(layer "F.Cu")
		(net "HDD_PRSNT_NET4")
	)
	(segment
		(start 223.249998 -70.849998)
		(end 219.503498 -70.849998)
		(width 0.111252)
		(layer "F.Cu")
		(net "HDD_PRSNT_NET4")
	)
	(segment
		(start 219.503498 -70.849998)
		(end 218.9353 -71.418196)
		(width 0.111252)
		(layer "F.Cu")
		(net "HDD_PRSNT_NET4")
	)
	(segment
		(start 215.703912 -71.354696)
		(end 216.910412 -71.354696)
		(width 0.111252)
		(layer "F.Cu")
		(net "HDD_PRSNT_NET4")
	)
	(segment
		(start 215.6968 -69.533516)
		(end 215.6968 -70.2056)
		(width 0.111252)
		(layer "F.Cu")
		(net "HDD_PRSNT_NET4")
	)
	(segment
		(start 218.9353 -71.418196)
		(end 218.053412 -71.418196)
		(width 0.111252)
		(layer "F.Cu")
		(net "HDD_PRSNT_NET4")
	)
	(segment
		(start 215.284558 -69.121274)
		(end 215.6968 -69.533516)
		(width 0.111252)
		(layer "F.Cu")
		(net "HDD_PRSNT_NET4")
	)
	(segment
		(start 217.989912 -71.354696)
		(end 218.053412 -71.418196)
		(width 0.111252)
		(layer "F.Cu")
		(net "HDD_PRSNT_NET4")
	)
	(segment
		(start 215.6968 -70.2056)
		(end 215.7095 -70.3072)
		(width 0.111252)
		(layer "F.Cu")
		(net "HDD_PRSNT_NET4")
	)
	(via
		(at 215.284558 -69.121274)
		(size 0.7112)
		(drill 0.3556)
		(layers "F.Cu" "B.Cu")
		(net "HDD_PRSNT_NET4")
	)
	(segment
		(start 46.450504 -20.936712)
		(end 47.065946 -20.32127)
		(width 0.508)
		(layer "F.Cu")
		(net "P5VB_SNB")
	)
	(segment
		(start 47.065946 -20.32127)
		(end 47.065946 -19.921474)
		(width 0.508)
		(layer "F.Cu")
		(net "P5VB_SNB")
	)
	(segment
		(start 47.504096 -19.483324)
		(end 47.504096 -19.36369)
		(width 0.508)
		(layer "F.Cu")
		(net "P5VB_SNB")
	)
	(segment
		(start 47.065946 -19.921474)
		(end 47.504096 -19.483324)
		(width 0.508)
		(layer "F.Cu")
		(net "P5VB_SNB")
	)
	(segment
		(start 46.354746 -18.9992)
		(end 47.139606 -18.9992)
		(width 0.508)
		(layer "F.Cu")
		(net "P5VB_SNB")
	)
	(segment
		(start 47.139606 -18.9992)
		(end 47.504096 -19.36369)
		(width 0.508)
		(layer "F.Cu")
		(net "P5VB_SNB")
	)
	(via
		(at 47.504096 -19.36369)
		(size 0.7112)
		(drill 0.3556)
		(layers "F.Cu" "B.Cu")
		(net "P5VB_SNB")
	)
	(via
		(at 28.2702 -15.7226)
		(size 0.7112)
		(drill 0.3556)
		(layers "F.Cu" "B.Cu")
		(net "P5VB_LL")
	)
	(via
		(at 36.067746 -16.6497)
		(size 0.7112)
		(drill 0.4064)
		(layers "F.Cu" "B.Cu")
		(net "P5VB_LL")
	)
	(via
		(at 42.544746 -11.0617)
		(size 0.7112)
		(drill 0.4064)
		(layers "F.Cu" "B.Cu")
		(net "P5VB_LL")
	)
	(via
		(at 45.339 -16.1798)
		(size 0.7112)
		(drill 0.3556)
		(layers "F.Cu" "B.Cu")
		(net "P5VB_LL")
	)
	(via
		(at 32.384746 -16.5227)
		(size 0.7112)
		(drill 0.4064)
		(layers "F.Cu" "B.Cu")
		(net "P5VB_LL")
	)
	(via
		(at 39.750746 -16.7767)
		(size 0.7112)
		(drill 0.4064)
		(layers "F.Cu" "B.Cu")
		(net "P5VB_LL")
	)
	(via
		(at 46.608746 -11.5697)
		(size 0.7112)
		(drill 0.4064)
		(layers "F.Cu" "B.Cu")
		(net "P5VB_LL")
	)
	(via
		(at 32.7914 -14.1986)
		(size 0.7112)
		(drill 0.4064)
		(layers "F.Cu" "B.Cu")
		(net "P5VB_LL")
	)
	(via
		(at 29.5656 -14.224)
		(size 0.7112)
		(drill 0.4064)
		(layers "F.Cu" "B.Cu")
		(net "P5VB_LL")
	)
	(via
		(at 29.1592 -17.399)
		(size 0.7112)
		(drill 0.4064)
		(layers "F.Cu" "B.Cu")
		(net "P5VB_LL")
	)
	(via
		(at 48.894746 -14.6177)
		(size 0.7112)
		(drill 0.4064)
		(layers "F.Cu" "B.Cu")
		(net "P5VB_LL")
	)
	(via
		(at 39.0398 -13.3858)
		(size 0.7112)
		(drill 0.3556)
		(layers "F.Cu" "B.Cu")
		(net "P5VB_LL")
	)
	(segment
		(start 45.719746 -24.1427)
		(end 45.674534 -24.097488)
		(width 0.508)
		(layer "F.Cu")
		(net "P5VB_VBST_NET")
	)
	(segment
		(start 45.674534 -24.097488)
		(end 44.805346 -24.097488)
		(width 0.508)
		(layer "F.Cu")
		(net "P5VB_VBST_NET")
	)
	(segment
		(start 45.465746 -18.9992)
		(end 45.465746 -20.0787)
		(width 0.508)
		(layer "F.Cu")
		(net "P5VB_VBST_NET")
	)
	(via
		(at 45.465746 -20.0787)
		(size 0.5588)
		(drill 0.3048)
		(layers "F.Cu" "B.Cu")
		(net "P5VB_VBST_NET")
	)
	(via
		(at 44.805346 -24.097488)
		(size 0.5588)
		(drill 0.3048)
		(layers "F.Cu" "B.Cu")
		(net "P5VB_VBST_NET")
	)
	(via
		(at 45.465746 -22.4917)
		(size 0.7112)
		(drill 0.3556)
		(layers "F.Cu" "B.Cu")
		(net "P5VB_VBST_NET")
	)
	(segment
		(start 44.805346 -24.097488)
		(end 45.211746 -24.097488)
		(width 0.508)
		(layer "B.Cu")
		(net "P5VB_VBST_NET")
	)
	(segment
		(start 45.465746 -20.0787)
		(end 45.465746 -22.4917)
		(width 0.508)
		(layer "B.Cu")
		(net "P5VB_VBST_NET")
	)
	(segment
		(start 45.211746 -24.097488)
		(end 45.465746 -23.843488)
		(width 0.508)
		(layer "B.Cu")
		(net "P5VB_VBST_NET")
	)
	(segment
		(start 45.465746 -23.843488)
		(end 45.465746 -22.4917)
		(width 0.508)
		(layer "B.Cu")
		(net "P5VB_VBST_NET")
	)
	(segment
		(start 51.062382 -19.42211)
		(end 49.424336 -19.42211)
		(width 0.254)
		(layer "F.Cu")
		(net "P5VB_VBST")
	)
	(segment
		(start 47.243746 -24.1427)
		(end 48.005746 -23.3807)
		(width 0.254)
		(layer "F.Cu")
		(net "P5VB_VBST")
	)
	(segment
		(start 48.386746 -22.1107)
		(end 48.005746 -22.4917)
		(width 0.254)
		(layer "F.Cu")
		(net "P5VB_VBST")
	)
	(segment
		(start 48.386746 -20.4597)
		(end 48.386746 -22.1107)
		(width 0.254)
		(layer "F.Cu")
		(net "P5VB_VBST")
	)
	(segment
		(start 48.005746 -23.3807)
		(end 48.005746 -22.4917)
		(width 0.254)
		(layer "F.Cu")
		(net "P5VB_VBST")
	)
	(segment
		(start 49.424336 -19.42211)
		(end 48.386746 -20.4597)
		(width 0.254)
		(layer "F.Cu")
		(net "P5VB_VBST")
	)
	(via
		(at 48.005746 -22.4917)
		(size 0.7112)
		(drill 0.3556)
		(layers "F.Cu" "B.Cu")
		(net "P5VB_VBST")
	)
	(segment
		(start 60.299346 -25.9207)
		(end 60.299346 -27.0637)
		(width 0.508)
		(layer "F.Cu")
		(net "P5VB_AGND")
	)
	(segment
		(start 53.212746 -27.4447)
		(end 52.831746 -27.8257)
		(width 0.508)
		(layer "F.Cu")
		(net "P5VB_AGND")
	)
	(segment
		(start 60.045346 -25.6667)
		(end 60.299346 -25.9207)
		(width 0.508)
		(layer "F.Cu")
		(net "P5VB_AGND")
	)
	(segment
		(start 59.372246 -25.6667)
		(end 60.045346 -25.6667)
		(width 0.508)
		(layer "F.Cu")
		(net "P5VB_AGND")
	)
	(segment
		(start 59.372246 -24.6507)
		(end 59.372246 -25.6667)
		(width 0.508)
		(layer "F.Cu")
		(net "P5VB_AGND")
	)
	(segment
		(start 60.299346 -27.0637)
		(end 60.426346 -27.1907)
		(width 0.508)
		(layer "F.Cu")
		(net "P5VB_AGND")
	)
	(segment
		(start 45.573188 -21.989288)
		(end 44.576746 -21.989288)
		(width 0.508)
		(layer "F.Cu")
		(net "P5VB_AGND")
	)
	(segment
		(start 53.212746 -25.7302)
		(end 53.212746 -27.4447)
		(width 0.508)
		(layer "F.Cu")
		(net "P5VB_AGND")
	)
	(via
		(at 52.831746 -27.8257)
		(size 0.5588)
		(drill 0.3048)
		(layers "F.Cu" "B.Cu")
		(net "P5VB_AGND")
	)
	(via
		(at 49.402746 -27.7749)
		(size 0.7112)
		(drill 0.3556)
		(layers "F.Cu" "B.Cu")
		(net "P5VB_AGND")
	)
	(via
		(at 60.426346 -27.1907)
		(size 0.5588)
		(drill 0.3048)
		(layers "F.Cu" "B.Cu")
		(net "P5VB_AGND")
	)
	(via
		(at 44.576746 -21.989288)
		(size 0.5588)
		(drill 0.3048)
		(layers "F.Cu" "B.Cu")
		(net "P5VB_AGND")
	)
	(segment
		(start 47.319946 -27.7749)
		(end 49.402746 -27.7749)
		(width 0.508)
		(layer "B.Cu")
		(net "P5VB_AGND")
	)
	(segment
		(start 60.426346 -27.1907)
		(end 60.045346 -26.8097)
		(width 0.508)
		(layer "B.Cu")
		(net "P5VB_AGND")
	)
	(segment
		(start 53.072538 -27.8257)
		(end 52.831746 -27.8257)
		(width 0.508)
		(layer "B.Cu")
		(net "P5VB_AGND")
	)
	(segment
		(start 56.299354 -26.8097)
		(end 54.902354 -28.2067)
		(width 0.508)
		(layer "B.Cu")
		(net "P5VB_AGND")
	)
	(segment
		(start 52.831746 -27.8257)
		(end 52.780946 -27.7749)
		(width 0.508)
		(layer "B.Cu")
		(net "P5VB_AGND")
	)
	(segment
		(start 43.992546 -22.573488)
		(end 43.992546 -24.434546)
		(width 0.508)
		(layer "B.Cu")
		(net "P5VB_AGND")
	)
	(segment
		(start 60.045346 -26.8097)
		(end 56.299354 -26.8097)
		(width 0.508)
		(layer "B.Cu")
		(net "P5VB_AGND")
	)
	(segment
		(start 54.902354 -28.2067)
		(end 53.453538 -28.2067)
		(width 0.508)
		(layer "B.Cu")
		(net "P5VB_AGND")
	)
	(segment
		(start 43.992546 -24.434546)
		(end 44.449746 -24.891746)
		(width 0.508)
		(layer "B.Cu")
		(net "P5VB_AGND")
	)
	(segment
		(start 44.576746 -21.989288)
		(end 43.992546 -22.573488)
		(width 0.508)
		(layer "B.Cu")
		(net "P5VB_AGND")
	)
	(segment
		(start 44.449746 -24.9047)
		(end 47.319946 -27.7749)
		(width 0.508)
		(layer "B.Cu")
		(net "P5VB_AGND")
	)
	(segment
		(start 44.449746 -24.891746)
		(end 44.449746 -24.9047)
		(width 0.508)
		(layer "B.Cu")
		(net "P5VB_AGND")
	)
	(segment
		(start 53.453538 -28.2067)
		(end 53.072538 -27.8257)
		(width 0.508)
		(layer "B.Cu")
		(net "P5VB_AGND")
	)
	(segment
		(start 52.780946 -27.7749)
		(end 49.402746 -27.7749)
		(width 0.508)
		(layer "B.Cu")
		(net "P5VB_AGND")
	)
	(segment
		(start 58.483246 -26.6827)
		(end 58.483246 -25.6667)
		(width 0.254)
		(layer "F.Cu")
		(net "P5VB_RF")
	)
	(segment
		(start 58.229246 -25.4127)
		(end 57.276746 -25.4127)
		(width 0.254)
		(layer "F.Cu")
		(net "P5VB_RF")
	)
	(segment
		(start 55.961026 -24.60498)
		(end 56.768746 -25.4127)
		(width 0.254)
		(layer "F.Cu")
		(net "P5VB_RF")
	)
	(segment
		(start 56.768746 -25.4127)
		(end 57.276746 -25.4127)
		(width 0.254)
		(layer "F.Cu")
		(net "P5VB_RF")
	)
	(segment
		(start 55.961026 -20.922234)
		(end 55.961026 -24.60498)
		(width 0.254)
		(layer "F.Cu")
		(net "P5VB_RF")
	)
	(segment
		(start 58.483246 -25.6667)
		(end 58.229246 -25.4127)
		(width 0.254)
		(layer "F.Cu")
		(net "P5VB_RF")
	)
	(via
		(at 57.276746 -25.4127)
		(size 0.7112)
		(drill 0.3556)
		(layers "F.Cu" "B.Cu")
		(net "P5VB_RF")
	)
	(segment
		(start 57.022746 -24.1427)
		(end 57.022746 -23.3807)
		(width 0.254)
		(layer "F.Cu")
		(net "P5VB_TRIP")
	)
	(segment
		(start 56.858154 -20.422108)
		(end 57.022746 -20.5867)
		(width 0.254)
		(layer "F.Cu")
		(net "P5VB_TRIP")
	)
	(segment
		(start 57.530746 -24.6507)
		(end 57.022746 -24.1427)
		(width 0.254)
		(layer "F.Cu")
		(net "P5VB_TRIP")
	)
	(segment
		(start 57.022746 -20.5867)
		(end 57.022746 -23.3807)
		(width 0.254)
		(layer "F.Cu")
		(net "P5VB_TRIP")
	)
	(segment
		(start 55.961026 -20.422108)
		(end 56.858154 -20.422108)
		(width 0.254)
		(layer "F.Cu")
		(net "P5VB_TRIP")
	)
	(segment
		(start 58.483246 -24.6507)
		(end 57.530746 -24.6507)
		(width 0.254)
		(layer "F.Cu")
		(net "P5VB_TRIP")
	)
	(via
		(at 57.022746 -23.3807)
		(size 0.7112)
		(drill 0.3556)
		(layers "F.Cu" "B.Cu")
		(net "P5VB_TRIP")
	)
	(segment
		(start 58.641996 -22.409404)
		(end 58.625994 -22.409404)
		(width 0.254)
		(layer "F.Cu")
		(net "P5VB_MODE_PG")
	)
	(segment
		(start 60.0964 -24.2697)
		(end 59.339988 -23.513288)
		(width 0.254)
		(layer "F.Cu")
		(net "P5VB_MODE_PG")
	)
	(segment
		(start 60.515246 -24.2697)
		(end 60.0964 -24.2697)
		(width 0.254)
		(layer "F.Cu")
		(net "P5VB_MODE_PG")
	)
	(segment
		(start 59.339988 -23.513288)
		(end 59.339988 -23.107396)
		(width 0.254)
		(layer "F.Cu")
		(net "P5VB_MODE_PG")
	)
	(segment
		(start 59.339988 -23.107396)
		(end 58.641996 -22.409404)
		(width 0.254)
		(layer "F.Cu")
		(net "P5VB_MODE_PG")
	)
	(via
		(at 58.625994 -22.409404)
		(size 0.7112)
		(drill 0.3556)
		(layers "F.Cu" "B.Cu")
		(net "P5VB_MODE_PG")
	)
	(segment
		(start 59.372246 -28.1432)
		(end 58.797444 -28.718002)
		(width 0.508)
		(layer "F.Cu")
		(net "P5VB_VREG")
	)
	(segment
		(start 58.927746 -19.6977)
		(end 58.610246 -19.3802)
		(width 0.254)
		(layer "F.Cu")
		(net "P5VB_VREG")
	)
	(segment
		(start 58.152284 -18.922238)
		(end 55.961026 -18.922238)
		(width 0.254)
		(layer "F.Cu")
		(net "P5VB_VREG")
	)
	(segment
		(start 58.927746 -20.2692)
		(end 58.927746 -19.6977)
		(width 0.254)
		(layer "F.Cu")
		(net "P5VB_VREG")
	)
	(segment
		(start 58.610246 -19.3802)
		(end 58.152284 -18.922238)
		(width 0.254)
		(layer "F.Cu")
		(net "P5VB_VREG")
	)
	(segment
		(start 59.816746 -21.5392)
		(end 59.597036 -21.5392)
		(width 0.254)
		(layer "F.Cu")
		(net "P5VB_VREG")
	)
	(segment
		(start 59.597036 -21.5392)
		(end 59.181746 -21.12391)
		(width 0.254)
		(layer "F.Cu")
		(net "P5VB_VREG")
	)
	(segment
		(start 58.797444 -28.718002)
		(end 50.993548 -28.718002)
		(width 0.508)
		(layer "F.Cu")
		(net "P5VB_VREG")
	)
	(segment
		(start 50.993548 -28.718002)
		(end 50.164746 -27.8892)
		(width 0.508)
		(layer "F.Cu")
		(net "P5VB_VREG")
	)
	(segment
		(start 59.181746 -21.12391)
		(end 59.181746 -20.5232)
		(width 0.254)
		(layer "F.Cu")
		(net "P5VB_VREG")
	)
	(segment
		(start 59.181746 -20.5232)
		(end 58.927746 -20.2692)
		(width 0.254)
		(layer "F.Cu")
		(net "P5VB_VREG")
	)
	(segment
		(start 59.372246 -26.6827)
		(end 59.372246 -28.1432)
		(width 0.508)
		(layer "F.Cu")
		(net "P5VB_VREG")
	)
	(segment
		(start 50.164746 -27.8892)
		(end 50.164746 -25.7302)
		(width 0.508)
		(layer "F.Cu")
		(net "P5VB_VREG")
	)
	(via
		(at 58.610246 -19.3802)
		(size 0.5588)
		(drill 0.3048)
		(layers "F.Cu" "B.Cu")
		(net "P5VB_VREG")
	)
	(via
		(at 59.372246 -28.1432)
		(size 0.5588)
		(drill 0.3048)
		(layers "F.Cu" "B.Cu")
		(net "P5VB_VREG")
	)
	(via
		(at 61.239146 -24.1427)
		(size 0.7112)
		(drill 0.3556)
		(layers "F.Cu" "B.Cu")
		(net "P5VB_VREG")
	)
	(segment
		(start 60.62345 -28.1432)
		(end 61.239146 -27.527504)
		(width 0.508)
		(layer "B.Cu")
		(net "P5VB_VREG")
	)
	(segment
		(start 61.239146 -27.527504)
		(end 61.239146 -24.1427)
		(width 0.508)
		(layer "B.Cu")
		(net "P5VB_VREG")
	)
	(segment
		(start 59.372246 -28.1432)
		(end 60.62345 -28.1432)
		(width 0.508)
		(layer "B.Cu")
		(net "P5VB_VREG")
	)
	(segment
		(start 58.610246 -19.3802)
		(end 61.239146 -22.0091)
		(width 0.508)
		(layer "B.Cu")
		(net "P5VB_VREG")
	)
	(segment
		(start 61.239146 -22.0091)
		(end 61.239146 -24.1427)
		(width 0.508)
		(layer "B.Cu")
		(net "P5VB_VREG")
	)
	(segment
		(start 49.910746 -21.311108)
		(end 50.456338 -21.8567)
		(width 0.254)
		(layer "F.Cu")
		(net "P5VB_EN")
	)
	(segment
		(start 51.180746 -24.1427)
		(end 51.561746 -23.7617)
		(width 0.254)
		(layer "F.Cu")
		(net "P5VB_EN")
	)
	(segment
		(start 52.196746 -24.8412)
		(end 51.180746 -24.8412)
		(width 0.254)
		(layer "F.Cu")
		(net "P5VB_EN")
	)
	(segment
		(start 51.180746 -24.8412)
		(end 51.180746 -24.1427)
		(width 0.254)
		(layer "F.Cu")
		(net "P5VB_EN")
	)
	(segment
		(start 50.456338 -21.8567)
		(end 50.456338 -21.894292)
		(width 0.254)
		(layer "F.Cu")
		(net "P5VB_EN")
	)
	(segment
		(start 51.062382 -20.422108)
		(end 50.202338 -20.422108)
		(width 0.254)
		(layer "F.Cu")
		(net "P5VB_EN")
	)
	(segment
		(start 50.456338 -21.894292)
		(end 51.561746 -22.9997)
		(width 0.254)
		(layer "F.Cu")
		(net "P5VB_EN")
	)
	(segment
		(start 49.910746 -20.7137)
		(end 49.910746 -21.311108)
		(width 0.254)
		(layer "F.Cu")
		(net "P5VB_EN")
	)
	(segment
		(start 50.202338 -20.422108)
		(end 49.910746 -20.7137)
		(width 0.254)
		(layer "F.Cu")
		(net "P5VB_EN")
	)
	(segment
		(start 51.561746 -23.7617)
		(end 51.561746 -22.9997)
		(width 0.254)
		(layer "F.Cu")
		(net "P5VB_EN")
	)
	(segment
		(start 63.528956 -20.0787)
		(end 63.528956 -22.46249)
		(width 0.508)
		(layer "F.Cu")
		(net "P5VB_VDD")
	)
	(segment
		(start 55.961026 -19.42211)
		(end 57.636156 -19.42211)
		(width 0.254)
		(layer "F.Cu")
		(net "P5VB_VDD")
	)
	(segment
		(start 63.528956 -22.46249)
		(end 63.169546 -22.8219)
		(width 0.508)
		(layer "F.Cu")
		(net "P5VB_VDD")
	)
	(segment
		(start 59.393836 -22.098)
		(end 59.406536 -22.1107)
		(width 0.254)
		(layer "F.Cu")
		(net "P5VB_VDD")
	)
	(segment
		(start 58.241184 -20.5867)
		(end 58.241184 -20.973796)
		(width 0.254)
		(layer "F.Cu")
		(net "P5VB_VDD")
	)
	(segment
		(start 59.365388 -22.098)
		(end 59.393836 -22.098)
		(width 0.254)
		(layer "F.Cu")
		(net "P5VB_VDD")
	)
	(segment
		(start 61.594746 -19.4437)
		(end 62.893956 -19.4437)
		(width 0.508)
		(layer "F.Cu")
		(net "P5VB_VDD")
	)
	(segment
		(start 62.893956 -19.4437)
		(end 63.528956 -20.0787)
		(width 0.508)
		(layer "F.Cu")
		(net "P5VB_VDD")
	)
	(segment
		(start 58.241184 -20.973796)
		(end 59.365388 -22.098)
		(width 0.254)
		(layer "F.Cu")
		(net "P5VB_VDD")
	)
	(segment
		(start 59.406536 -22.1107)
		(end 60.502546 -22.1107)
		(width 0.254)
		(layer "F.Cu")
		(net "P5VB_VDD")
	)
	(segment
		(start 63.169546 -22.8219)
		(end 61.213746 -22.8219)
		(width 0.508)
		(layer "F.Cu")
		(net "P5VB_VDD")
	)
	(segment
		(start 57.636156 -19.42211)
		(end 58.241184 -20.027138)
		(width 0.254)
		(layer "F.Cu")
		(net "P5VB_VDD")
	)
	(segment
		(start 60.502546 -22.1107)
		(end 61.213746 -22.8219)
		(width 0.254)
		(layer "F.Cu")
		(net "P5VB_VDD")
	)
	(segment
		(start 58.241184 -20.027138)
		(end 58.241184 -20.5867)
		(width 0.254)
		(layer "F.Cu")
		(net "P5VB_VDD")
	)
	(via
		(at 58.241184 -20.5867)
		(size 0.7112)
		(drill 0.3556)
		(layers "F.Cu" "B.Cu")
		(net "P5VB_VDD")
	)
	(via
		(at 213.486746 -13.9827)
		(size 0.7112)
		(drill 0.4064)
		(layers "F.Cu" "B.Cu")
		(net "P5VA_LL")
	)
	(via
		(at 220.217746 -17.9197)
		(size 0.7112)
		(drill 0.4064)
		(layers "F.Cu" "B.Cu")
		(net "P5VA_LL")
	)
	(via
		(at 217.550746 -18.0467)
		(size 0.7112)
		(drill 0.4064)
		(layers "F.Cu" "B.Cu")
		(net "P5VA_LL")
	)
	(via
		(at 229.869746 -17.1577)
		(size 0.7112)
		(drill 0.4064)
		(layers "F.Cu" "B.Cu")
		(net "P5VA_LL")
	)
	(via
		(at 215.899746 -11.3157)
		(size 0.7112)
		(drill 0.3556)
		(layers "F.Cu" "B.Cu")
		(net "P5VA_LL")
	)
	(via
		(at 213.740746 -18.1737)
		(size 0.7112)
		(drill 0.4064)
		(layers "F.Cu" "B.Cu")
		(net "P5VA_LL")
	)
	(via
		(at 219.836746 -10.0457)
		(size 0.7112)
		(drill 0.4064)
		(layers "F.Cu" "B.Cu")
		(net "P5VA_LL")
	)
	(via
		(at 213.359746 -11.6967)
		(size 0.7112)
		(drill 0.4064)
		(layers "F.Cu" "B.Cu")
		(net "P5VA_LL")
	)
	(via
		(at 226.313746 -18.5547)
		(size 0.7112)
		(drill 0.3556)
		(layers "F.Cu" "B.Cu")
		(net "P5VA_LL")
	)
	(via
		(at 229.996746 -14.3637)
		(size 0.7112)
		(drill 0.4064)
		(layers "F.Cu" "B.Cu")
		(net "P5VA_LL")
	)
	(via
		(at 227.075746 -11.8237)
		(size 0.7112)
		(drill 0.3556)
		(layers "F.Cu" "B.Cu")
		(net "P5VA_LL")
	)
	(via
		(at 213.613746 -15.8877)
		(size 0.7112)
		(drill 0.4064)
		(layers "F.Cu" "B.Cu")
		(net "P5VA_LL")
	)
	(via
		(at 224.535746 -9.9187)
		(size 0.7112)
		(drill 0.4064)
		(layers "F.Cu" "B.Cu")
		(net "P5VA_LL")
	)
	(via
		(at 223.900746 -17.9197)
		(size 0.7112)
		(drill 0.4064)
		(layers "F.Cu" "B.Cu")
		(net "P5VA_LL")
	)
	(via
		(at 229.742746 -18.8087)
		(size 0.7112)
		(drill 0.4064)
		(layers "F.Cu" "B.Cu")
		(net "P5VA_LL")
	)
	(via
		(at 217.042746 -10.0457)
		(size 0.7112)
		(drill 0.4064)
		(layers "F.Cu" "B.Cu")
		(net "P5VA_LL")
	)
	(via
		(at 215.518746 -17.1577)
		(size 0.7112)
		(drill 0.3556)
		(layers "F.Cu" "B.Cu")
		(net "P5VA_LL")
	)
	(via
		(at 229.869746 -15.6337)
		(size 0.7112)
		(drill 0.4064)
		(layers "F.Cu" "B.Cu")
		(net "P5VA_LL")
	)
	(segment
		(start 235.838746 -28.3972)
		(end 235.838746 -28.8417)
		(width 0.508)
		(layer "F.Cu")
		(net "P5VA_LL_NET")
	)
	(segment
		(start 235.838746 -28.8417)
		(end 235.457746 -29.2227)
		(width 0.508)
		(layer "F.Cu")
		(net "P5VA_LL_NET")
	)
	(segment
		(start 230.441246 -31.6357)
		(end 231.393746 -31.6357)
		(width 0.508)
		(layer "F.Cu")
		(net "P5VA_LL_NET")
	)
	(segment
		(start 228.536246 -22.4282)
		(end 227.97897 -22.985476)
		(width 0.508)
		(layer "F.Cu")
		(net "P5VA_LL_NET")
	)
	(segment
		(start 228.726746 -22.4282)
		(end 228.536246 -22.4282)
		(width 0.508)
		(layer "F.Cu")
		(net "P5VA_LL_NET")
	)
	(via
		(at 229.742746 -30.8737)
		(size 0.7112)
		(drill 0.3556)
		(layers "F.Cu" "B.Cu")
		(net "P5VA_LL_NET")
	)
	(via
		(at 231.393746 -31.6357)
		(size 0.5588)
		(drill 0.3048)
		(layers "F.Cu" "B.Cu")
		(net "P5VA_LL_NET")
	)
	(via
		(at 227.97897 -22.985476)
		(size 0.5588)
		(drill 0.3048)
		(layers "F.Cu" "B.Cu")
		(net "P5VA_LL_NET")
	)
	(via
		(at 235.457746 -29.2227)
		(size 0.5588)
		(drill 0.3048)
		(layers "F.Cu" "B.Cu")
		(net "P5VA_LL_NET")
	)
	(segment
		(start 230.758746 -30.8737)
		(end 229.742746 -30.8737)
		(width 0.508)
		(layer "B.Cu")
		(net "P5VA_LL_NET")
	)
	(segment
		(start 234.187746 -29.2227)
		(end 231.774746 -31.6357)
		(width 0.508)
		(layer "B.Cu")
		(net "P5VA_LL_NET")
	)
	(segment
		(start 231.393746 -31.6357)
		(end 231.393746 -31.5087)
		(width 0.508)
		(layer "B.Cu")
		(net "P5VA_LL_NET")
	)
	(segment
		(start 227.532946 -23.4315)
		(end 227.532946 -30.0609)
		(width 0.508)
		(layer "B.Cu")
		(net "P5VA_LL_NET")
	)
	(segment
		(start 228.345746 -30.8737)
		(end 229.742746 -30.8737)
		(width 0.508)
		(layer "B.Cu")
		(net "P5VA_LL_NET")
	)
	(segment
		(start 227.532946 -30.0609)
		(end 228.345746 -30.8737)
		(width 0.508)
		(layer "B.Cu")
		(net "P5VA_LL_NET")
	)
	(segment
		(start 227.97897 -22.985476)
		(end 227.532946 -23.4315)
		(width 0.508)
		(layer "B.Cu")
		(net "P5VA_LL_NET")
	)
	(segment
		(start 235.457746 -29.2227)
		(end 234.187746 -29.2227)
		(width 0.508)
		(layer "B.Cu")
		(net "P5VA_LL_NET")
	)
	(segment
		(start 231.393746 -31.5087)
		(end 230.758746 -30.8737)
		(width 0.508)
		(layer "B.Cu")
		(net "P5VA_LL_NET")
	)
	(segment
		(start 231.774746 -31.6357)
		(end 231.393746 -31.6357)
		(width 0.508)
		(layer "B.Cu")
		(net "P5VA_LL_NET")
	)
	(segment
		(start 229.742746 -22.4282)
		(end 229.742746 -22.6187)
		(width 0.254)
		(layer "F.Cu")
		(net "P5VA_VBST_NET")
	)
	(segment
		(start 228.726746 -29.2227)
		(end 228.345746 -28.8417)
		(width 0.508)
		(layer "F.Cu")
		(net "P5VA_VBST_NET")
	)
	(segment
		(start 229.742746 -22.6187)
		(end 228.980746 -23.3807)
		(width 0.254)
		(layer "F.Cu")
		(net "P5VA_VBST_NET")
	)
	(segment
		(start 228.345746 -28.8417)
		(end 228.345746 -28.0797)
		(width 0.508)
		(layer "F.Cu")
		(net "P5VA_VBST_NET")
	)
	(via
		(at 228.980746 -23.3807)
		(size 0.5588)
		(drill 0.3048)
		(layers "F.Cu" "B.Cu")
		(net "P5VA_VBST_NET")
	)
	(via
		(at 228.345746 -28.0797)
		(size 0.5588)
		(drill 0.3048)
		(layers "F.Cu" "B.Cu")
		(net "P5VA_VBST_NET")
	)
	(via
		(at 228.345746 -26.5557)
		(size 0.7112)
		(drill 0.3556)
		(layers "F.Cu" "B.Cu")
		(net "P5VA_VBST_NET")
	)
	(segment
		(start 228.345746 -28.0797)
		(end 228.345746 -26.5557)
		(width 0.508)
		(layer "B.Cu")
		(net "P5VA_VBST_NET")
	)
	(segment
		(start 228.345746 -26.1747)
		(end 228.345746 -26.5557)
		(width 0.508)
		(layer "B.Cu")
		(net "P5VA_VBST_NET")
	)
	(segment
		(start 228.980746 -23.3807)
		(end 229.006146 -23.4061)
		(width 0.508)
		(layer "B.Cu")
		(net "P5VA_VBST_NET")
	)
	(segment
		(start 229.006146 -25.5143)
		(end 228.345746 -26.1747)
		(width 0.508)
		(layer "B.Cu")
		(net "P5VA_VBST_NET")
	)
	(segment
		(start 229.006146 -23.4061)
		(end 229.006146 -25.5143)
		(width 0.508)
		(layer "B.Cu")
		(net "P5VA_VBST_NET")
	)
	(segment
		(start 235.330746 -25.7937)
		(end 235.330746 -26.1747)
		(width 0.254)
		(layer "F.Cu")
		(net "P5VA_VFB")
	)
	(segment
		(start 236.854746 -27.5082)
		(end 235.838746 -27.5082)
		(width 0.508)
		(layer "F.Cu")
		(net "P5VA_VFB")
	)
	(segment
		(start 235.838746 -27.5082)
		(end 234.822746 -27.5082)
		(width 0.508)
		(layer "F.Cu")
		(net "P5VA_VFB")
	)
	(segment
		(start 234.822746 -27.5082)
		(end 234.822746 -26.6827)
		(width 0.254)
		(layer "F.Cu")
		(net "P5VA_VFB")
	)
	(segment
		(start 233.389424 -24.229822)
		(end 233.389424 -24.614378)
		(width 0.254)
		(layer "F.Cu")
		(net "P5VA_VFB")
	)
	(segment
		(start 233.389424 -24.614378)
		(end 233.806746 -25.0317)
		(width 0.254)
		(layer "F.Cu")
		(net "P5VA_VFB")
	)
	(segment
		(start 233.806746 -25.0317)
		(end 234.568746 -25.0317)
		(width 0.254)
		(layer "F.Cu")
		(net "P5VA_VFB")
	)
	(segment
		(start 234.822746 -26.6827)
		(end 235.330746 -26.1747)
		(width 0.254)
		(layer "F.Cu")
		(net "P5VA_VFB")
	)
	(segment
		(start 234.568746 -25.0317)
		(end 235.330746 -25.7937)
		(width 0.254)
		(layer "F.Cu")
		(net "P5VA_VFB")
	)
	(via
		(at 235.330746 -26.1747)
		(size 0.7112)
		(drill 0.3556)
		(layers "F.Cu" "B.Cu")
		(net "P5VA_VFB")
	)
	(segment
		(start 230.631746 -22.717252)
		(end 229.996746 -23.352252)
		(width 0.254)
		(layer "F.Cu")
		(net "P5VA_SNB")
	)
	(segment
		(start 230.060246 -25.1587)
		(end 229.996746 -25.0952)
		(width 0.254)
		(layer "F.Cu")
		(net "P5VA_SNB")
	)
	(segment
		(start 230.631746 -22.4282)
		(end 230.631746 -22.717252)
		(width 0.254)
		(layer "F.Cu")
		(net "P5VA_SNB")
	)
	(segment
		(start 229.996746 -25.0952)
		(end 229.996746 -24.0157)
		(width 0.254)
		(layer "F.Cu")
		(net "P5VA_SNB")
	)
	(segment
		(start 229.996746 -23.352252)
		(end 229.996746 -24.0157)
		(width 0.254)
		(layer "F.Cu")
		(net "P5VA_SNB")
	)
	(via
		(at 229.996746 -24.0157)
		(size 0.7112)
		(drill 0.3556)
		(layers "F.Cu" "B.Cu")
		(net "P5VA_SNB")
	)
	(segment
		(start 230.885746 -27.387042)
		(end 230.885746 -26.3017)
		(width 0.254)
		(layer "F.Cu")
		(net "P5VA_VBST")
	)
	(segment
		(start 231.266746 -23.8125)
		(end 231.266746 -25.0317)
		(width 0.254)
		(layer "F.Cu")
		(net "P5VA_VBST")
	)
	(segment
		(start 233.389424 -22.729698)
		(end 232.349548 -22.729698)
		(width 0.254)
		(layer "F.Cu")
		(net "P5VA_VBST")
	)
	(segment
		(start 230.250746 -29.2227)
		(end 230.250746 -28.022042)
		(width 0.254)
		(layer "F.Cu")
		(net "P5VA_VBST")
	)
	(segment
		(start 230.250746 -28.022042)
		(end 230.885746 -27.387042)
		(width 0.254)
		(layer "F.Cu")
		(net "P5VA_VBST")
	)
	(segment
		(start 231.266746 -25.9207)
		(end 231.266746 -25.0317)
		(width 0.254)
		(layer "F.Cu")
		(net "P5VA_VBST")
	)
	(segment
		(start 232.349548 -22.729698)
		(end 231.266746 -23.8125)
		(width 0.254)
		(layer "F.Cu")
		(net "P5VA_VBST")
	)
	(segment
		(start 230.885746 -26.3017)
		(end 231.266746 -25.9207)
		(width 0.254)
		(layer "F.Cu")
		(net "P5VA_VBST")
	)
	(via
		(at 231.266746 -25.0317)
		(size 0.7112)
		(drill 0.3556)
		(layers "F.Cu" "B.Cu")
		(net "P5VA_VBST")
	)
	(segment
		(start 237.362746 -30.1625)
		(end 239.033558 -30.1625)
		(width 0.508)
		(layer "F.Cu")
		(net "P5VA_AGND")
	)
	(segment
		(start 234.695746 -28.5242)
		(end 234.695746 -29.6037)
		(width 0.508)
		(layer "F.Cu")
		(net "P5VA_AGND")
	)
	(segment
		(start 239.902746 -28.6893)
		(end 240.537746 -29.3243)
		(width 0.508)
		(layer "F.Cu")
		(net "P5VA_AGND")
	)
	(segment
		(start 234.695746 -29.6037)
		(end 235.254546 -30.1625)
		(width 0.508)
		(layer "F.Cu")
		(net "P5VA_AGND")
	)
	(segment
		(start 234.822746 -28.3972)
		(end 234.695746 -28.5242)
		(width 0.508)
		(layer "F.Cu")
		(net "P5VA_AGND")
	)
	(segment
		(start 239.033558 -30.1625)
		(end 239.871758 -29.3243)
		(width 0.508)
		(layer "F.Cu")
		(net "P5VA_AGND")
	)
	(segment
		(start 238.886746 -28.3972)
		(end 239.902746 -28.3972)
		(width 0.508)
		(layer "F.Cu")
		(net "P5VA_AGND")
	)
	(segment
		(start 235.254546 -30.1625)
		(end 237.362746 -30.1625)
		(width 0.508)
		(layer "F.Cu")
		(net "P5VA_AGND")
	)
	(segment
		(start 239.902746 -28.3972)
		(end 239.902746 -28.6893)
		(width 0.508)
		(layer "F.Cu")
		(net "P5VA_AGND")
	)
	(segment
		(start 239.871758 -29.3243)
		(end 240.537746 -29.3243)
		(width 0.508)
		(layer "F.Cu")
		(net "P5VA_AGND")
	)
	(segment
		(start 229.171246 -27.1907)
		(end 229.234746 -27.2542)
		(width 0.508)
		(layer "F.Cu")
		(net "P5VA_AGND")
	)
	(segment
		(start 229.234746 -27.2542)
		(end 229.234746 -28.0797)
		(width 0.508)
		(layer "F.Cu")
		(net "P5VA_AGND")
	)
	(via
		(at 229.234746 -28.0797)
		(size 0.5588)
		(drill 0.3048)
		(layers "F.Cu" "B.Cu")
		(net "P5VA_AGND")
	)
	(via
		(at 233.298746 -27.1907)
		(size 0.7112)
		(drill 0.3556)
		(layers "F.Cu" "B.Cu")
		(net "P5VA_AGND")
	)
	(via
		(at 237.362746 -30.1625)
		(size 0.5588)
		(drill 0.3048)
		(layers "F.Cu" "B.Cu")
		(net "P5VA_AGND")
	)
	(segment
		(start 237.362746 -28.7147)
		(end 235.838746 -27.1907)
		(width 0.508)
		(layer "B.Cu")
		(net "P5VA_AGND")
	)
	(segment
		(start 237.362746 -30.1625)
		(end 237.362746 -28.7147)
		(width 0.508)
		(layer "B.Cu")
		(net "P5VA_AGND")
	)
	(segment
		(start 230.123746 -27.1907)
		(end 233.298746 -27.1907)
		(width 0.508)
		(layer "B.Cu")
		(net "P5VA_AGND")
	)
	(segment
		(start 229.234746 -28.0797)
		(end 230.123746 -27.1907)
		(width 0.508)
		(layer "B.Cu")
		(net "P5VA_AGND")
	)
	(segment
		(start 235.838746 -27.1907)
		(end 233.298746 -27.1907)
		(width 0.508)
		(layer "B.Cu")
		(net "P5VA_AGND")
	)
	(segment
		(start 237.743746 -27.3812)
		(end 237.743746 -26.4287)
		(width 0.254)
		(layer "F.Cu")
		(net "P5VA_RF")
	)
	(segment
		(start 237.743746 -26.0477)
		(end 237.743746 -26.4287)
		(width 0.254)
		(layer "F.Cu")
		(net "P5VA_RF")
	)
	(segment
		(start 238.288068 -24.229822)
		(end 238.288068 -25.503378)
		(width 0.254)
		(layer "F.Cu")
		(net "P5VA_RF")
	)
	(segment
		(start 237.870746 -27.5082)
		(end 237.743746 -27.3812)
		(width 0.254)
		(layer "F.Cu")
		(net "P5VA_RF")
	)
	(segment
		(start 238.288068 -25.503378)
		(end 237.743746 -26.0477)
		(width 0.254)
		(layer "F.Cu")
		(net "P5VA_RF")
	)
	(segment
		(start 238.886746 -27.5082)
		(end 237.870746 -27.5082)
		(width 0.254)
		(layer "F.Cu")
		(net "P5VA_RF")
	)
	(via
		(at 237.743746 -26.4287)
		(size 0.7112)
		(drill 0.3556)
		(layers "F.Cu" "B.Cu")
		(net "P5VA_RF")
	)
	(segment
		(start 238.981742 -23.729696)
		(end 239.235742 -23.983696)
		(width 0.254)
		(layer "F.Cu")
		(net "P5VA_TRIP")
	)
	(segment
		(start 238.288068 -23.729696)
		(end 238.981742 -23.729696)
		(width 0.254)
		(layer "F.Cu")
		(net "P5VA_TRIP")
	)
	(segment
		(start 239.235742 -26.841196)
		(end 239.235742 -26.1747)
		(width 0.254)
		(layer "F.Cu")
		(net "P5VA_TRIP")
	)
	(segment
		(start 239.235742 -23.983696)
		(end 239.235742 -26.1747)
		(width 0.254)
		(layer "F.Cu")
		(net "P5VA_TRIP")
	)
	(segment
		(start 239.902746 -27.5082)
		(end 239.235742 -26.841196)
		(width 0.254)
		(layer "F.Cu")
		(net "P5VA_TRIP")
	)
	(via
		(at 239.235742 -26.1747)
		(size 0.7112)
		(drill 0.3556)
		(layers "F.Cu" "B.Cu")
		(net "P5VA_TRIP")
	)
	(segment
		(start 239.902746 -23.7617)
		(end 239.902746 -24.1427)
		(width 0.254)
		(layer "F.Cu")
		(net "P5VA_MODE")
	)
	(segment
		(start 239.37087 -23.229824)
		(end 239.902746 -23.7617)
		(width 0.254)
		(layer "F.Cu")
		(net "P5VA_MODE")
	)
	(segment
		(start 239.902746 -26.5557)
		(end 239.902746 -24.1427)
		(width 0.254)
		(layer "F.Cu")
		(net "P5VA_MODE")
	)
	(segment
		(start 240.156746 -26.8097)
		(end 239.902746 -26.5557)
		(width 0.254)
		(layer "F.Cu")
		(net "P5VA_MODE")
	)
	(segment
		(start 240.918746 -27.5082)
		(end 240.220246 -26.8097)
		(width 0.254)
		(layer "F.Cu")
		(net "P5VA_MODE")
	)
	(segment
		(start 238.288068 -23.229824)
		(end 239.37087 -23.229824)
		(width 0.254)
		(layer "F.Cu")
		(net "P5VA_MODE")
	)
	(segment
		(start 240.220246 -26.8097)
		(end 240.156746 -26.8097)
		(width 0.254)
		(layer "F.Cu")
		(net "P5VA_MODE")
	)
	(via
		(at 239.902746 -24.1427)
		(size 0.7112)
		(drill 0.3556)
		(layers "F.Cu" "B.Cu")
		(net "P5VA_MODE")
	)
	(segment
		(start 241.934746 -28.3972)
		(end 242.442746 -28.9052)
		(width 0.508)
		(layer "F.Cu")
		(net "P5VA_MODE_PG")
	)
	(segment
		(start 240.918746 -28.3972)
		(end 241.934746 -28.3972)
		(width 0.508)
		(layer "F.Cu")
		(net "P5VA_MODE_PG")
	)
	(segment
		(start 242.442746 -28.9052)
		(end 242.442746 -29.6037)
		(width 0.508)
		(layer "F.Cu")
		(net "P5VA_MODE_PG")
	)
	(via
		(at 242.442746 -29.6037)
		(size 0.7112)
		(drill 0.3556)
		(layers "F.Cu" "B.Cu")
		(net "P5VA_MODE_PG")
	)
	(segment
		(start 232.790746 -27.5082)
		(end 233.806746 -27.5082)
		(width 0.508)
		(layer "F.Cu")
		(net "P5VA_EN")
	)
	(segment
		(start 233.806746 -27.5082)
		(end 233.806746 -26.3017)
		(width 0.508)
		(layer "F.Cu")
		(net "P5VA_EN")
	)
	(segment
		(start 232.536746 -23.983696)
		(end 232.536746 -24.7777)
		(width 0.254)
		(layer "F.Cu")
		(net "P5VA_EN")
	)
	(segment
		(start 233.806746 -26.3017)
		(end 233.933746 -26.1747)
		(width 0.508)
		(layer "F.Cu")
		(net "P5VA_EN")
	)
	(segment
		(start 232.536746 -24.7777)
		(end 233.933746 -26.1747)
		(width 0.254)
		(layer "F.Cu")
		(net "P5VA_EN")
	)
	(segment
		(start 233.389424 -23.729696)
		(end 232.790746 -23.729696)
		(width 0.254)
		(layer "F.Cu")
		(net "P5VA_EN")
	)
	(segment
		(start 232.790746 -23.729696)
		(end 232.536746 -23.983696)
		(width 0.254)
		(layer "F.Cu")
		(net "P5VA_EN")
	)
	(segment
		(start 243.458746 -22.7457)
		(end 244.347746 -22.7457)
		(width 0.254)
		(layer "F.Cu")
		(net "P5VA_VDD")
	)
	(segment
		(start 244.866668 -23.264622)
		(end 244.866668 -24.3967)
		(width 0.254)
		(layer "F.Cu")
		(net "P5VA_VDD")
	)
	(segment
		(start 240.537746 -23.3807)
		(end 239.886744 -22.729698)
		(width 0.254)
		(layer "F.Cu")
		(net "P5VA_VDD")
	)
	(segment
		(start 240.537746 -24.942546)
		(end 240.537746 -25.2349)
		(width 0.254)
		(layer "F.Cu")
		(net "P5VA_VDD")
	)
	(segment
		(start 240.537746 -24.942546)
		(end 240.537746 -23.3807)
		(width 0.254)
		(layer "F.Cu")
		(net "P5VA_VDD")
	)
	(segment
		(start 244.866668 -25.736804)
		(end 243.857272 -26.7462)
		(width 0.254)
		(layer "F.Cu")
		(net "P5VA_VDD")
	)
	(segment
		(start 241.871246 -26.7462)
		(end 241.096546 -25.9715)
		(width 0.254)
		(layer "F.Cu")
		(net "P5VA_VDD")
	)
	(segment
		(start 241.096546 -25.9715)
		(end 241.096546 -25.7937)
		(width 0.254)
		(layer "F.Cu")
		(net "P5VA_VDD")
	)
	(segment
		(start 244.347746 -22.7457)
		(end 244.866668 -23.264622)
		(width 0.254)
		(layer "F.Cu")
		(net "P5VA_VDD")
	)
	(segment
		(start 239.886744 -22.729698)
		(end 238.288068 -22.729698)
		(width 0.254)
		(layer "F.Cu")
		(net "P5VA_VDD")
	)
	(segment
		(start 240.537746 -25.2349)
		(end 241.096546 -25.7937)
		(width 0.254)
		(layer "F.Cu")
		(net "P5VA_VDD")
	)
	(segment
		(start 244.866668 -24.3967)
		(end 244.866668 -25.736804)
		(width 0.254)
		(layer "F.Cu")
		(net "P5VA_VDD")
	)
	(segment
		(start 243.857272 -26.7462)
		(end 241.871246 -26.7462)
		(width 0.254)
		(layer "F.Cu")
		(net "P5VA_VDD")
	)
	(via
		(at 244.866668 -24.3967)
		(size 0.7112)
		(drill 0.3556)
		(layers "F.Cu" "B.Cu")
		(net "P5VA_VDD")
	)
	(segment
		(start 45.9994 -426.7454)
		(end 45.5676 -426.3136)
		(width 0.4064)
		(layer "F.Cu")
		(net "P5VC")
	)
	(segment
		(start 19.621246 -466.7377)
		(end 20.319746 -466.7377)
		(width 0.508)
		(layer "F.Cu")
		(net "P5VC")
	)
	(segment
		(start 6.86562 -488.40009)
		(end 6.857746 -488.392216)
		(width 0.508)
		(layer "F.Cu")
		(net "P5VC")
	)
	(segment
		(start 45.9994 -427.4058)
		(end 45.9994 -426.7454)
		(width 0.4064)
		(layer "F.Cu")
		(net "P5VC")
	)
	(segment
		(start 6.857746 -488.233466)
		(end 6.79831 -488.17403)
		(width 0.508)
		(layer "F.Cu")
		(net "P5VC")
	)
	(segment
		(start 132.459476 -448.57162)
		(end 82.880454 -448.57162)
		(width 0.508)
		(layer "F.Cu")
		(net "P5VC")
	)
	(segment
		(start 47.36084 -238.0234)
		(end 53.971444 -238.0234)
		(width 0.4064)
		(layer "F.Cu")
		(net "P5VC")
	)
	(segment
		(start 14.207744 -167.0177)
		(end 11.048746 -167.0177)
		(width 0.508)
		(layer "F.Cu")
		(net "P5VC")
	)
	(segment
		(start 37.7952 -139.7762)
		(end 37.09924 -139.7762)
		(width 0.4064)
		(layer "F.Cu")
		(net "P5VC")
	)
	(segment
		(start 15.049246 -51.7017)
		(end 15.049246 -51.0667)
		(width 0.508)
		(layer "F.Cu")
		(net "P5VC")
	)
	(segment
		(start 86.70544 -24.75484)
		(end 82.4992 -24.75484)
		(width 0.4064)
		(layer "F.Cu")
		(net "P5VC")
	)
	(segment
		(start 53.971444 -238.0234)
		(end 54.609746 -238.661702)
		(width 0.4064)
		(layer "F.Cu")
		(net "P5VC")
	)
	(segment
		(start 45.5676 -426.3136)
		(end 45.04944 -426.3136)
		(width 0.4064)
		(layer "F.Cu")
		(net "P5VC")
	)
	(segment
		(start 30.416246 -345.020646)
		(end 30.9118 -345.5162)
		(width 0.508)
		(layer "F.Cu")
		(net "P5VC")
	)
	(segment
		(start 16.649446 -256.921)
		(end 17.018 -256.921)
		(width 0.508)
		(layer "F.Cu")
		(net "P5VC")
	)
	(segment
		(start 15.049246 -51.0667)
		(end 15.430246 -50.6857)
		(width 0.508)
		(layer "F.Cu")
		(net "P5VC")
	)
	(segment
		(start 87.883746 -25.5397)
		(end 87.4903 -25.5397)
		(width 0.4064)
		(layer "F.Cu")
		(net "P5VC")
	)
	(segment
		(start 15.430246 -50.6857)
		(end 24.764746 -50.6857)
		(width 1.016)
		(layer "F.Cu")
		(net "P5VC")
	)
	(segment
		(start 30.9118 -345.5162)
		(end 31.369 -345.5162)
		(width 0.508)
		(layer "F.Cu")
		(net "P5VC")
	)
	(segment
		(start 24.764746 -50.6857)
		(end 24.891746 -50.5587)
		(width 1.016)
		(layer "F.Cu")
		(net "P5VC")
	)
	(segment
		(start 30.416246 -344.4367)
		(end 30.416246 -345.020646)
		(width 0.508)
		(layer "F.Cu")
		(net "P5VC")
	)
	(segment
		(start 179.197 -452.2216)
		(end 136.109456 -452.2216)
		(width 0.508)
		(layer "F.Cu")
		(net "P5VC")
	)
	(segment
		(start 20.319746 -466.7377)
		(end 20.573746 -466.4837)
		(width 0.508)
		(layer "F.Cu")
		(net "P5VC")
	)
	(segment
		(start 136.109456 -452.2216)
		(end 132.459476 -448.57162)
		(width 0.508)
		(layer "F.Cu")
		(net "P5VC")
	)
	(segment
		(start 6.86562 -488.997752)
		(end 6.86562 -488.40009)
		(width 0.508)
		(layer "F.Cu")
		(net "P5VC")
	)
	(segment
		(start 37.4396 -338.556854)
		(end 37.4396 -337.73364)
		(width 0.4064)
		(layer "F.Cu")
		(net "P5VC")
	)
	(segment
		(start 39.751 -140.716)
		(end 38.735 -140.716)
		(width 0.4064)
		(layer "F.Cu")
		(net "P5VC")
	)
	(segment
		(start 87.4903 -25.5397)
		(end 86.70544 -24.75484)
		(width 0.4064)
		(layer "F.Cu")
		(net "P5VC")
	)
	(segment
		(start 180.479446 -456.662536)
		(end 180.479446 -453.504046)
		(width 0.508)
		(layer "F.Cu")
		(net "P5VC")
	)
	(segment
		(start 15.176246 -258.3307)
		(end 15.239746 -258.3307)
		(width 0.508)
		(layer "F.Cu")
		(net "P5VC")
	)
	(segment
		(start 180.479446 -453.504046)
		(end 179.197 -452.2216)
		(width 0.508)
		(layer "F.Cu")
		(net "P5VC")
	)
	(segment
		(start 15.239746 -258.3307)
		(end 16.649446 -256.921)
		(width 0.508)
		(layer "F.Cu")
		(net "P5VC")
	)
	(segment
		(start 14.477746 -166.747698)
		(end 14.207744 -167.0177)
		(width 0.508)
		(layer "F.Cu")
		(net "P5VC")
	)
	(segment
		(start 37.598096 -338.71535)
		(end 37.4396 -338.556854)
		(width 0.4064)
		(layer "F.Cu")
		(net "P5VC")
	)
	(segment
		(start 6.857746 -488.392216)
		(end 6.857746 -488.233466)
		(width 0.508)
		(layer "F.Cu")
		(net "P5VC")
	)
	(segment
		(start 38.735 -140.716)
		(end 37.7952 -139.7762)
		(width 0.4064)
		(layer "F.Cu")
		(net "P5VC")
	)
	(via
		(at 43.814746 -438.559702)
		(size 0.7112)
		(drill 0.4064)
		(layers "F.Cu" "B.Cu")
		(net "P5VC")
	)
	(via
		(at 43.814746 -435.3687)
		(size 0.7112)
		(drill 0.4064)
		(layers "F.Cu" "B.Cu")
		(net "P5VC")
	)
	(via
		(at 14.731746 -480.3267)
		(size 0.5588)
		(drill 0.3048)
		(layers "F.Cu" "B.Cu")
		(net "P5VC")
	)
	(via
		(at 41.147746 -195.0847)
		(size 0.7112)
		(drill 0.4064)
		(layers "F.Cu" "B.Cu")
		(net "P5VC")
	)
	(via
		(at 41.274746 -435.384702)
		(size 0.7112)
		(drill 0.4064)
		(layers "F.Cu" "B.Cu")
		(net "P5VC")
	)
	(via
		(at 33.2994 -484.759)
		(size 0.7112)
		(drill 0.4064)
		(layers "F.Cu" "B.Cu")
		(net "P5VC")
	)
	(via
		(at 49.148746 -137.442702)
		(size 0.7112)
		(drill 0.4064)
		(layers "F.Cu" "B.Cu")
		(net "P5VC")
	)
	(via
		(at 32.9184 -485.7496)
		(size 0.7112)
		(drill 0.4064)
		(layers "F.Cu" "B.Cu")
		(net "P5VC")
	)
	(via
		(at 31.749746 -485.7877)
		(size 0.7112)
		(drill 0.4064)
		(layers "F.Cu" "B.Cu")
		(net "P5VC")
	)
	(via
		(at 31.605982 -484.76154)
		(size 0.7112)
		(drill 0.4064)
		(layers "F.Cu" "B.Cu")
		(net "P5VC")
	)
	(via
		(at 40.433244 -240.313718)
		(size 0.7112)
		(drill 0.4064)
		(layers "F.Cu" "B.Cu")
		(net "P5VC")
	)
	(via
		(at 43.306746 -439.6867)
		(size 0.7112)
		(drill 0.4064)
		(layers "F.Cu" "B.Cu")
		(net "P5VC")
	)
	(via
		(at 21.191982 -483.61854)
		(size 0.7112)
		(drill 0.4064)
		(layers "F.Cu" "B.Cu")
		(net "P5VC")
	)
	(via
		(at 57.911746 -46.3677)
		(size 0.7112)
		(drill 0.4064)
		(layers "F.Cu" "B.Cu")
		(net "P5VC")
	)
	(via
		(at 21.081746 -479.4377)
		(size 0.7112)
		(drill 0.4064)
		(layers "F.Cu" "B.Cu")
		(net "P5VC")
	)
	(via
		(at 20.065746 -479.4377)
		(size 0.7112)
		(drill 0.4064)
		(layers "F.Cu" "B.Cu")
		(net "P5VC")
	)
	(via
		(at 45.719746 -328.3077)
		(size 0.7112)
		(drill 0.4064)
		(layers "F.Cu" "B.Cu")
		(net "P5VC")
	)
	(via
		(at 58.927746 -46.3677)
		(size 0.7112)
		(drill 0.4064)
		(layers "F.Cu" "B.Cu")
		(net "P5VC")
	)
	(via
		(at 85.978746 -30.6197)
		(size 0.7112)
		(drill 0.3556)
		(layers "F.Cu" "B.Cu")
		(net "P5VC")
	)
	(via
		(at 48.005746 -137.442702)
		(size 0.7112)
		(drill 0.4064)
		(layers "F.Cu" "B.Cu")
		(net "P5VC")
	)
	(via
		(at 39.751 -140.716)
		(size 0.5588)
		(drill 0.3048)
		(layers "F.Cu" "B.Cu")
		(net "P5VC")
	)
	(via
		(at 44.659042 -329.45578)
		(size 0.7112)
		(drill 0.4064)
		(layers "F.Cu" "B.Cu")
		(net "P5VC")
	)
	(via
		(at 89.153746 -25.5397)
		(size 0.7112)
		(drill 0.4064)
		(layers "F.Cu" "B.Cu")
		(net "P5VC")
	)
	(via
		(at 87.883746 -25.5397)
		(size 0.7112)
		(drill 0.4064)
		(layers "F.Cu" "B.Cu")
		(net "P5VC")
	)
	(via
		(at 16.9926 -480.3902)
		(size 0.7112)
		(drill 0.3556)
		(layers "F.Cu" "B.Cu")
		(net "P5VC")
	)
	(via
		(at 19.921982 -482.60254)
		(size 0.7112)
		(drill 0.4064)
		(layers "F.Cu" "B.Cu")
		(net "P5VC")
	)
	(via
		(at 26.271982 -493.90554)
		(size 0.7112)
		(drill 0.4064)
		(layers "F.Cu" "B.Cu")
		(net "P5VC")
	)
	(via
		(at 54.609746 -235.359702)
		(size 0.7112)
		(drill 0.4064)
		(layers "F.Cu" "B.Cu")
		(net "P5VC")
	)
	(via
		(at 21.081746 -480.4537)
		(size 0.7112)
		(drill 0.4064)
		(layers "F.Cu" "B.Cu")
		(net "P5VC")
	)
	(via
		(at 41.909746 -331.6097)
		(size 0.7112)
		(drill 0.3556)
		(layers "F.Cu" "B.Cu")
		(net "P5VC")
	)
	(via
		(at 47.624746 -135.029702)
		(size 0.7112)
		(drill 0.4064)
		(layers "F.Cu" "B.Cu")
		(net "P5VC")
	)
	(via
		(at 23.876 -478.155)
		(size 0.7112)
		(drill 0.3556)
		(layers "F.Cu" "B.Cu")
		(net "P5VC")
	)
	(via
		(at 49.148746 -139.601702)
		(size 0.7112)
		(drill 0.4064)
		(layers "F.Cu" "B.Cu")
		(net "P5VC")
	)
	(via
		(at 55.752746 -240.947702)
		(size 0.7112)
		(drill 0.4064)
		(layers "F.Cu" "B.Cu")
		(net "P5VC")
	)
	(via
		(at 26.017982 -492.90097)
		(size 0.7112)
		(drill 0.4064)
		(layers "F.Cu" "B.Cu")
		(net "P5VC")
	)
	(via
		(at 57.785 -239.649)
		(size 0.7112)
		(drill 0.3556)
		(layers "F.Cu" "B.Cu")
		(net "P5VC")
	)
	(via
		(at 45.719746 -329.339702)
		(size 0.7112)
		(drill 0.4064)
		(layers "F.Cu" "B.Cu")
		(net "P5VC")
	)
	(via
		(at 91.693746 -28.7147)
		(size 0.7112)
		(drill 0.4064)
		(layers "F.Cu" "B.Cu")
		(net "P5VC")
	)
	(via
		(at 58.927746 -47.5107)
		(size 0.7112)
		(drill 0.4064)
		(layers "F.Cu" "B.Cu")
		(net "P5VC")
	)
	(via
		(at 20.573746 -466.4837)
		(size 0.5588)
		(drill 0.3048)
		(layers "F.Cu" "B.Cu")
		(net "P5VC")
	)
	(via
		(at 20.065746 -480.4537)
		(size 0.7112)
		(drill 0.4064)
		(layers "F.Cu" "B.Cu")
		(net "P5VC")
	)
	(via
		(at 57.784746 -48.7807)
		(size 0.7112)
		(drill 0.4064)
		(layers "F.Cu" "B.Cu")
		(net "P5VC")
	)
	(via
		(at 26.5684 -249.047)
		(size 0.5588)
		(drill 0.3048)
		(layers "F.Cu" "B.Cu")
		(net "P5VC")
	)
	(via
		(at 42.544746 -435.384702)
		(size 0.7112)
		(drill 0.4064)
		(layers "F.Cu" "B.Cu")
		(net "P5VC")
	)
	(via
		(at 21.208746 -481.5967)
		(size 0.7112)
		(drill 0.4064)
		(layers "F.Cu" "B.Cu")
		(net "P5VC")
	)
	(via
		(at 89.407746 -28.7147)
		(size 0.7112)
		(drill 0.4064)
		(layers "F.Cu" "B.Cu")
		(net "P5VC")
	)
	(via
		(at 44.576746 -330.736702)
		(size 0.7112)
		(drill 0.4064)
		(layers "F.Cu" "B.Cu")
		(net "P5VC")
	)
	(via
		(at 44.576746 -331.752702)
		(size 0.7112)
		(drill 0.4064)
		(layers "F.Cu" "B.Cu")
		(net "P5VC")
	)
	(via
		(at 54.609746 -238.661702)
		(size 0.7112)
		(drill 0.4064)
		(layers "F.Cu" "B.Cu")
		(net "P5VC")
	)
	(via
		(at 24.891746 -50.5587)
		(size 0.7112)
		(drill 0.4064)
		(layers "F.Cu" "B.Cu")
		(net "P5VC")
	)
	(via
		(at 48.005746 -138.585702)
		(size 0.7112)
		(drill 0.4064)
		(layers "F.Cu" "B.Cu")
		(net "P5VC")
	)
	(via
		(at 58.927746 -48.7807)
		(size 0.7112)
		(drill 0.4064)
		(layers "F.Cu" "B.Cu")
		(net "P5VC")
	)
	(via
		(at 31.369 -345.5162)
		(size 0.7112)
		(drill 0.4064)
		(layers "F.Cu" "B.Cu")
		(net "P5VC")
	)
	(via
		(at 25.145746 -493.9157)
		(size 0.7112)
		(drill 0.4064)
		(layers "F.Cu" "B.Cu")
		(net "P5VC")
	)
	(via
		(at 54.609746 -239.804702)
		(size 0.7112)
		(drill 0.4064)
		(layers "F.Cu" "B.Cu")
		(net "P5VC")
	)
	(via
		(at 42.671746 -438.559702)
		(size 0.7112)
		(drill 0.4064)
		(layers "F.Cu" "B.Cu")
		(net "P5VC")
	)
	(via
		(at 58.927746 -45.2247)
		(size 0.7112)
		(drill 0.4064)
		(layers "F.Cu" "B.Cu")
		(net "P5VC")
	)
	(via
		(at 45.719746 -330.5937)
		(size 0.7112)
		(drill 0.4064)
		(layers "F.Cu" "B.Cu")
		(net "P5VC")
	)
	(via
		(at 55.752746 -235.359702)
		(size 0.7112)
		(drill 0.4064)
		(layers "F.Cu" "B.Cu")
		(net "P5VC")
	)
	(via
		(at 20.065746 -481.5967)
		(size 0.7112)
		(drill 0.4064)
		(layers "F.Cu" "B.Cu")
		(net "P5VC")
	)
	(via
		(at 48.005746 -139.601702)
		(size 0.7112)
		(drill 0.4064)
		(layers "F.Cu" "B.Cu")
		(net "P5VC")
	)
	(via
		(at 90.423746 -25.5397)
		(size 0.7112)
		(drill 0.4064)
		(layers "F.Cu" "B.Cu")
		(net "P5VC")
	)
	(via
		(at 91.693746 -25.5397)
		(size 0.7112)
		(drill 0.4064)
		(layers "F.Cu" "B.Cu")
		(net "P5VC")
	)
	(via
		(at 50.7492 -138.7094)
		(size 0.7112)
		(drill 0.3556)
		(layers "F.Cu" "B.Cu")
		(net "P5VC")
	)
	(via
		(at 17.018 -256.921)
		(size 0.7112)
		(drill 0.4064)
		(layers "F.Cu" "B.Cu")
		(net "P5VC")
	)
	(via
		(at 57.911746 -47.5107)
		(size 0.7112)
		(drill 0.4064)
		(layers "F.Cu" "B.Cu")
		(net "P5VC")
	)
	(via
		(at 90.550746 -28.7147)
		(size 0.7112)
		(drill 0.4064)
		(layers "F.Cu" "B.Cu")
		(net "P5VC")
	)
	(via
		(at 11.048746 -167.0177)
		(size 0.7112)
		(drill 0.4064)
		(layers "F.Cu" "B.Cu")
		(net "P5VC")
	)
	(via
		(at 40.258746 -439.1787)
		(size 0.7112)
		(drill 0.3556)
		(layers "F.Cu" "B.Cu")
		(net "P5VC")
	)
	(via
		(at 6.79831 -488.17403)
		(size 0.5588)
		(drill 0.3048)
		(layers "F.Cu" "B.Cu")
		(net "P5VC")
	)
	(via
		(at 45.9994 -427.4058)
		(size 0.5588)
		(drill 0.3048)
		(layers "F.Cu" "B.Cu")
		(net "P5VC")
	)
	(via
		(at 47.624746 -136.172702)
		(size 0.7112)
		(drill 0.4064)
		(layers "F.Cu" "B.Cu")
		(net "P5VC")
	)
	(via
		(at 88.264746 -28.7147)
		(size 0.7112)
		(drill 0.4064)
		(layers "F.Cu" "B.Cu")
		(net "P5VC")
	)
	(via
		(at 37.598096 -338.71535)
		(size 0.5588)
		(drill 0.3048)
		(layers "F.Cu" "B.Cu")
		(net "P5VC")
	)
	(via
		(at 21.335746 -482.6127)
		(size 0.7112)
		(drill 0.4064)
		(layers "F.Cu" "B.Cu")
		(net "P5VC")
	)
	(via
		(at 12.191746 -480.3267)
		(size 0.7112)
		(drill 0.3556)
		(layers "F.Cu" "B.Cu")
		(net "P5VC")
	)
	(via
		(at 82.880454 -448.57162)
		(size 0.7112)
		(drill 0.4064)
		(layers "F.Cu" "B.Cu")
		(net "P5VC")
	)
	(via
		(at 57.911746 -45.2247)
		(size 0.7112)
		(drill 0.4064)
		(layers "F.Cu" "B.Cu")
		(net "P5VC")
	)
	(via
		(at 42.036746 -439.575702)
		(size 0.7112)
		(drill 0.4064)
		(layers "F.Cu" "B.Cu")
		(net "P5VC")
	)
	(via
		(at 54.609746 -240.947702)
		(size 0.7112)
		(drill 0.4064)
		(layers "F.Cu" "B.Cu")
		(net "P5VC")
	)
	(via
		(at 41.528746 -438.559702)
		(size 0.7112)
		(drill 0.4064)
		(layers "F.Cu" "B.Cu")
		(net "P5VC")
	)
	(via
		(at 29.2354 -490.728)
		(size 0.7112)
		(drill 0.3556)
		(layers "F.Cu" "B.Cu")
		(net "P5VC")
	)
	(via
		(at 25.001982 -492.88954)
		(size 0.7112)
		(drill 0.4064)
		(layers "F.Cu" "B.Cu")
		(net "P5VC")
	)
	(via
		(at 55.752746 -238.661702)
		(size 0.7112)
		(drill 0.4064)
		(layers "F.Cu" "B.Cu")
		(net "P5VC")
	)
	(via
		(at 55.752746 -239.728502)
		(size 0.7112)
		(drill 0.4064)
		(layers "F.Cu" "B.Cu")
		(net "P5VC")
	)
	(via
		(at 45.719746 -331.7367)
		(size 0.7112)
		(drill 0.4064)
		(layers "F.Cu" "B.Cu")
		(net "P5VC")
	)
	(via
		(at 39.623746 -45.9867)
		(size 0.7112)
		(drill 0.4064)
		(layers "F.Cu" "B.Cu")
		(net "P5VC")
	)
	(via
		(at 49.275746 -138.5697)
		(size 0.7112)
		(drill 0.4064)
		(layers "F.Cu" "B.Cu")
		(net "P5VC")
	)
	(via
		(at 20.065746 -483.6287)
		(size 0.7112)
		(drill 0.4064)
		(layers "F.Cu" "B.Cu")
		(net "P5VC")
	)
	(via
		(at 44.576746 -328.3077)
		(size 0.7112)
		(drill 0.4064)
		(layers "F.Cu" "B.Cu")
		(net "P5VC")
	)
	(segment
		(start 8.88238 -486.807764)
		(end 8.88238 -482.860604)
		(width 0.508)
		(layer "B.Cu")
		(net "P5VC")
	)
	(segment
		(start 24.891746 -50.5587)
		(end 31.241746 -50.5587)
		(width 1.016)
		(layer "B.Cu")
		(net "P5VC")
	)
	(segment
		(start 19.837146 -253.840742)
		(end 24.630888 -249.047)
		(width 0.508)
		(layer "B.Cu")
		(net "P5VC")
	)
	(segment
		(start 14.731746 -480.3267)
		(end 12.191746 -480.3267)
		(width 0.508)
		(layer "B.Cu")
		(net "P5VC")
	)
	(segment
		(start 24.630888 -249.047)
		(end 26.5684 -249.047)
		(width 0.508)
		(layer "B.Cu")
		(net "P5VC")
	)
	(segment
		(start 17.018 -256.921)
		(end 17.071594 -256.921)
		(width 0.508)
		(layer "B.Cu")
		(net "P5VC")
	)
	(segment
		(start 17.071594 -256.921)
		(end 19.837146 -254.155448)
		(width 0.508)
		(layer "B.Cu")
		(net "P5VC")
	)
	(segment
		(start 31.241746 -50.5587)
		(end 35.813746 -45.9867)
		(width 1.016)
		(layer "B.Cu")
		(net "P5VC")
	)
	(segment
		(start 8.88238 -482.860604)
		(end 11.416284 -480.3267)
		(width 0.508)
		(layer "B.Cu")
		(net "P5VC")
	)
	(segment
		(start 11.416284 -480.3267)
		(end 12.191746 -480.3267)
		(width 0.508)
		(layer "B.Cu")
		(net "P5VC")
	)
	(segment
		(start 19.837146 -254.155448)
		(end 19.837146 -253.840742)
		(width 0.508)
		(layer "B.Cu")
		(net "P5VC")
	)
	(segment
		(start 7.516114 -488.17403)
		(end 8.88238 -486.807764)
		(width 0.508)
		(layer "B.Cu")
		(net "P5VC")
	)
	(segment
		(start 6.79831 -488.17403)
		(end 7.516114 -488.17403)
		(width 0.508)
		(layer "B.Cu")
		(net "P5VC")
	)
	(segment
		(start 35.813746 -45.9867)
		(end 39.623746 -45.9867)
		(width 1.016)
		(layer "B.Cu")
		(net "P5VC")
	)
	(segment
		(start 35.179 -346.329)
		(end 35.941 -345.567)
		(width 0.762)
		(layer "In2.Cu")
		(net "P5VC")
	)
	(segment
		(start 43.814746 -435.3687)
		(end 45.9994 -433.184046)
		(width 0.508)
		(layer "In2.Cu")
		(net "P5VC")
	)
	(segment
		(start 32.2072 -345.5162)
		(end 33.02 -346.329)
		(width 0.762)
		(layer "In2.Cu")
		(net "P5VC")
	)
	(segment
		(start 45.9994 -433.184046)
		(end 45.9994 -427.4058)
		(width 0.508)
		(layer "In2.Cu")
		(net "P5VC")
	)
	(segment
		(start 31.369 -345.5162)
		(end 32.2072 -345.5162)
		(width 0.762)
		(layer "In2.Cu")
		(net "P5VC")
	)
	(segment
		(start 33.02 -346.329)
		(end 35.179 -346.329)
		(width 0.762)
		(layer "In2.Cu")
		(net "P5VC")
	)
	(segment
		(start 35.941 -345.567)
		(end 35.941 -340.372446)
		(width 0.762)
		(layer "In2.Cu")
		(net "P5VC")
	)
	(segment
		(start 35.941 -340.372446)
		(end 37.598096 -338.71535)
		(width 0.762)
		(layer "In2.Cu")
		(net "P5VC")
	)
	(segment
		(start 41.147746 -195.0847)
		(end 13.080746 -167.0177)
		(width 1.016)
		(layer "In5.Cu")
		(net "P5VC")
	)
	(segment
		(start 35.8648 -241.5032)
		(end 39.243762 -241.5032)
		(width 0.508)
		(layer "In5.Cu")
		(net "P5VC")
	)
	(segment
		(start 42.687748 -333.6417)
		(end 44.576746 -331.752702)
		(width 1.016)
		(layer "In5.Cu")
		(net "P5VC")
	)
	(segment
		(start 13.080746 -167.0177)
		(end 11.048746 -167.0177)
		(width 1.016)
		(layer "In5.Cu")
		(net "P5VC")
	)
	(segment
		(start 42.671746 -333.6417)
		(end 42.687748 -333.6417)
		(width 1.016)
		(layer "In5.Cu")
		(net "P5VC")
	)
	(segment
		(start 39.243762 -241.5032)
		(end 40.433244 -240.313718)
		(width 0.508)
		(layer "In5.Cu")
		(net "P5VC")
	)
	(segment
		(start 26.5684 -249.047)
		(end 28.321 -249.047)
		(width 0.508)
		(layer "In5.Cu")
		(net "P5VC")
	)
	(segment
		(start 28.321 -249.047)
		(end 35.8648 -241.5032)
		(width 0.508)
		(layer "In5.Cu")
		(net "P5VC")
	)
	(segment
		(start 37.598096 -338.71535)
		(end 42.671746 -333.6417)
		(width 1.016)
		(layer "In5.Cu")
		(net "P5VC")
	)
	(segment
		(start 44.830746 -252.983746)
		(end 44.879514 -252.983746)
		(width 0.5588)
		(layer "F.Cu")
		(net "P5VB")
	)
	(segment
		(start 47.370746 -456.4507)
		(end 75.564746 -456.4507)
		(width 0.508)
		(layer "F.Cu")
		(net "P5VB")
	)
	(segment
		(start 64.593978 -277.065232)
		(end 68.198746 -280.67)
		(width 0.5588)
		(layer "F.Cu")
		(net "P5VB")
	)
	(segment
		(start 67.1322 -281.300174)
		(end 62.565026 -276.733)
		(width 0.4064)
		(layer "F.Cu")
		(net "P5VB")
	)
	(segment
		(start 44.691046 -42.1894)
		(end 44.12361 -42.1894)
		(width 0.508)
		(layer "F.Cu")
		(net "P5VB")
	)
	(segment
		(start 85.089746 -456.4507)
		(end 75.564746 -456.4507)
		(width 0.508)
		(layer "F.Cu")
		(net "P5VB")
	)
	(segment
		(start 67.1322 -286.291528)
		(end 67.1322 -281.300174)
		(width 0.4064)
		(layer "F.Cu")
		(net "P5VB")
	)
	(segment
		(start 44.12361 -42.1894)
		(end 44.069 -42.24401)
		(width 0.508)
		(layer "F.Cu")
		(net "P5VB")
	)
	(segment
		(start 63.3984 -477.464374)
		(end 61.447426 -475.5134)
		(width 0.4064)
		(layer "F.Cu")
		(net "P5VB")
	)
	(segment
		(start 68.198746 -284.733746)
		(end 71.755 -288.29)
		(width 0.5588)
		(layer "F.Cu")
		(net "P5VB")
	)
	(segment
		(start 64.593978 -272.69821)
		(end 64.593978 -277.065232)
		(width 0.5588)
		(layer "F.Cu")
		(net "P5VB")
	)
	(segment
		(start 50.418746 -151.7142)
		(end 89.026746 -151.7142)
		(width 0.5588)
		(layer "F.Cu")
		(net "P5VB")
	)
	(segment
		(start 68.453 -287.612328)
		(end 67.1322 -286.291528)
		(width 0.4064)
		(layer "F.Cu")
		(net "P5VB")
	)
	(segment
		(start 60.4393 -276.266656)
		(end 60.4393 -274.5867)
		(width 0.4064)
		(layer "F.Cu")
		(net "P5VB")
	)
	(segment
		(start 61.447426 -475.5134)
		(end 55.9816 -475.5134)
		(width 0.4064)
		(layer "F.Cu")
		(net "P5VB")
	)
	(segment
		(start 44.830746 -248.0437)
		(end 44.830746 -252.983746)
		(width 0.5588)
		(layer "F.Cu")
		(net "P5VB")
	)
	(segment
		(start 68.198746 -280.67)
		(end 68.198746 -284.733746)
		(width 0.5588)
		(layer "F.Cu")
		(net "P5VB")
	)
	(segment
		(start 62.565026 -276.733)
		(end 60.905644 -276.733)
		(width 0.4064)
		(layer "F.Cu")
		(net "P5VB")
	)
	(segment
		(start 60.4393 -274.5867)
		(end 61.468 -273.558)
		(width 0.4064)
		(layer "F.Cu")
		(net "P5VB")
	)
	(segment
		(start 44.879514 -252.983746)
		(end 64.593978 -272.69821)
		(width 0.5588)
		(layer "F.Cu")
		(net "P5VB")
	)
	(segment
		(start 45.037756 -454.11771)
		(end 47.370746 -456.4507)
		(width 0.508)
		(layer "F.Cu")
		(net "P5VB")
	)
	(segment
		(start 68.453 -288.417)
		(end 68.453 -287.612328)
		(width 0.4064)
		(layer "F.Cu")
		(net "P5VB")
	)
	(segment
		(start 61.468 -273.558)
		(end 61.468 -272.82648)
		(width 0.4064)
		(layer "F.Cu")
		(net "P5VB")
	)
	(segment
		(start 44.894246 -146.1897)
		(end 50.418746 -151.7142)
		(width 0.5588)
		(layer "F.Cu")
		(net "P5VB")
	)
	(segment
		(start 48.577246 -350.7867)
		(end 48.577246 -351.218246)
		(width 0.508)
		(layer "F.Cu")
		(net "P5VB")
	)
	(segment
		(start 58.17235 -373.780304)
		(end 58.595006 -374.20296)
		(width 0.4064)
		(layer "F.Cu")
		(net "P5VB")
	)
	(segment
		(start 44.894246 -41.9862)
		(end 44.691046 -42.1894)
		(width 0.508)
		(layer "F.Cu")
		(net "P5VB")
	)
	(segment
		(start 62.77864 -69.8754)
		(end 63.5762 -69.8754)
		(width 0.4064)
		(layer "F.Cu")
		(net "P5VB")
	)
	(segment
		(start 48.577246 -351.218246)
		(end 49.3268 -351.9678)
		(width 0.508)
		(layer "F.Cu")
		(net "P5VB")
	)
	(segment
		(start 63.3984 -481.7872)
		(end 63.3984 -477.464374)
		(width 0.4064)
		(layer "F.Cu")
		(net "P5VB")
	)
	(segment
		(start 55.9816 -475.5134)
		(end 55.3974 -476.0976)
		(width 0.4064)
		(layer "F.Cu")
		(net "P5VB")
	)
	(segment
		(start 44.894246 -41.9227)
		(end 44.894246 -41.9862)
		(width 0.508)
		(layer "F.Cu")
		(net "P5VB")
	)
	(segment
		(start 58.595006 -374.20296)
		(end 59.3344 -374.20296)
		(width 0.4064)
		(layer "F.Cu")
		(net "P5VB")
	)
	(segment
		(start 43.179746 -22.9997)
		(end 43.185334 -23.005288)
		(width 0.508)
		(layer "F.Cu")
		(net "P5VB")
	)
	(segment
		(start 45.037756 -453.799702)
		(end 45.037756 -454.11771)
		(width 0.508)
		(layer "F.Cu")
		(net "P5VB")
	)
	(segment
		(start 162.508946 -453.298052)
		(end 138.2522 -453.298052)
		(width 0.508)
		(layer "F.Cu")
		(net "P5VB")
	)
	(segment
		(start 55.3974 -476.0976)
		(end 55.3974 -476.97136)
		(width 0.4064)
		(layer "F.Cu")
		(net "P5VB")
	)
	(segment
		(start 62.62624 -173.355)
		(end 63.4238 -173.355)
		(width 0.4064)
		(layer "F.Cu")
		(net "P5VB")
	)
	(segment
		(start 49.3268 -351.9678)
		(end 49.4538 -351.9678)
		(width 0.508)
		(layer "F.Cu")
		(net "P5VB")
	)
	(segment
		(start 163.588446 -454.377552)
		(end 162.508946 -453.298052)
		(width 0.508)
		(layer "F.Cu")
		(net "P5VB")
	)
	(segment
		(start 43.185334 -23.005288)
		(end 45.573188 -23.005288)
		(width 0.508)
		(layer "F.Cu")
		(net "P5VB")
	)
	(segment
		(start 44.894246 -145.3007)
		(end 44.894246 -146.1897)
		(width 0.5588)
		(layer "F.Cu")
		(net "P5VB")
	)
	(segment
		(start 163.588446 -455.392536)
		(end 163.588446 -454.377552)
		(width 0.508)
		(layer "F.Cu")
		(net "P5VB")
	)
	(segment
		(start 60.905644 -276.733)
		(end 60.4393 -276.266656)
		(width 0.4064)
		(layer "F.Cu")
		(net "P5VB")
	)
	(via
		(at 56.649366 -372.25732)
		(size 0.7112)
		(drill 0.3556)
		(layers "F.Cu" "B.Cu")
		(net "P5VB")
	)
	(via
		(at 44.069 -42.24401)
		(size 0.5588)
		(drill 0.3048)
		(layers "F.Cu" "B.Cu")
		(net "P5VB")
	)
	(via
		(at 71.119492 -74.958956)
		(size 0.7112)
		(drill 0.4064)
		(layers "F.Cu" "B.Cu")
		(net "P5VB")
	)
	(via
		(at 70.88505 -387.593078)
		(size 0.7112)
		(drill 0.4064)
		(layers "F.Cu" "B.Cu")
		(net "P5VB")
	)
	(via
		(at 67.055746 -292.8747)
		(size 0.7112)
		(drill 0.4064)
		(layers "F.Cu" "B.Cu")
		(net "P5VB")
	)
	(via
		(at 63.5762 -69.8754)
		(size 0.5588)
		(drill 0.3048)
		(layers "F.Cu" "B.Cu")
		(net "P5VB")
	)
	(via
		(at 68.198746 -180.7337)
		(size 0.7112)
		(drill 0.4064)
		(layers "F.Cu" "B.Cu")
		(net "P5VB")
	)
	(via
		(at 71.627746 -487.3117)
		(size 0.7112)
		(drill 0.4064)
		(layers "F.Cu" "B.Cu")
		(net "P5VB")
	)
	(via
		(at 66.039746 -292.859968)
		(size 0.7112)
		(drill 0.4064)
		(layers "F.Cu" "B.Cu")
		(net "P5VB")
	)
	(via
		(at 89.026746 -151.7142)
		(size 0.5588)
		(drill 0.3048)
		(layers "F.Cu" "B.Cu")
		(net "P5VB")
	)
	(via
		(at 85.089746 -456.4507)
		(size 0.7112)
		(drill 0.4064)
		(layers "F.Cu" "B.Cu")
		(net "P5VB")
	)
	(via
		(at 63.7032 -296.3418)
		(size 0.7112)
		(drill 0.3556)
		(layers "F.Cu" "B.Cu")
		(net "P5VB")
	)
	(via
		(at 71.229982 -181.25186)
		(size 0.7112)
		(drill 0.4064)
		(layers "F.Cu" "B.Cu")
		(net "P5VB")
	)
	(via
		(at 68.198746 -182.0037)
		(size 0.7112)
		(drill 0.4064)
		(layers "F.Cu" "B.Cu")
		(net "P5VB")
	)
	(via
		(at 70.993 -386.334)
		(size 0.7112)
		(drill 0.3556)
		(layers "F.Cu" "B.Cu")
		(net "P5VB")
	)
	(via
		(at 42.417746 -22.3647)
		(size 0.7112)
		(drill 0.4064)
		(layers "F.Cu" "B.Cu")
		(net "P5VB")
	)
	(via
		(at 33.019746 -19.8247)
		(size 0.7112)
		(drill 0.4064)
		(layers "F.Cu" "B.Cu")
		(net "P5VB")
	)
	(via
		(at 67.817746 -489.9787)
		(size 0.7112)
		(drill 0.4064)
		(layers "F.Cu" "B.Cu")
		(net "P5VB")
	)
	(via
		(at 58.17235 -373.780304)
		(size 0.5588)
		(drill 0.3048)
		(layers "F.Cu" "B.Cu")
		(net "P5VB")
	)
	(via
		(at 71.627746 -489.8517)
		(size 0.7112)
		(drill 0.4064)
		(layers "F.Cu" "B.Cu")
		(net "P5VB")
	)
	(via
		(at 66.928746 -295.0337)
		(size 0.7112)
		(drill 0.4064)
		(layers "F.Cu" "B.Cu")
		(net "P5VB")
	)
	(via
		(at 72.135746 -179.9717)
		(size 0.7112)
		(drill 0.3556)
		(layers "F.Cu" "B.Cu")
		(net "P5VB")
	)
	(via
		(at 42.290746 -20.0787)
		(size 0.7112)
		(drill 0.4064)
		(layers "F.Cu" "B.Cu")
		(net "P5VB")
	)
	(via
		(at 42.290746 -21.2217)
		(size 0.7112)
		(drill 0.4064)
		(layers "F.Cu" "B.Cu")
		(net "P5VB")
	)
	(via
		(at 75.564746 -456.4507)
		(size 0.7112)
		(drill 0.3556)
		(layers "F.Cu" "B.Cu")
		(net "P5VB")
	)
	(via
		(at 67.944492 -76.228956)
		(size 0.7112)
		(drill 0.4064)
		(layers "F.Cu" "B.Cu")
		(net "P5VB")
	)
	(via
		(at 68.453 -288.417)
		(size 0.5588)
		(drill 0.3048)
		(layers "F.Cu" "B.Cu")
		(net "P5VB")
	)
	(via
		(at 40.258746 -22.4917)
		(size 0.7112)
		(drill 0.4064)
		(layers "F.Cu" "B.Cu")
		(net "P5VB")
	)
	(via
		(at 65.912746 -295.0337)
		(size 0.7112)
		(drill 0.4064)
		(layers "F.Cu" "B.Cu")
		(net "P5VB")
	)
	(via
		(at 69.214746 -292.8747)
		(size 0.7112)
		(drill 0.4064)
		(layers "F.Cu" "B.Cu")
		(net "P5VB")
	)
	(via
		(at 71.119492 -78.387956)
		(size 0.7112)
		(drill 0.4064)
		(layers "F.Cu" "B.Cu")
		(net "P5VB")
	)
	(via
		(at 67.817746 -491.1217)
		(size 0.7112)
		(drill 0.4064)
		(layers "F.Cu" "B.Cu")
		(net "P5VB")
	)
	(via
		(at 68.198746 -179.4637)
		(size 0.7112)
		(drill 0.4064)
		(layers "F.Cu" "B.Cu")
		(net "P5VB")
	)
	(via
		(at 40.258746 -23.7617)
		(size 0.7112)
		(drill 0.4064)
		(layers "F.Cu" "B.Cu")
		(net "P5VB")
	)
	(via
		(at 68.198746 -178.1937)
		(size 0.7112)
		(drill 0.4064)
		(layers "F.Cu" "B.Cu")
		(net "P5VB")
	)
	(via
		(at 34.671 -23.4696)
		(size 0.7112)
		(drill 0.3556)
		(layers "F.Cu" "B.Cu")
		(net "P5VB")
	)
	(via
		(at 71.373746 -178.1937)
		(size 0.7112)
		(drill 0.4064)
		(layers "F.Cu" "B.Cu")
		(net "P5VB")
	)
	(via
		(at 40.258746 -20.0787)
		(size 0.7112)
		(drill 0.4064)
		(layers "F.Cu" "B.Cu")
		(net "P5VB")
	)
	(via
		(at 69.087746 -295.0337)
		(size 0.7112)
		(drill 0.4064)
		(layers "F.Cu" "B.Cu")
		(net "P5VB")
	)
	(via
		(at 70.992746 -383.6797)
		(size 0.7112)
		(drill 0.4064)
		(layers "F.Cu" "B.Cu")
		(net "P5VB")
	)
	(via
		(at 42.036746 -26.9367)
		(size 0.7112)
		(drill 0.4064)
		(layers "F.Cu" "B.Cu")
		(net "P5VB")
	)
	(via
		(at 43.179746 -26.1747)
		(size 0.7112)
		(drill 0.4064)
		(layers "F.Cu" "B.Cu")
		(net "P5VB")
	)
	(via
		(at 40.258746 -21.3487)
		(size 0.7112)
		(drill 0.4064)
		(layers "F.Cu" "B.Cu")
		(net "P5VB")
	)
	(via
		(at 71.119492 -77.244956)
		(size 0.7112)
		(drill 0.4064)
		(layers "F.Cu" "B.Cu")
		(net "P5VB")
	)
	(via
		(at 70.756018 -388.60095)
		(size 0.7112)
		(drill 0.4064)
		(layers "F.Cu" "B.Cu")
		(net "P5VB")
	)
	(via
		(at 67.906646 -387.901688)
		(size 0.7112)
		(drill 0.4064)
		(layers "F.Cu" "B.Cu")
		(net "P5VB")
	)
	(via
		(at 32.511746 -25.2857)
		(size 0.7112)
		(drill 0.4064)
		(layers "F.Cu" "B.Cu")
		(net "P5VB")
	)
	(via
		(at 71.755 -288.29)
		(size 0.5588)
		(drill 0.3048)
		(layers "F.Cu" "B.Cu")
		(net "P5VB")
	)
	(via
		(at 42.417746 -23.5077)
		(size 0.7112)
		(drill 0.4064)
		(layers "F.Cu" "B.Cu")
		(net "P5VB")
	)
	(via
		(at 37.465 -27.9146)
		(size 0.7112)
		(drill 0.3556)
		(layers "F.Cu" "B.Cu")
		(net "P5VB")
	)
	(via
		(at 67.906646 -385.6101)
		(size 0.7112)
		(drill 0.4064)
		(layers "F.Cu" "B.Cu")
		(net "P5VB")
	)
	(via
		(at 67.817746 -488.8357)
		(size 0.7112)
		(drill 0.4064)
		(layers "F.Cu" "B.Cu")
		(net "P5VB")
	)
	(via
		(at 67.944492 -74.958956)
		(size 0.7112)
		(drill 0.4064)
		(layers "F.Cu" "B.Cu")
		(net "P5VB")
	)
	(via
		(at 49.4538 -351.9678)
		(size 0.5588)
		(drill 0.3048)
		(layers "F.Cu" "B.Cu")
		(net "P5VB")
	)
	(via
		(at 68.198746 -292.8747)
		(size 0.7112)
		(drill 0.4064)
		(layers "F.Cu" "B.Cu")
		(net "P5VB")
	)
	(via
		(at 63.4238 -173.355)
		(size 0.5588)
		(drill 0.3048)
		(layers "F.Cu" "B.Cu")
		(net "P5VB")
	)
	(via
		(at 71.119492 -76.101956)
		(size 0.7112)
		(drill 0.4064)
		(layers "F.Cu" "B.Cu")
		(net "P5VB")
	)
	(via
		(at 71.373746 -182.2577)
		(size 0.7112)
		(drill 0.4064)
		(layers "F.Cu" "B.Cu")
		(net "P5VB")
	)
	(via
		(at 63.3984 -481.7872)
		(size 0.5588)
		(drill 0.3048)
		(layers "F.Cu" "B.Cu")
		(net "P5VB")
	)
	(via
		(at 66.293746 -381.9017)
		(size 0.7112)
		(drill 0.4064)
		(layers "F.Cu" "B.Cu")
		(net "P5VB")
	)
	(via
		(at 67.817746 -486.5497)
		(size 0.7112)
		(drill 0.4064)
		(layers "F.Cu" "B.Cu")
		(net "P5VB")
	)
	(via
		(at 71.627746 -488.5817)
		(size 0.7112)
		(drill 0.4064)
		(layers "F.Cu" "B.Cu")
		(net "P5VB")
	)
	(via
		(at 68.071746 -295.0337)
		(size 0.7112)
		(drill 0.4064)
		(layers "F.Cu" "B.Cu")
		(net "P5VB")
	)
	(via
		(at 67.817746 -487.6927)
		(size 0.7112)
		(drill 0.4064)
		(layers "F.Cu" "B.Cu")
		(net "P5VB")
	)
	(via
		(at 70.992746 -384.8227)
		(size 0.7112)
		(drill 0.4064)
		(layers "F.Cu" "B.Cu")
		(net "P5VB")
	)
	(via
		(at 67.817746 -384.1877)
		(size 0.7112)
		(drill 0.4064)
		(layers "F.Cu" "B.Cu")
		(net "P5VB")
	)
	(via
		(at 67.944492 -77.498956)
		(size 0.7112)
		(drill 0.4064)
		(layers "F.Cu" "B.Cu")
		(net "P5VB")
	)
	(via
		(at 67.944492 -78.768956)
		(size 0.7112)
		(drill 0.4064)
		(layers "F.Cu" "B.Cu")
		(net "P5VB")
	)
	(via
		(at 67.906646 -386.7277)
		(size 0.7112)
		(drill 0.4064)
		(layers "F.Cu" "B.Cu")
		(net "P5VB")
	)
	(via
		(at 71.373746 -179.2097)
		(size 0.7112)
		(drill 0.4064)
		(layers "F.Cu" "B.Cu")
		(net "P5VB")
	)
	(via
		(at 138.2522 -453.298052)
		(size 0.7112)
		(drill 0.4064)
		(layers "F.Cu" "B.Cu")
		(net "P5VB")
	)
	(via
		(at 42.417746 -24.6507)
		(size 0.7112)
		(drill 0.4064)
		(layers "F.Cu" "B.Cu")
		(net "P5VB")
	)
	(segment
		(start 49.314354 -351.9678)
		(end 49.021746 -352.260408)
		(width 1.016)
		(layer "B.Cu")
		(net "P5VB")
	)
	(segment
		(start 49.021746 -352.260408)
		(end 49.021746 -364.6297)
		(width 1.016)
		(layer "B.Cu")
		(net "P5VB")
	)
	(segment
		(start 58.17235 -373.780304)
		(end 66.293746 -381.9017)
		(width 1.016)
		(layer "B.Cu")
		(net "P5VB")
	)
	(segment
		(start 49.021746 -364.6297)
		(end 56.649366 -372.25732)
		(width 1.016)
		(layer "B.Cu")
		(net "P5VB")
	)
	(segment
		(start 49.4538 -351.9678)
		(end 49.314354 -351.9678)
		(width 1.016)
		(layer "B.Cu")
		(net "P5VB")
	)
	(segment
		(start 56.649366 -372.25732)
		(end 58.17235 -373.780304)
		(width 1.016)
		(layer "B.Cu")
		(net "P5VB")
	)
	(segment
		(start 63.5762 -70.590664)
		(end 63.5762 -69.8754)
		(width 0.508)
		(layer "In2.Cu")
		(net "P5VB")
	)
	(segment
		(start 63.4238 -173.418754)
		(end 63.4238 -173.355)
		(width 0.508)
		(layer "In2.Cu")
		(net "P5VB")
	)
	(segment
		(start 67.944492 -74.958956)
		(end 63.5762 -70.590664)
		(width 0.508)
		(layer "In2.Cu")
		(net "P5VB")
	)
	(segment
		(start 68.198746 -178.1937)
		(end 63.4238 -173.418754)
		(width 0.508)
		(layer "In2.Cu")
		(net "P5VB")
	)
	(segment
		(start 233.806746 -29.9847)
		(end 234.822746 -31.0007)
		(width 0.508)
		(layer "F.Cu")
		(net "P5VA_12VIN")
	)
	(segment
		(start 233.806746 -28.3972)
		(end 233.806746 -29.9847)
		(width 0.508)
		(layer "F.Cu")
		(net "P5VA_12VIN")
	)
	(segment
		(start 234.822746 -31.0007)
		(end 235.457746 -31.0007)
		(width 0.508)
		(layer "F.Cu")
		(net "P5VA_12VIN")
	)
	(via
		(at 239.521746 -15.6337)
		(size 0.7112)
		(drill 0.4064)
		(layers "F.Cu" "B.Cu")
		(net "P5VA_12VIN")
	)
	(via
		(at 235.838746 -15.3797)
		(size 0.7112)
		(drill 0.4064)
		(layers "F.Cu" "B.Cu")
		(net "P5VA_12VIN")
	)
	(via
		(at 239.648746 -13.9827)
		(size 0.7112)
		(drill 0.4064)
		(layers "F.Cu" "B.Cu")
		(net "P5VA_12VIN")
	)
	(via
		(at 239.648746 -19.8247)
		(size 0.7112)
		(drill 0.4064)
		(layers "F.Cu" "B.Cu")
		(net "P5VA_12VIN")
	)
	(via
		(at 235.838746 -13.0937)
		(size 0.7112)
		(drill 0.4064)
		(layers "F.Cu" "B.Cu")
		(net "P5VA_12VIN")
	)
	(via
		(at 236.219746 -8.2677)
		(size 0.7112)
		(drill 0.4064)
		(layers "F.Cu" "B.Cu")
		(net "P5VA_12VIN")
	)
	(via
		(at 238.886746 -8.3947)
		(size 0.7112)
		(drill 0.4064)
		(layers "F.Cu" "B.Cu")
		(net "P5VA_12VIN")
	)
	(via
		(at 237.489746 -17.0307)
		(size 0.7112)
		(drill 0.3556)
		(layers "F.Cu" "B.Cu")
		(net "P5VA_12VIN")
	)
	(via
		(at 235.711746 -9.6647)
		(size 0.7112)
		(drill 0.3556)
		(layers "F.Cu" "B.Cu")
		(net "P5VA_12VIN")
	)
	(via
		(at 239.648746 -20.9677)
		(size 0.5588)
		(drill 0.3048)
		(layers "F.Cu" "B.Cu")
		(net "P5VA_12VIN")
	)
	(via
		(at 239.648746 -18.4277)
		(size 0.7112)
		(drill 0.4064)
		(layers "F.Cu" "B.Cu")
		(net "P5VA_12VIN")
	)
	(via
		(at 240.156746 -8.5217)
		(size 0.7112)
		(drill 0.4064)
		(layers "F.Cu" "B.Cu")
		(net "P5VA_12VIN")
	)
	(via
		(at 244.238272 -28.846018)
		(size 0.7112)
		(drill 0.3556)
		(layers "F.Cu" "B.Cu")
		(net "P5VA_12VIN")
	)
	(via
		(at 235.457746 -31.0007)
		(size 0.5588)
		(drill 0.3048)
		(layers "F.Cu" "B.Cu")
		(net "P5VA_12VIN")
	)
	(via
		(at 239.648746 -12.2047)
		(size 0.7112)
		(drill 0.4064)
		(layers "F.Cu" "B.Cu")
		(net "P5VA_12VIN")
	)
	(via
		(at 235.965746 -14.2367)
		(size 0.7112)
		(drill 0.4064)
		(layers "F.Cu" "B.Cu")
		(net "P5VA_12VIN")
	)
	(via
		(at 241.680746 -20.5867)
		(size 0.7112)
		(drill 0.3556)
		(layers "F.Cu" "B.Cu")
		(net "P5VA_12VIN")
	)
	(via
		(at 241.782346 -11.5697)
		(size 0.7112)
		(drill 0.3556)
		(layers "F.Cu" "B.Cu")
		(net "P5VA_12VIN")
	)
	(via
		(at 239.521746 -16.9037)
		(size 0.7112)
		(drill 0.4064)
		(layers "F.Cu" "B.Cu")
		(net "P5VA_12VIN")
	)
	(via
		(at 235.965746 -16.6497)
		(size 0.7112)
		(drill 0.4064)
		(layers "F.Cu" "B.Cu")
		(net "P5VA_12VIN")
	)
	(segment
		(start 246.049546 -23.4315)
		(end 246.049546 -27.034744)
		(width 0.508)
		(layer "B.Cu")
		(net "P5VA_12VIN")
	)
	(segment
		(start 241.19459 -31.8897)
		(end 244.238272 -28.846018)
		(width 0.508)
		(layer "B.Cu")
		(net "P5VA_12VIN")
	)
	(segment
		(start 235.584746 -31.0007)
		(end 236.473746 -31.8897)
		(width 0.508)
		(layer "B.Cu")
		(net "P5VA_12VIN")
	)
	(segment
		(start 241.045746 -22.3647)
		(end 244.982746 -22.3647)
		(width 0.508)
		(layer "B.Cu")
		(net "P5VA_12VIN")
	)
	(segment
		(start 239.648746 -20.9677)
		(end 241.045746 -22.3647)
		(width 0.508)
		(layer "B.Cu")
		(net "P5VA_12VIN")
	)
	(segment
		(start 235.457746 -31.0007)
		(end 235.584746 -31.0007)
		(width 0.508)
		(layer "B.Cu")
		(net "P5VA_12VIN")
	)
	(segment
		(start 244.982746 -22.3647)
		(end 246.049546 -23.4315)
		(width 0.508)
		(layer "B.Cu")
		(net "P5VA_12VIN")
	)
	(segment
		(start 246.049546 -27.034744)
		(end 244.238272 -28.846018)
		(width 0.508)
		(layer "B.Cu")
		(net "P5VA_12VIN")
	)
	(segment
		(start 236.473746 -31.8897)
		(end 241.19459 -31.8897)
		(width 0.508)
		(layer "B.Cu")
		(net "P5VA_12VIN")
	)
	(segment
		(start 238.124746 -29.3497)
		(end 238.378746 -29.3497)
		(width 0.508)
		(layer "F.Cu")
		(net "P5VA_VREG")
	)
	(segment
		(start 242.239546 -23.7109)
		(end 241.820446 -24.13)
		(width 0.254)
		(layer "F.Cu")
		(net "P5VA_VREG")
	)
	(segment
		(start 241.617246 -24.3967)
		(end 241.299746 -24.0792)
		(width 0.254)
		(layer "F.Cu")
		(net "P5VA_VREG")
	)
	(segment
		(start 237.870746 -28.3972)
		(end 237.870746 -29.0957)
		(width 0.508)
		(layer "F.Cu")
		(net "P5VA_VREG")
	)
	(segment
		(start 241.299746 -24.0792)
		(end 241.299746 -23.1775)
		(width 0.254)
		(layer "F.Cu")
		(net "P5VA_VREG")
	)
	(segment
		(start 241.299746 -23.1775)
		(end 240.352072 -22.229826)
		(width 0.254)
		(layer "F.Cu")
		(net "P5VA_VREG")
	)
	(segment
		(start 231.774746 -28.3972)
		(end 231.774746 -29.3497)
		(width 0.508)
		(layer "F.Cu")
		(net "P5VA_VREG")
	)
	(segment
		(start 244.220746 -23.7109)
		(end 242.239546 -23.7109)
		(width 0.254)
		(layer "F.Cu")
		(net "P5VA_VREG")
	)
	(segment
		(start 241.820446 -24.13)
		(end 241.820446 -24.1935)
		(width 0.254)
		(layer "F.Cu")
		(net "P5VA_VREG")
	)
	(segment
		(start 231.774746 -29.3497)
		(end 234.314746 -31.8897)
		(width 0.508)
		(layer "F.Cu")
		(net "P5VA_VREG")
	)
	(segment
		(start 241.820446 -24.1935)
		(end 241.617246 -24.3967)
		(width 0.254)
		(layer "F.Cu")
		(net "P5VA_VREG")
	)
	(segment
		(start 237.362746 -31.8897)
		(end 238.251746 -31.0007)
		(width 0.508)
		(layer "F.Cu")
		(net "P5VA_VREG")
	)
	(segment
		(start 234.314746 -31.8897)
		(end 237.362746 -31.8897)
		(width 0.508)
		(layer "F.Cu")
		(net "P5VA_VREG")
	)
	(segment
		(start 237.870746 -29.0957)
		(end 238.124746 -29.3497)
		(width 0.508)
		(layer "F.Cu")
		(net "P5VA_VREG")
	)
	(segment
		(start 240.352072 -22.229826)
		(end 238.288068 -22.229826)
		(width 0.254)
		(layer "F.Cu")
		(net "P5VA_VREG")
	)
	(via
		(at 240.156746 -29.6037)
		(size 0.7112)
		(drill 0.3556)
		(layers "F.Cu" "B.Cu")
		(net "P5VA_VREG")
	)
	(via
		(at 238.251746 -31.0007)
		(size 0.5588)
		(drill 0.3048)
		(layers "F.Cu" "B.Cu")
		(net "P5VA_VREG")
	)
	(via
		(at 244.220746 -23.7109)
		(size 0.5588)
		(drill 0.3048)
		(layers "F.Cu" "B.Cu")
		(net "P5VA_VREG")
	)
	(via
		(at 238.378746 -29.3497)
		(size 0.5588)
		(drill 0.3048)
		(layers "F.Cu" "B.Cu")
		(net "P5VA_VREG")
	)
	(segment
		(start 238.378746 -29.3497)
		(end 238.378746 -29.6037)
		(width 0.508)
		(layer "B.Cu")
		(net "P5VA_VREG")
	)
	(segment
		(start 244.5385 -23.7109)
		(end 244.931946 -23.7109)
		(width 0.508)
		(layer "B.Cu")
		(net "P5VA_VREG")
	)
	(segment
		(start 245.236746 -26.5557)
		(end 242.188746 -29.6037)
		(width 0.508)
		(layer "B.Cu")
		(net "P5VA_VREG")
	)
	(segment
		(start 244.931946 -23.7109)
		(end 245.236746 -24.0157)
		(width 0.508)
		(layer "B.Cu")
		(net "P5VA_VREG")
	)
	(segment
		(start 238.632746 -29.6037)
		(end 238.378746 -29.3497)
		(width 0.508)
		(layer "B.Cu")
		(net "P5VA_VREG")
	)
	(segment
		(start 238.378746 -29.6037)
		(end 238.251746 -29.7307)
		(width 0.508)
		(layer "B.Cu")
		(net "P5VA_VREG")
	)
	(segment
		(start 244.5385 -23.7109)
		(end 244.220746 -23.7109)
		(width 0.508)
		(layer "B.Cu")
		(net "P5VA_VREG")
	)
	(segment
		(start 238.251746 -29.7307)
		(end 238.251746 -31.0007)
		(width 0.508)
		(layer "B.Cu")
		(net "P5VA_VREG")
	)
	(segment
		(start 245.236746 -24.0157)
		(end 245.236746 -26.5557)
		(width 0.508)
		(layer "B.Cu")
		(net "P5VA_VREG")
	)
	(segment
		(start 240.156746 -29.6037)
		(end 238.632746 -29.6037)
		(width 0.508)
		(layer "B.Cu")
		(net "P5VA_VREG")
	)
	(segment
		(start 242.188746 -29.6037)
		(end 240.156746 -29.6037)
		(width 0.508)
		(layer "B.Cu")
		(net "P5VA_VREG")
	)
	(segment
		(start 204.978 -272.5166)
		(end 205.62824 -271.86636)
		(width 0.4064)
		(layer "F.Cu")
		(net "P5VA")
	)
	(segment
		(start 242.594892 -411.759908)
		(end 255.474978 -411.759908)
		(width 0.762)
		(layer "F.Cu")
		(net "P5VA")
	)
	(segment
		(start 229.891082 -247.495568)
		(end 229.891082 -247.641364)
		(width 0.508)
		(layer "F.Cu")
		(net "P5VA")
	)
	(segment
		(start 205.62824 -271.86636)
		(end 206.4766 -271.86636)
		(width 0.4064)
		(layer "F.Cu")
		(net "P5VA")
	)
	(segment
		(start 221.868746 -344.5637)
		(end 221.868746 -344.4367)
		(width 0.508)
		(layer "F.Cu")
		(net "P5VA")
	)
	(segment
		(start 232.790746 -43.8277)
		(end 234.251246 -43.8277)
		(width 0.508)
		(layer "F.Cu")
		(net "P5VA")
	)
	(segment
		(start 206.5528 -169.55516)
		(end 205.39964 -169.55516)
		(width 0.4064)
		(layer "F.Cu")
		(net "P5VA")
	)
	(segment
		(start 229.919784 -145.004028)
		(end 229.919784 -145.327624)
		(width 0.508)
		(layer "F.Cu")
		(net "P5VA")
	)
	(segment
		(start 206.9338 -67.29476)
		(end 205.72476 -67.29476)
		(width 0.4064)
		(layer "F.Cu")
		(net "P5VA")
	)
	(segment
		(start 229.822756 -453.545702)
		(end 229.822756 -454.434702)
		(width 0.508)
		(layer "F.Cu")
		(net "P5VA")
	)
	(segment
		(start 229.891082 -247.641364)
		(end 228.853746 -248.6787)
		(width 0.508)
		(layer "F.Cu")
		(net "P5VA")
	)
	(segment
		(start 207.0862 -478.13976)
		(end 205.9686 -478.13976)
		(width 0.4064)
		(layer "F.Cu")
		(net "P5VA")
	)
	(segment
		(start 241.3254 -413.0294)
		(end 242.594892 -411.759908)
		(width 0.762)
		(layer "F.Cu")
		(net "P5VA")
	)
	(segment
		(start 162.572446 -459.075536)
		(end 160.994598 -459.075536)
		(width 0.508)
		(layer "F.Cu")
		(net "P5VA")
	)
	(segment
		(start 229.919784 -145.327624)
		(end 229.615746 -145.631662)
		(width 0.508)
		(layer "F.Cu")
		(net "P5VA")
	)
	(segment
		(start 206.9338 -375.42216)
		(end 205.72984 -375.42216)
		(width 0.4064)
		(layer "F.Cu")
		(net "P5VA")
	)
	(segment
		(start 221.805246 -344.6272)
		(end 221.868746 -344.5637)
		(width 0.508)
		(layer "F.Cu")
		(net "P5VA")
	)
	(segment
		(start 229.615746 -145.631662)
		(end 229.615746 -145.892012)
		(width 0.508)
		(layer "F.Cu")
		(net "P5VA")
	)
	(segment
		(start 221.805246 -345.3257)
		(end 221.805246 -344.6272)
		(width 0.508)
		(layer "F.Cu")
		(net "P5VA")
	)
	(segment
		(start 229.171246 -26.1747)
		(end 227.329746 -26.1747)
		(width 0.508)
		(layer "F.Cu")
		(net "P5VA")
	)
	(via
		(at 205.54823 -381.945388)
		(size 0.7112)
		(drill 0.4064)
		(layers "F.Cu" "B.Cu")
		(net "P5VA")
	)
	(via
		(at 202.183746 -384.5687)
		(size 0.7112)
		(drill 0.4064)
		(layers "F.Cu" "B.Cu")
		(net "P5VA")
	)
	(via
		(at 204.977746 -177.0507)
		(size 0.7112)
		(drill 0.4064)
		(layers "F.Cu" "B.Cu")
		(net "P5VA")
	)
	(via
		(at 194.858386 -455.260456)
		(size 0.7112)
		(drill 0.4064)
		(layers "F.Cu" "B.Cu")
		(net "P5VA")
	)
	(via
		(at 206.120746 -278.6507)
		(size 0.7112)
		(drill 0.4064)
		(layers "F.Cu" "B.Cu")
		(net "P5VA")
	)
	(via
		(at 204.935074 -179.540662)
		(size 0.7112)
		(drill 0.4064)
		(layers "F.Cu" "B.Cu")
		(net "P5VA")
	)
	(via
		(at 205.485746 -76.9747)
		(size 0.7112)
		(drill 0.4064)
		(layers "F.Cu" "B.Cu")
		(net "P5VA")
	)
	(via
		(at 204.978 -272.5166)
		(size 0.5588)
		(drill 0.3048)
		(layers "F.Cu" "B.Cu")
		(net "P5VA")
	)
	(via
		(at 215.391746 -30.3657)
		(size 0.7112)
		(drill 0.3556)
		(layers "F.Cu" "B.Cu")
		(net "P5VA")
	)
	(via
		(at 224.027746 -30.3657)
		(size 0.7112)
		(drill 0.3556)
		(layers "F.Cu" "B.Cu")
		(net "P5VA")
	)
	(via
		(at 205.54823 -385.755388)
		(size 0.7112)
		(drill 0.4064)
		(layers "F.Cu" "B.Cu")
		(net "P5VA")
	)
	(via
		(at 205.580742 -75.583034)
		(size 0.7112)
		(drill 0.4064)
		(layers "F.Cu" "B.Cu")
		(net "P5VA")
	)
	(via
		(at 201.760074 -177.381662)
		(size 0.7112)
		(drill 0.4064)
		(layers "F.Cu" "B.Cu")
		(net "P5VA")
	)
	(via
		(at 222.757746 -20.8407)
		(size 0.7112)
		(drill 0.4064)
		(layers "F.Cu" "B.Cu")
		(net "P5VA")
	)
	(via
		(at 214.883746 -28.2067)
		(size 0.7112)
		(drill 0.4064)
		(layers "F.Cu" "B.Cu")
		(net "P5VA")
	)
	(via
		(at 205.064614 -282.248864)
		(size 0.7112)
		(drill 0.4064)
		(layers "F.Cu" "B.Cu")
		(net "P5VA")
	)
	(via
		(at 202.183746 -385.7117)
		(size 0.7112)
		(drill 0.4064)
		(layers "F.Cu" "B.Cu")
		(net "P5VA")
	)
	(via
		(at 205.104746 -278.6507)
		(size 0.7112)
		(drill 0.4064)
		(layers "F.Cu" "B.Cu")
		(net "P5VA")
	)
	(via
		(at 205.580742 -78.123034)
		(size 0.7112)
		(drill 0.4064)
		(layers "F.Cu" "B.Cu")
		(net "P5VA")
	)
	(via
		(at 222.376746 -31.8897)
		(size 0.7112)
		(drill 0.4064)
		(layers "F.Cu" "B.Cu")
		(net "P5VA")
	)
	(via
		(at 202.405742 -78.123034)
		(size 0.7112)
		(drill 0.4064)
		(layers "F.Cu" "B.Cu")
		(net "P5VA")
	)
	(via
		(at 223.138746 -23.2537)
		(size 0.7112)
		(drill 0.3556)
		(layers "F.Cu" "B.Cu")
		(net "P5VA")
	)
	(via
		(at 205.064614 -283.518864)
		(size 0.7112)
		(drill 0.4064)
		(layers "F.Cu" "B.Cu")
		(net "P5VA")
	)
	(via
		(at 202.405742 -75.837034)
		(size 0.7112)
		(drill 0.4064)
		(layers "F.Cu" "B.Cu")
		(net "P5VA")
	)
	(via
		(at 201.760074 -179.667662)
		(size 0.7112)
		(drill 0.4064)
		(layers "F.Cu" "B.Cu")
		(net "P5VA")
	)
	(via
		(at 226.186746 -26.5557)
		(size 0.7112)
		(drill 0.4064)
		(layers "F.Cu" "B.Cu")
		(net "P5VA")
	)
	(via
		(at 202.405742 -74.694034)
		(size 0.7112)
		(drill 0.4064)
		(layers "F.Cu" "B.Cu")
		(net "P5VA")
	)
	(via
		(at 228.853746 -248.6787)
		(size 0.5588)
		(drill 0.3048)
		(layers "F.Cu" "B.Cu")
		(net "P5VA")
	)
	(via
		(at 205.231238 -488.40771)
		(size 0.7112)
		(drill 0.4064)
		(layers "F.Cu" "B.Cu")
		(net "P5VA")
	)
	(via
		(at 202.056746 -488.2007)
		(size 0.7112)
		(drill 0.4064)
		(layers "F.Cu" "B.Cu")
		(net "P5VA")
	)
	(via
		(at 205.215744 -485.23271)
		(size 0.7112)
		(drill 0.4064)
		(layers "F.Cu" "B.Cu")
		(net "P5VA")
	)
	(via
		(at 205.485746 -384.4417)
		(size 0.7112)
		(drill 0.4064)
		(layers "F.Cu" "B.Cu")
		(net "P5VA")
	)
	(via
		(at 205.72984 -375.42216)
		(size 0.5588)
		(drill 0.3048)
		(layers "F.Cu" "B.Cu")
		(net "P5VA")
	)
	(via
		(at 217.296746 -20.8407)
		(size 0.7112)
		(drill 0.4064)
		(layers "F.Cu" "B.Cu")
		(net "P5VA")
	)
	(via
		(at 201.760074 -178.524662)
		(size 0.7112)
		(drill 0.4064)
		(layers "F.Cu" "B.Cu")
		(net "P5VA")
	)
	(via
		(at 205.215744 -486.37571)
		(size 0.7112)
		(drill 0.4064)
		(layers "F.Cu" "B.Cu")
		(net "P5VA")
	)
	(via
		(at 204.977746 -280.9367)
		(size 0.7112)
		(drill 0.4064)
		(layers "F.Cu" "B.Cu")
		(net "P5VA")
	)
	(via
		(at 201.760074 -180.810662)
		(size 0.7112)
		(drill 0.4064)
		(layers "F.Cu" "B.Cu")
		(net "P5VA")
	)
	(via
		(at 205.064614 -279.708864)
		(size 0.7112)
		(drill 0.4064)
		(layers "F.Cu" "B.Cu")
		(net "P5VA")
	)
	(via
		(at 220.344746 -20.8407)
		(size 0.7112)
		(drill 0.4064)
		(layers "F.Cu" "B.Cu")
		(net "P5VA")
	)
	(via
		(at 205.54823 -383.215388)
		(size 0.7112)
		(drill 0.4064)
		(layers "F.Cu" "B.Cu")
		(net "P5VA")
	)
	(via
		(at 160.994598 -459.075536)
		(size 0.7112)
		(drill 0.4064)
		(layers "F.Cu" "B.Cu")
		(net "P5VA")
	)
	(via
		(at 213.105746 -21.6027)
		(size 0.7112)
		(drill 0.4064)
		(layers "F.Cu" "B.Cu")
		(net "P5VA")
	)
	(via
		(at 212.978746 -25.2857)
		(size 0.7112)
		(drill 0.4064)
		(layers "F.Cu" "B.Cu")
		(net "P5VA")
	)
	(via
		(at 202.057254 -487.094784)
		(size 0.7112)
		(drill 0.4064)
		(layers "F.Cu" "B.Cu")
		(net "P5VA")
	)
	(via
		(at 205.72476 -67.29476)
		(size 0.5588)
		(drill 0.3048)
		(layers "F.Cu" "B.Cu")
		(net "P5VA")
	)
	(via
		(at 225.170746 -25.2857)
		(size 0.7112)
		(drill 0.4064)
		(layers "F.Cu" "B.Cu")
		(net "P5VA")
	)
	(via
		(at 202.063604 -485.062784)
		(size 0.7112)
		(drill 0.4064)
		(layers "F.Cu" "B.Cu")
		(net "P5VA")
	)
	(via
		(at 203.834746 -278.781764)
		(size 0.7112)
		(drill 0.4064)
		(layers "F.Cu" "B.Cu")
		(net "P5VA")
	)
	(via
		(at 205.580742 -74.313034)
		(size 0.7112)
		(drill 0.4064)
		(layers "F.Cu" "B.Cu")
		(net "P5VA")
	)
	(via
		(at 204.935074 -180.810662)
		(size 0.7112)
		(drill 0.4064)
		(layers "F.Cu" "B.Cu")
		(net "P5VA")
	)
	(via
		(at 202.055222 -486.078784)
		(size 0.7112)
		(drill 0.4064)
		(layers "F.Cu" "B.Cu")
		(net "P5VA")
	)
	(via
		(at 205.23327 -487.39171)
		(size 0.7112)
		(drill 0.4064)
		(layers "F.Cu" "B.Cu")
		(net "P5VA")
	)
	(via
		(at 241.3254 -413.0294)
		(size 0.7112)
		(drill 0.4064)
		(layers "F.Cu" "B.Cu")
		(net "P5VA")
	)
	(via
		(at 204.935074 -178.270662)
		(size 0.7112)
		(drill 0.4064)
		(layers "F.Cu" "B.Cu")
		(net "P5VA")
	)
	(via
		(at 202.818746 -278.781764)
		(size 0.7112)
		(drill 0.4064)
		(layers "F.Cu" "B.Cu")
		(net "P5VA")
	)
	(via
		(at 202.183746 -383.4257)
		(size 0.7112)
		(drill 0.4064)
		(layers "F.Cu" "B.Cu")
		(net "P5VA")
	)
	(via
		(at 221.868746 -344.4367)
		(size 0.7112)
		(drill 0.4064)
		(layers "F.Cu" "B.Cu")
		(net "P5VA")
	)
	(via
		(at 232.790746 -43.8277)
		(size 0.5588)
		(drill 0.3048)
		(layers "F.Cu" "B.Cu")
		(net "P5VA")
	)
	(via
		(at 229.615746 -145.892012)
		(size 0.7112)
		(drill 0.4064)
		(layers "F.Cu" "B.Cu")
		(net "P5VA")
	)
	(via
		(at 202.183746 -382.1557)
		(size 0.7112)
		(drill 0.4064)
		(layers "F.Cu" "B.Cu")
		(net "P5VA")
	)
	(via
		(at 226.176586 -25.429464)
		(size 0.7112)
		(drill 0.4064)
		(layers "F.Cu" "B.Cu")
		(net "P5VA")
	)
	(via
		(at 215.772746 -23.1267)
		(size 0.7112)
		(drill 0.3556)
		(layers "F.Cu" "B.Cu")
		(net "P5VA")
	)
	(via
		(at 214.248746 -20.9677)
		(size 0.7112)
		(drill 0.4064)
		(layers "F.Cu" "B.Cu")
		(net "P5VA")
	)
	(via
		(at 205.9686 -478.13976)
		(size 0.5588)
		(drill 0.3048)
		(layers "F.Cu" "B.Cu")
		(net "P5VA")
	)
	(via
		(at 219.836746 -31.8897)
		(size 0.7112)
		(drill 0.4064)
		(layers "F.Cu" "B.Cu")
		(net "P5VA")
	)
	(via
		(at 213.232746 -30.2387)
		(size 0.7112)
		(drill 0.4064)
		(layers "F.Cu" "B.Cu")
		(net "P5VA")
	)
	(via
		(at 202.405742 -76.980034)
		(size 0.7112)
		(drill 0.4064)
		(layers "F.Cu" "B.Cu")
		(net "P5VA")
	)
	(via
		(at 212.851746 -23.1267)
		(size 0.7112)
		(drill 0.4064)
		(layers "F.Cu" "B.Cu")
		(net "P5VA")
	)
	(via
		(at 229.822756 -454.434702)
		(size 0.7112)
		(drill 0.4064)
		(layers "F.Cu" "B.Cu")
		(net "P5VA")
	)
	(via
		(at 225.170746 -26.5557)
		(size 0.7112)
		(drill 0.4064)
		(layers "F.Cu" "B.Cu")
		(net "P5VA")
	)
	(via
		(at 205.39964 -169.55516)
		(size 0.5588)
		(drill 0.3048)
		(layers "F.Cu" "B.Cu")
		(net "P5VA")
	)
	(via
		(at 212.978746 -27.1907)
		(size 0.7112)
		(drill 0.4064)
		(layers "F.Cu" "B.Cu")
		(net "P5VA")
	)
	(segment
		(start 192.87363 -453.2757)
		(end 162.051746 -453.2757)
		(width 0.508)
		(layer "In5.Cu")
		(net "P5VA")
	)
	(segment
		(start 194.858386 -455.260456)
		(end 192.87363 -453.2757)
		(width 0.508)
		(layer "In5.Cu")
		(net "P5VA")
	)
	(segment
		(start 160.994598 -454.332848)
		(end 160.994598 -459.075536)
		(width 0.508)
		(layer "In5.Cu")
		(net "P5VA")
	)
	(segment
		(start 162.051746 -453.2757)
		(end 160.994598 -454.332848)
		(width 0.508)
		(layer "In5.Cu")
		(net "P5VA")
	)
	(segment
		(start 221.2594 -429.7934)
		(end 222.504 -431.038)
		(width 0.508)
		(layer "F.Cu")
		(net "P3V3_BS_NET")
	)
	(segment
		(start 221.031054 -434.3146)
		(end 221.031054 -433.552346)
		(width 0.508)
		(layer "F.Cu")
		(net "P3V3_BS_NET")
	)
	(segment
		(start 221.031054 -433.552346)
		(end 221.793054 -432.790346)
		(width 0.508)
		(layer "F.Cu")
		(net "P3V3_BS_NET")
	)
	(segment
		(start 221.793054 -432.790346)
		(end 222.504 -432.790346)
		(width 0.508)
		(layer "F.Cu")
		(net "P3V3_BS_NET")
	)
	(segment
		(start 221.2594 -429.3362)
		(end 221.2594 -429.7934)
		(width 0.508)
		(layer "F.Cu")
		(net "P3V3_BS_NET")
	)
	(segment
		(start 222.504 -431.038)
		(end 222.504 -432.790346)
		(width 0.508)
		(layer "F.Cu")
		(net "P3V3_BS_NET")
	)
	(via
		(at 221.2594 -429.3362)
		(size 0.7112)
		(drill 0.3556)
		(layers "F.Cu" "B.Cu")
		(net "P3V3_BS_NET")
	)
	(via
		(at 219.1512 -435.0258)
		(size 0.5588)
		(drill 0.3048)
		(layers "F.Cu" "B.Cu")
		(net "P3V3_LX")
	)
	(via
		(at 218.46159 -435.664356)
		(size 0.7112)
		(drill 0.3556)
		(layers "F.Cu" "B.Cu")
		(net "P3V3_LX")
	)
	(segment
		(start 218.512644 -435.664356)
		(end 218.46159 -435.664356)
		(width 0.508)
		(layer "B.Cu")
		(net "P3V3_LX")
	)
	(segment
		(start 219.1512 -435.0258)
		(end 218.512644 -435.664356)
		(width 0.508)
		(layer "B.Cu")
		(net "P3V3_LX")
	)
	(via
		(at 226.949 -430.403)
		(size 0.7112)
		(drill 0.3556)
		(layers "F.Cu" "B.Cu")
		(net "P3V3_FB")
	)
	(via
		(at 225.155506 -436.2704)
		(size 0.5588)
		(drill 0.3048)
		(layers "F.Cu" "B.Cu")
		(net "P3V3_EN")
	)
	(via
		(at 225.172524 -437.2102)
		(size 0.7112)
		(drill 0.3556)
		(layers "F.Cu" "B.Cu")
		(net "P3V3_EN")
	)
	(segment
		(start 225.171 -437.208676)
		(end 225.172524 -437.2102)
		(width 0.508)
		(layer "B.Cu")
		(net "P3V3_EN")
	)
	(segment
		(start 225.171 -437.134)
		(end 225.171 -437.208676)
		(width 0.508)
		(layer "B.Cu")
		(net "P3V3_EN")
	)
	(segment
		(start 225.155506 -437.118506)
		(end 225.171 -437.134)
		(width 0.508)
		(layer "B.Cu")
		(net "P3V3_EN")
	)
	(segment
		(start 225.155506 -436.2704)
		(end 225.155506 -437.118506)
		(width 0.508)
		(layer "B.Cu")
		(net "P3V3_EN")
	)
	(segment
		(start 233.389424 -23.229824)
		(end 232.560622 -23.229824)
		(width 0.254)
		(layer "F.Cu")
		(net "P5VA_PGD")
	)
	(segment
		(start 232.560622 -23.229824)
		(end 231.901746 -23.8887)
		(width 0.254)
		(layer "F.Cu")
		(net "P5VA_PGD")
	)
	(segment
		(start 231.088946 -28.11272)
		(end 231.490266 -27.7114)
		(width 0.254)
		(layer "F.Cu")
		(net "P5VA_PGD")
	)
	(segment
		(start 231.088946 -30.047946)
		(end 231.088946 -28.11272)
		(width 0.254)
		(layer "F.Cu")
		(net "P5VA_PGD")
	)
	(segment
		(start 231.571546 -27.7114)
		(end 231.774746 -27.5082)
		(width 0.254)
		(layer "F.Cu")
		(net "P5VA_PGD")
	)
	(segment
		(start 233.8197 -32.7787)
		(end 231.088946 -30.047946)
		(width 0.254)
		(layer "F.Cu")
		(net "P5VA_PGD")
	)
	(segment
		(start 232.409746 -26.1747)
		(end 231.774746 -26.8097)
		(width 0.254)
		(layer "F.Cu")
		(net "P5VA_PGD")
	)
	(segment
		(start 243.458746 -29.9847)
		(end 240.664746 -32.7787)
		(width 0.254)
		(layer "F.Cu")
		(net "P5VA_PGD")
	)
	(segment
		(start 242.760246 -27.5082)
		(end 243.458746 -28.2067)
		(width 0.254)
		(layer "F.Cu")
		(net "P5VA_PGD")
	)
	(segment
		(start 240.664746 -32.7787)
		(end 233.8197 -32.7787)
		(width 0.254)
		(layer "F.Cu")
		(net "P5VA_PGD")
	)
	(segment
		(start 231.901746 -25.6667)
		(end 232.409746 -26.1747)
		(width 0.254)
		(layer "F.Cu")
		(net "P5VA_PGD")
	)
	(segment
		(start 231.901746 -23.8887)
		(end 231.901746 -25.6667)
		(width 0.254)
		(layer "F.Cu")
		(net "P5VA_PGD")
	)
	(segment
		(start 241.934746 -27.5082)
		(end 242.760246 -27.5082)
		(width 0.254)
		(layer "F.Cu")
		(net "P5VA_PGD")
	)
	(segment
		(start 231.490266 -27.7114)
		(end 231.571546 -27.7114)
		(width 0.254)
		(layer "F.Cu")
		(net "P5VA_PGD")
	)
	(segment
		(start 231.774746 -26.8097)
		(end 231.774746 -27.5082)
		(width 0.254)
		(layer "F.Cu")
		(net "P5VA_PGD")
	)
	(segment
		(start 243.458746 -28.2067)
		(end 243.458746 -29.9847)
		(width 0.254)
		(layer "F.Cu")
		(net "P5VA_PGD")
	)
	(segment
		(start 178.002946 -457.615036)
		(end 179.399946 -457.615036)
		(width 0.508)
		(layer "F.Cu")
		(net "P5VC_DIV")
	)
	(segment
		(start 179.463446 -457.551536)
		(end 180.479446 -457.551536)
		(width 0.508)
		(layer "F.Cu")
		(net "P5VC_DIV")
	)
	(segment
		(start 180.479446 -457.551536)
		(end 181.304946 -457.551536)
		(width 0.508)
		(layer "F.Cu")
		(net "P5VC_DIV")
	)
	(segment
		(start 181.304946 -457.551536)
		(end 181.749446 -457.107036)
		(width 0.508)
		(layer "F.Cu")
		(net "P5VC_DIV")
	)
	(segment
		(start 179.399946 -457.615036)
		(end 179.463446 -457.551536)
		(width 0.508)
		(layer "F.Cu")
		(net "P5VC_DIV")
	)
	(via
		(at 181.749446 -457.107036)
		(size 0.7112)
		(drill 0.3556)
		(layers "F.Cu" "B.Cu")
		(net "P5VC_DIV")
	)
	(segment
		(start 162.572446 -456.281536)
		(end 161.2519 -456.281536)
		(width 0.508)
		(layer "F.Cu")
		(net "P5VB_DIV")
	)
	(segment
		(start 163.651946 -456.218036)
		(end 163.588446 -456.281536)
		(width 0.508)
		(layer "F.Cu")
		(net "P5VB_DIV")
	)
	(segment
		(start 164.667946 -456.218036)
		(end 163.651946 -456.218036)
		(width 0.508)
		(layer "F.Cu")
		(net "P5VB_DIV")
	)
	(segment
		(start 163.588446 -456.281536)
		(end 162.572446 -456.281536)
		(width 0.508)
		(layer "F.Cu")
		(net "P5VB_DIV")
	)
	(segment
		(start 161.2519 -456.281536)
		(end 161.018474 -456.04811)
		(width 0.508)
		(layer "F.Cu")
		(net "P5VB_DIV")
	)
	(via
		(at 161.018474 -456.04811)
		(size 0.7112)
		(drill 0.3556)
		(layers "F.Cu" "B.Cu")
		(net "P5VB_DIV")
	)
	(segment
		(start 164.667946 -458.123036)
		(end 164.604446 -458.186536)
		(width 0.508)
		(layer "F.Cu")
		(net "P5VA_DIV")
	)
	(segment
		(start 162.572446 -458.186536)
		(end 162.254946 -458.186536)
		(width 0.508)
		(layer "F.Cu")
		(net "P5VA_DIV")
	)
	(segment
		(start 162.04311 -457.9747)
		(end 161.289746 -457.9747)
		(width 0.508)
		(layer "F.Cu")
		(net "P5VA_DIV")
	)
	(segment
		(start 163.588446 -458.186536)
		(end 162.572446 -458.186536)
		(width 0.508)
		(layer "F.Cu")
		(net "P5VA_DIV")
	)
	(segment
		(start 164.604446 -458.186536)
		(end 163.588446 -458.186536)
		(width 0.508)
		(layer "F.Cu")
		(net "P5VA_DIV")
	)
	(segment
		(start 162.254946 -458.186536)
		(end 162.04311 -457.9747)
		(width 0.508)
		(layer "F.Cu")
		(net "P5VA_DIV")
	)
	(via
		(at 161.289746 -457.9747)
		(size 0.7112)
		(drill 0.3556)
		(layers "F.Cu" "B.Cu")
		(net "P5VA_DIV")
	)
	(segment
		(start 175.824388 -457.602336)
		(end 175.202088 -456.980036)
		(width 0.508)
		(layer "F.Cu")
		(net "P5VC_SENSE")
	)
	(segment
		(start 176.161446 -457.678536)
		(end 176.085246 -457.602336)
		(width 0.508)
		(layer "F.Cu")
		(net "P5VC_SENSE")
	)
	(segment
		(start 177.113946 -457.615036)
		(end 177.050446 -457.678536)
		(width 0.508)
		(layer "F.Cu")
		(net "P5VC_SENSE")
	)
	(segment
		(start 176.085246 -457.602336)
		(end 175.824388 -457.602336)
		(width 0.508)
		(layer "F.Cu")
		(net "P5VC_SENSE")
	)
	(segment
		(start 173.367446 -457.742036)
		(end 174.129446 -456.980036)
		(width 0.508)
		(layer "F.Cu")
		(net "P5VC_SENSE")
	)
	(segment
		(start 173.367446 -458.123036)
		(end 173.367446 -457.742036)
		(width 0.508)
		(layer "F.Cu")
		(net "P5VC_SENSE")
	)
	(segment
		(start 173.405546 -458.161136)
		(end 173.367446 -458.123036)
		(width 0.3048)
		(layer "F.Cu")
		(net "P5VC_SENSE")
	)
	(segment
		(start 177.050446 -457.678536)
		(end 176.161446 -457.678536)
		(width 0.508)
		(layer "F.Cu")
		(net "P5VC_SENSE")
	)
	(segment
		(start 173.405546 -458.901546)
		(end 173.405546 -458.161136)
		(width 0.3048)
		(layer "F.Cu")
		(net "P5VC_SENSE")
	)
	(segment
		(start 175.202088 -456.980036)
		(end 174.129446 -456.980036)
		(width 0.508)
		(layer "F.Cu")
		(net "P5VC_SENSE")
	)
	(via
		(at 174.129446 -456.980036)
		(size 0.7112)
		(drill 0.3556)
		(layers "F.Cu" "B.Cu")
		(net "P5VC_SENSE")
	)
	(segment
		(start 166.445946 -456.218036)
		(end 166.509446 -456.281536)
		(width 0.508)
		(layer "F.Cu")
		(net "P5VB_SENSE")
	)
	(segment
		(start 170.4467 -458.630782)
		(end 170.4467 -458.199998)
		(width 0.3048)
		(layer "F.Cu")
		(net "P5VB_SENSE")
	)
	(segment
		(start 170.4467 -458.199998)
		(end 169.926254 -457.679552)
		(width 0.3048)
		(layer "F.Cu")
		(net "P5VB_SENSE")
	)
	(segment
		(start 169.265346 -458.901546)
		(end 170.175936 -458.901546)
		(width 0.3048)
		(layer "F.Cu")
		(net "P5VB_SENSE")
	)
	(segment
		(start 166.509446 -456.281536)
		(end 168.528238 -456.281536)
		(width 0.508)
		(layer "F.Cu")
		(net "P5VB_SENSE")
	)
	(segment
		(start 170.175936 -458.901546)
		(end 170.4467 -458.630782)
		(width 0.3048)
		(layer "F.Cu")
		(net "P5VB_SENSE")
	)
	(segment
		(start 168.528238 -456.281536)
		(end 168.795446 -456.548744)
		(width 0.508)
		(layer "F.Cu")
		(net "P5VB_SENSE")
	)
	(segment
		(start 169.926254 -457.679552)
		(end 168.795446 -456.548744)
		(width 0.508)
		(layer "F.Cu")
		(net "P5VB_SENSE")
	)
	(segment
		(start 165.556946 -456.218036)
		(end 166.445946 -456.218036)
		(width 0.508)
		(layer "F.Cu")
		(net "P5VB_SENSE")
	)
	(via
		(at 168.795446 -456.548744)
		(size 0.7112)
		(drill 0.3556)
		(layers "F.Cu" "B.Cu")
		(net "P5VB_SENSE")
	)
	(segment
		(start 166.509446 -458.186536)
		(end 166.563802 -458.13218)
		(width 0.508)
		(layer "F.Cu")
		(net "P5VA_SENSE")
	)
	(segment
		(start 169.265346 -459.400656)
		(end 168.223184 -459.400656)
		(width 0.3048)
		(layer "F.Cu")
		(net "P5VA_SENSE")
	)
	(segment
		(start 167.627046 -458.804518)
		(end 167.627046 -458.13218)
		(width 0.508)
		(layer "F.Cu")
		(net "P5VA_SENSE")
	)
	(segment
		(start 166.445946 -458.123036)
		(end 166.509446 -458.186536)
		(width 0.508)
		(layer "F.Cu")
		(net "P5VA_SENSE")
	)
	(segment
		(start 166.563802 -458.13218)
		(end 167.627046 -458.13218)
		(width 0.508)
		(layer "F.Cu")
		(net "P5VA_SENSE")
	)
	(segment
		(start 167.771826 -458.949298)
		(end 167.627046 -458.804518)
		(width 0.508)
		(layer "F.Cu")
		(net "P5VA_SENSE")
	)
	(segment
		(start 168.223184 -459.400656)
		(end 167.771826 -458.949298)
		(width 0.3048)
		(layer "F.Cu")
		(net "P5VA_SENSE")
	)
	(segment
		(start 165.556946 -458.123036)
		(end 166.445946 -458.123036)
		(width 0.508)
		(layer "F.Cu")
		(net "P5VA_SENSE")
	)
	(via
		(at 167.627046 -458.13218)
		(size 0.7112)
		(drill 0.3556)
		(layers "F.Cu" "B.Cu")
		(net "P5VA_SENSE")
	)
	(segment
		(start 13.271246 -481.8507)
		(end 12.318746 -481.8507)
		(width 0.508)
		(layer "F.Cu")
		(net "P5VC_VFB_NET")
	)
	(segment
		(start 4.635246 -495.8207)
		(end 2.998978 -495.8207)
		(width 0.508)
		(layer "F.Cu")
		(net "P5VC_VFB_NET")
	)
	(segment
		(start 2.998978 -495.8207)
		(end 2.972562 -495.794284)
		(width 0.508)
		(layer "F.Cu")
		(net "P5VC_VFB_NET")
	)
	(via
		(at 12.318746 -481.8507)
		(size 0.5588)
		(drill 0.3048)
		(layers "F.Cu" "B.Cu")
		(net "P5VC_VFB_NET")
	)
	(via
		(at 2.972562 -495.794284)
		(size 0.5588)
		(drill 0.3048)
		(layers "F.Cu" "B.Cu")
		(net "P5VC_VFB_NET")
	)
	(via
		(at 6.095746 -490.943646)
		(size 0.7112)
		(drill 0.3556)
		(layers "F.Cu" "B.Cu")
		(net "P5VC_VFB_NET")
	)
	(segment
		(start 2.971546 -493.445292)
		(end 2.971546 -491.445296)
		(width 0.508)
		(layer "B.Cu")
		(net "P5VC_VFB_NET")
	)
	(segment
		(start 12.318746 -481.8507)
		(end 11.041888 -481.8507)
		(width 0.508)
		(layer "B.Cu")
		(net "P5VC_VFB_NET")
	)
	(segment
		(start 2.972562 -493.446308)
		(end 2.971546 -493.445292)
		(width 0.508)
		(layer "B.Cu")
		(net "P5VC_VFB_NET")
	)
	(segment
		(start 6.9088 -490.943646)
		(end 6.095746 -490.943646)
		(width 0.508)
		(layer "B.Cu")
		(net "P5VC_VFB_NET")
	)
	(segment
		(start 2.972562 -495.794284)
		(end 2.972562 -493.446308)
		(width 0.508)
		(layer "B.Cu")
		(net "P5VC_VFB_NET")
	)
	(segment
		(start 11.041888 -481.8507)
		(end 9.905746 -482.986842)
		(width 0.508)
		(layer "B.Cu")
		(net "P5VC_VFB_NET")
	)
	(segment
		(start 3.473196 -490.943646)
		(end 6.095746 -490.943646)
		(width 0.508)
		(layer "B.Cu")
		(net "P5VC_VFB_NET")
	)
	(segment
		(start 2.971546 -491.445296)
		(end 3.473196 -490.943646)
		(width 0.508)
		(layer "B.Cu")
		(net "P5VC_VFB_NET")
	)
	(segment
		(start 9.905746 -487.9467)
		(end 6.9088 -490.943646)
		(width 0.508)
		(layer "B.Cu")
		(net "P5VC_VFB_NET")
	)
	(segment
		(start 9.905746 -482.986842)
		(end 9.905746 -487.9467)
		(width 0.508)
		(layer "B.Cu")
		(net "P5VC_VFB_NET")
	)
	(segment
		(start 6.222746 -497.288058)
		(end 6.337046 -497.173758)
		(width 0.508)
		(layer "F.Cu")
		(net "P5VC_LL_NET")
	)
	(segment
		(start 4.635246 -496.8367)
		(end 4.711446 -496.9129)
		(width 0.508)
		(layer "F.Cu")
		(net "P5VC_LL_NET")
	)
	(segment
		(start 5.988304 -497.5225)
		(end 5.999734 -497.5225)
		(width 0.508)
		(layer "F.Cu")
		(net "P5VC_LL_NET")
	)
	(segment
		(start 6.222746 -497.299488)
		(end 6.222746 -497.288058)
		(width 0.508)
		(layer "F.Cu")
		(net "P5VC_LL_NET")
	)
	(segment
		(start 4.711446 -497.173758)
		(end 5.187188 -497.6495)
		(width 0.508)
		(layer "F.Cu")
		(net "P5VC_LL_NET")
	)
	(segment
		(start 5.187188 -497.6495)
		(end 5.861304 -497.6495)
		(width 0.508)
		(layer "F.Cu")
		(net "P5VC_LL_NET")
	)
	(segment
		(start 13.652246 -482.9937)
		(end 13.588746 -483.0572)
		(width 0.508)
		(layer "F.Cu")
		(net "P5VC_LL_NET")
	)
	(segment
		(start 6.337046 -496.9764)
		(end 6.476746 -496.8367)
		(width 0.508)
		(layer "F.Cu")
		(net "P5VC_LL_NET")
	)
	(segment
		(start 5.861304 -497.6495)
		(end 5.988304 -497.5225)
		(width 0.508)
		(layer "F.Cu")
		(net "P5VC_LL_NET")
	)
	(segment
		(start 5.999734 -497.5225)
		(end 6.222746 -497.299488)
		(width 0.508)
		(layer "F.Cu")
		(net "P5VC_LL_NET")
	)
	(segment
		(start 13.588746 -483.0572)
		(end 12.572746 -483.0572)
		(width 0.508)
		(layer "F.Cu")
		(net "P5VC_LL_NET")
	)
	(segment
		(start 6.337046 -497.173758)
		(end 6.337046 -496.9764)
		(width 0.508)
		(layer "F.Cu")
		(net "P5VC_LL_NET")
	)
	(segment
		(start 12.572746 -483.0572)
		(end 10.985246 -483.0572)
		(width 0.508)
		(layer "F.Cu")
		(net "P5VC_LL_NET")
	)
	(segment
		(start 4.711446 -496.9129)
		(end 4.711446 -497.173758)
		(width 0.508)
		(layer "F.Cu")
		(net "P5VC_LL_NET")
	)
	(segment
		(start 10.985246 -483.0572)
		(end 10.794746 -483.2477)
		(width 0.508)
		(layer "F.Cu")
		(net "P5VC_LL_NET")
	)
	(via
		(at 10.794746 -483.2477)
		(size 0.5588)
		(drill 0.3048)
		(layers "F.Cu" "B.Cu")
		(net "P5VC_LL_NET")
	)
	(via
		(at 9.022334 -490.354112)
		(size 0.7112)
		(drill 0.3556)
		(layers "F.Cu" "B.Cu")
		(net "P5VC_LL_NET")
	)
	(via
		(at 6.476746 -496.8367)
		(size 0.5588)
		(drill 0.3048)
		(layers "F.Cu" "B.Cu")
		(net "P5VC_LL_NET")
	)
	(segment
		(start 10.794746 -488.5817)
		(end 9.022334 -490.354112)
		(width 0.508)
		(layer "B.Cu")
		(net "P5VC_LL_NET")
	)
	(segment
		(start 6.476746 -496.8367)
		(end 6.476746 -492.8997)
		(width 0.508)
		(layer "B.Cu")
		(net "P5VC_LL_NET")
	)
	(segment
		(start 6.476746 -492.8997)
		(end 9.022334 -490.354112)
		(width 0.508)
		(layer "B.Cu")
		(net "P5VC_LL_NET")
	)
	(segment
		(start 10.794746 -483.2477)
		(end 10.794746 -488.5817)
		(width 0.508)
		(layer "B.Cu")
		(net "P5VC_LL_NET")
	)
	(segment
		(start 9.473946 -488.6579)
		(end 11.124946 -488.6579)
		(width 0.254)
		(layer "F.Cu")
		(net "P5VC_SNB")
	)
	(segment
		(start 9.207246 -488.3912)
		(end 9.473946 -488.6579)
		(width 0.254)
		(layer "F.Cu")
		(net "P5VC_SNB")
	)
	(segment
		(start 11.124946 -488.6579)
		(end 11.175746 -488.7087)
		(width 0.254)
		(layer "F.Cu")
		(net "P5VC_SNB")
	)
	(segment
		(start 8.318246 -488.0737)
		(end 9.207246 -488.0737)
		(width 0.508)
		(layer "F.Cu")
		(net "P5VC_SNB")
	)
	(segment
		(start 8.127746 -488.2642)
		(end 8.318246 -488.0737)
		(width 0.508)
		(layer "F.Cu")
		(net "P5VC_SNB")
	)
	(segment
		(start 9.207246 -488.0737)
		(end 9.207246 -488.3912)
		(width 0.254)
		(layer "F.Cu")
		(net "P5VC_SNB")
	)
	(via
		(at 11.175746 -488.7087)
		(size 0.7112)
		(drill 0.3556)
		(layers "F.Cu" "B.Cu")
		(net "P5VC_SNB")
	)
	(segment
		(start 7.1374 -486.791)
		(end 6.2738 -487.6546)
		(width 0.254)
		(layer "F.Cu")
		(net "P5VC_VBST_NET")
	)
	(segment
		(start 10.388346 -485.8131)
		(end 10.388346 -485.885236)
		(width 0.254)
		(layer "F.Cu")
		(net "P5VC_VBST_NET")
	)
	(segment
		(start 9.207246 -487.1847)
		(end 8.813546 -486.791)
		(width 0.254)
		(layer "F.Cu")
		(net "P5VC_VBST_NET")
	)
	(segment
		(start 8.813546 -486.791)
		(end 7.1374 -486.791)
		(width 0.254)
		(layer "F.Cu")
		(net "P5VC_VBST_NET")
	)
	(segment
		(start 9.207246 -486.9942)
		(end 10.388346 -485.8131)
		(width 0.254)
		(layer "F.Cu")
		(net "P5VC_VBST_NET")
	)
	(segment
		(start 4.698746 -488.3785)
		(end 4.698746 -488.5817)
		(width 0.254)
		(layer "F.Cu")
		(net "P5VC_VBST_NET")
	)
	(segment
		(start 10.388346 -485.885236)
		(end 10.565638 -485.885236)
		(width 0.254)
		(layer "F.Cu")
		(net "P5VC_VBST_NET")
	)
	(segment
		(start 6.2738 -487.6546)
		(end 5.422646 -487.6546)
		(width 0.254)
		(layer "F.Cu")
		(net "P5VC_VBST_NET")
	)
	(segment
		(start 9.207246 -487.1847)
		(end 9.207246 -486.9942)
		(width 0.254)
		(layer "F.Cu")
		(net "P5VC_VBST_NET")
	)
	(segment
		(start 5.422646 -487.6546)
		(end 4.698746 -488.3785)
		(width 0.254)
		(layer "F.Cu")
		(net "P5VC_VBST_NET")
	)
	(via
		(at 10.565638 -485.885236)
		(size 0.7112)
		(drill 0.3556)
		(layers "F.Cu" "B.Cu")
		(net "P5VC_VBST_NET")
	)
	(segment
		(start 10.269474 -492.015526)
		(end 10.269474 -490.596428)
		(width 0.254)
		(layer "F.Cu")
		(net "P5VC_VBST")
	)
	(segment
		(start 4.876546 -490.1057)
		(end 5.343398 -490.572552)
		(width 0.254)
		(layer "F.Cu")
		(net "P5VC_VBST")
	)
	(segment
		(start 7.1501 -490.572552)
		(end 7.845552 -489.8771)
		(width 0.254)
		(layer "F.Cu")
		(net "P5VC_VBST")
	)
	(segment
		(start 4.698746 -490.1057)
		(end 4.876546 -490.1057)
		(width 0.254)
		(layer "F.Cu")
		(net "P5VC_VBST")
	)
	(segment
		(start 9.550146 -489.8771)
		(end 8.527542 -489.8771)
		(width 0.254)
		(layer "F.Cu")
		(net "P5VC_VBST")
	)
	(segment
		(start 10.269474 -490.596428)
		(end 9.550146 -489.8771)
		(width 0.254)
		(layer "F.Cu")
		(net "P5VC_VBST")
	)
	(segment
		(start 5.343398 -490.572552)
		(end 7.1501 -490.572552)
		(width 0.254)
		(layer "F.Cu")
		(net "P5VC_VBST")
	)
	(segment
		(start 7.845552 -489.8771)
		(end 8.527542 -489.8771)
		(width 0.254)
		(layer "F.Cu")
		(net "P5VC_VBST")
	)
	(via
		(at 8.527542 -489.8771)
		(size 0.7112)
		(drill 0.3556)
		(layers "F.Cu" "B.Cu")
		(net "P5VC_VBST")
	)
	(via
		(at 21.335746 -494.0427)
		(size 0.7112)
		(drill 0.4064)
		(layers "F.Cu" "B.Cu")
		(net "P5VC_LL")
	)
	(via
		(at 20.9296 -490.601)
		(size 0.7112)
		(drill 0.3556)
		(layers "F.Cu" "B.Cu")
		(net "P5VC_LL")
	)
	(via
		(at 12.064746 -490.3597)
		(size 0.7112)
		(drill 0.4064)
		(layers "F.Cu" "B.Cu")
		(net "P5VC_LL")
	)
	(via
		(at 13.9192 -490.0676)
		(size 0.7112)
		(drill 0.3556)
		(layers "F.Cu" "B.Cu")
		(net "P5VC_LL")
	)
	(via
		(at 12.064746 -486.4227)
		(size 0.7112)
		(drill 0.4064)
		(layers "F.Cu" "B.Cu")
		(net "P5VC_LL")
	)
	(via
		(at 20.700746 -486.5497)
		(size 0.7112)
		(drill 0.4064)
		(layers "F.Cu" "B.Cu")
		(net "P5VC_LL")
	)
	(via
		(at 18.668746 -494.1697)
		(size 0.7112)
		(drill 0.4064)
		(layers "F.Cu" "B.Cu")
		(net "P5VC_LL")
	)
	(via
		(at 16.001746 -486.2957)
		(size 0.7112)
		(drill 0.4064)
		(layers "F.Cu" "B.Cu")
		(net "P5VC_LL")
	)
	(via
		(at 15.874746 -492.6457)
		(size 0.7112)
		(drill 0.4064)
		(layers "F.Cu" "B.Cu")
		(net "P5VC_LL")
	)
	(via
		(at 17.5514 -487.3752)
		(size 0.7112)
		(drill 0.3556)
		(layers "F.Cu" "B.Cu")
		(net "P5VC_LL")
	)
	(via
		(at 16.001746 -489.2167)
		(size 0.7112)
		(drill 0.4064)
		(layers "F.Cu" "B.Cu")
		(net "P5VC_LL")
	)
	(segment
		(start 5.524246 -496.8367)
		(end 5.524246 -495.8207)
		(width 0.508)
		(layer "F.Cu")
		(net "P5VC_VFB")
	)
	(segment
		(start 5.524246 -495.8207)
		(end 5.524246 -494.8047)
		(width 0.508)
		(layer "F.Cu")
		(net "P5VC_VFB")
	)
	(segment
		(start 8.76935 -492.015526)
		(end 8.63092 -492.015526)
		(width 0.254)
		(layer "F.Cu")
		(net "P5VC_VFB")
	)
	(segment
		(start 7.873746 -493.4077)
		(end 6.730746 -494.5507)
		(width 0.254)
		(layer "F.Cu")
		(net "P5VC_VFB")
	)
	(segment
		(start 6.476746 -494.8047)
		(end 6.730746 -494.5507)
		(width 0.254)
		(layer "F.Cu")
		(net "P5VC_VFB")
	)
	(segment
		(start 5.524246 -494.8047)
		(end 6.476746 -494.8047)
		(width 0.254)
		(layer "F.Cu")
		(net "P5VC_VFB")
	)
	(segment
		(start 8.63092 -492.015526)
		(end 7.873746 -492.7727)
		(width 0.254)
		(layer "F.Cu")
		(net "P5VC_VFB")
	)
	(segment
		(start 7.873746 -492.7727)
		(end 7.873746 -493.4077)
		(width 0.254)
		(layer "F.Cu")
		(net "P5VC_VFB")
	)
	(via
		(at 6.730746 -494.5507)
		(size 0.7112)
		(drill 0.3556)
		(layers "F.Cu" "B.Cu")
		(net "P5VC_VFB")
	)
	(segment
		(start 6.095746 -500.710454)
		(end 5.7023 -501.1039)
		(width 0.508)
		(layer "F.Cu")
		(net "P5VC_AGND")
	)
	(segment
		(start 6.095746 -499.9482)
		(end 6.095746 -500.710454)
		(width 0.508)
		(layer "F.Cu")
		(net "P5VC_AGND")
	)
	(segment
		(start 5.102098 -501.1039)
		(end 4.501896 -501.1039)
		(width 0.508)
		(layer "F.Cu")
		(net "P5VC_AGND")
	)
	(segment
		(start 3.047746 -494.5507)
		(end 3.301746 -494.8047)
		(width 0.508)
		(layer "F.Cu")
		(net "P5VC_AGND")
	)
	(segment
		(start 1.346962 -497.948966)
		(end 1.346962 -494.5507)
		(width 0.508)
		(layer "F.Cu")
		(net "P5VC_AGND")
	)
	(segment
		(start 3.301746 -494.8047)
		(end 4.635246 -494.8047)
		(width 0.508)
		(layer "F.Cu")
		(net "P5VC_AGND")
	)
	(segment
		(start 5.7023 -501.1039)
		(end 5.102098 -501.1039)
		(width 0.508)
		(layer "F.Cu")
		(net "P5VC_AGND")
	)
	(segment
		(start 5.84962 -488.997752)
		(end 5.84962 -488.197652)
		(width 0.508)
		(layer "F.Cu")
		(net "P5VC_AGND")
	)
	(segment
		(start 1.346962 -494.5507)
		(end 3.047746 -494.5507)
		(width 0.508)
		(layer "F.Cu")
		(net "P5VC_AGND")
	)
	(segment
		(start 4.501896 -501.1039)
		(end 1.346962 -497.948966)
		(width 0.508)
		(layer "F.Cu")
		(net "P5VC_AGND")
	)
	(segment
		(start 7.111746 -499.9482)
		(end 6.095746 -499.9482)
		(width 0.508)
		(layer "F.Cu")
		(net "P5VC_AGND")
	)
	(via
		(at 1.346962 -494.5507)
		(size 0.5588)
		(drill 0.3048)
		(layers "F.Cu" "B.Cu")
		(net "P5VC_AGND")
	)
	(via
		(at 4.43357 -489.910374)
		(size 0.7112)
		(drill 0.3556)
		(layers "F.Cu" "B.Cu")
		(net "P5VC_AGND")
	)
	(via
		(at 5.84962 -488.197652)
		(size 0.5588)
		(drill 0.3048)
		(layers "F.Cu" "B.Cu")
		(net "P5VC_AGND")
	)
	(segment
		(start 1.27 -494.473738)
		(end 1.27 -491.7186)
		(width 0.508)
		(layer "B.Cu")
		(net "P5VC_AGND")
	)
	(segment
		(start 1.27 -491.7186)
		(end 3.078226 -489.910374)
		(width 0.508)
		(layer "B.Cu")
		(net "P5VC_AGND")
	)
	(segment
		(start 3.078226 -489.910374)
		(end 4.43357 -489.910374)
		(width 0.508)
		(layer "B.Cu")
		(net "P5VC_AGND")
	)
	(segment
		(start 5.84962 -488.197652)
		(end 5.84962 -488.494324)
		(width 0.508)
		(layer "B.Cu")
		(net "P5VC_AGND")
	)
	(segment
		(start 5.84962 -488.494324)
		(end 4.43357 -489.910374)
		(width 0.508)
		(layer "B.Cu")
		(net "P5VC_AGND")
	)
	(segment
		(start 1.346962 -494.5507)
		(end 1.27 -494.473738)
		(width 0.508)
		(layer "B.Cu")
		(net "P5VC_AGND")
	)
	(segment
		(start 5.079746 -499.0592)
		(end 6.095746 -499.0592)
		(width 0.254)
		(layer "F.Cu")
		(net "P5VC_RF")
	)
	(segment
		(start 8.431276 -496.91417)
		(end 8.000746 -497.3447)
		(width 0.254)
		(layer "F.Cu")
		(net "P5VC_RF")
	)
	(segment
		(start 6.222746 -498.9322)
		(end 6.333236 -498.9322)
		(width 0.254)
		(layer "F.Cu")
		(net "P5VC_RF")
	)
	(segment
		(start 6.72719 -498.538246)
		(end 6.72719 -497.907564)
		(width 0.254)
		(layer "F.Cu")
		(net "P5VC_RF")
	)
	(segment
		(start 6.333236 -498.9322)
		(end 6.72719 -498.538246)
		(width 0.254)
		(layer "F.Cu")
		(net "P5VC_RF")
	)
	(segment
		(start 6.72719 -497.907564)
		(end 7.210806 -497.423948)
		(width 0.254)
		(layer "F.Cu")
		(net "P5VC_RF")
	)
	(segment
		(start 7.290054 -497.3447)
		(end 7.210806 -497.423948)
		(width 0.254)
		(layer "F.Cu")
		(net "P5VC_RF")
	)
	(segment
		(start 6.095746 -499.0592)
		(end 6.222746 -498.9322)
		(width 0.254)
		(layer "F.Cu")
		(net "P5VC_RF")
	)
	(segment
		(start 8.000746 -497.3447)
		(end 7.290054 -497.3447)
		(width 0.254)
		(layer "F.Cu")
		(net "P5VC_RF")
	)
	(segment
		(start 8.76935 -496.91417)
		(end 8.431276 -496.91417)
		(width 0.254)
		(layer "F.Cu")
		(net "P5VC_RF")
	)
	(via
		(at 7.210806 -497.423948)
		(size 0.7112)
		(drill 0.3556)
		(layers "F.Cu" "B.Cu")
		(net "P5VC_RF")
	)
	(segment
		(start 8.127746 -500.9642)
		(end 7.175246 -500.9642)
		(width 0.508)
		(layer "F.Cu")
		(net "P5VC_MODE_PG")
	)
	(segment
		(start 7.175246 -500.9642)
		(end 6.857746 -501.2817)
		(width 0.508)
		(layer "F.Cu")
		(net "P5VC_MODE_PG")
	)
	(segment
		(start 8.127746 -499.9482)
		(end 8.127746 -500.9642)
		(width 0.508)
		(layer "F.Cu")
		(net "P5VC_MODE_PG")
	)
	(via
		(at 6.857746 -501.2817)
		(size 0.7112)
		(drill 0.3556)
		(layers "F.Cu" "B.Cu")
		(net "P5VC_MODE_PG")
	)
	(segment
		(start 7.111746 -499.0592)
		(end 8.189976 -497.98097)
		(width 0.254)
		(layer "F.Cu")
		(net "P5VC_TRIP")
	)
	(segment
		(start 9.014206 -497.98097)
		(end 9.269476 -497.7257)
		(width 0.254)
		(layer "F.Cu")
		(net "P5VC_TRIP")
	)
	(segment
		(start 8.189976 -497.98097)
		(end 8.381746 -497.98097)
		(width 0.254)
		(layer "F.Cu")
		(net "P5VC_TRIP")
	)
	(segment
		(start 9.269476 -497.7257)
		(end 9.269476 -496.91417)
		(width 0.254)
		(layer "F.Cu")
		(net "P5VC_TRIP")
	)
	(segment
		(start 8.381746 -497.98097)
		(end 9.014206 -497.98097)
		(width 0.254)
		(layer "F.Cu")
		(net "P5VC_TRIP")
	)
	(via
		(at 8.381746 -497.04117)
		(size 0.7112)
		(drill 0.3556)
		(layers "F.Cu" "B.Cu")
		(net "P5VC_TRIP")
	)
	(via
		(at 8.381746 -497.98097)
		(size 0.5588)
		(drill 0.3048)
		(layers "F.Cu" "B.Cu")
		(net "P5VC_TRIP")
	)
	(segment
		(start 8.381746 -497.98097)
		(end 8.381746 -497.04117)
		(width 0.508)
		(layer "B.Cu")
		(net "P5VC_TRIP")
	)
	(segment
		(start 9.321546 -498.6909)
		(end 9.321546 -498.6782)
		(width 0.254)
		(layer "F.Cu")
		(net "P5VC_MODE")
	)
	(segment
		(start 8.127746 -499.0592)
		(end 8.191246 -498.9957)
		(width 0.254)
		(layer "F.Cu")
		(net "P5VC_MODE")
	)
	(segment
		(start 9.769348 -496.91417)
		(end 9.769348 -498.275864)
		(width 0.254)
		(layer "F.Cu")
		(net "P5VC_MODE")
	)
	(segment
		(start 9.016746 -498.9957)
		(end 9.321546 -498.6909)
		(width 0.254)
		(layer "F.Cu")
		(net "P5VC_MODE")
	)
	(segment
		(start 9.367012 -498.6782)
		(end 9.321546 -498.6782)
		(width 0.254)
		(layer "F.Cu")
		(net "P5VC_MODE")
	)
	(segment
		(start 9.769348 -498.275864)
		(end 9.367012 -498.6782)
		(width 0.254)
		(layer "F.Cu")
		(net "P5VC_MODE")
	)
	(segment
		(start 8.191246 -498.9957)
		(end 9.016746 -498.9957)
		(width 0.254)
		(layer "F.Cu")
		(net "P5VC_MODE")
	)
	(via
		(at 9.321546 -498.6782)
		(size 0.7112)
		(drill 0.3556)
		(layers "F.Cu" "B.Cu")
		(net "P5VC_MODE")
	)
	(segment
		(start 4.635246 -491.7567)
		(end 3.809746 -491.7567)
		(width 0.508)
		(layer "F.Cu")
		(net "P5VC_VREG")
	)
	(segment
		(start 4.393946 -498.1575)
		(end 4.444746 -498.1067)
		(width 0.508)
		(layer "F.Cu")
		(net "P5VC_VREG")
	)
	(segment
		(start 11.039348 -498.13464)
		(end 11.100816 -498.13464)
		(width 0.254)
		(layer "F.Cu")
		(net "P5VC_VREG")
	)
	(segment
		(start 11.100816 -498.13464)
		(end 11.302746 -498.33657)
		(width 0.254)
		(layer "F.Cu")
		(net "P5VC_VREG")
	)
	(segment
		(start 11.302746 -498.33657)
		(end 11.302746 -498.9322)
		(width 0.254)
		(layer "F.Cu")
		(net "P5VC_VREG")
	)
	(segment
		(start 10.769346 -496.91417)
		(end 10.769346 -497.80317)
		(width 0.254)
		(layer "F.Cu")
		(net "P5VC_VREG")
	)
	(segment
		(start 10.769346 -497.80317)
		(end 11.039348 -498.073172)
		(width 0.254)
		(layer "F.Cu")
		(net "P5VC_VREG")
	)
	(segment
		(start 5.079746 -499.9482)
		(end 4.889246 -499.9482)
		(width 0.508)
		(layer "F.Cu")
		(net "P5VC_VREG")
	)
	(segment
		(start 4.393946 -499.4529)
		(end 4.393946 -498.1575)
		(width 0.508)
		(layer "F.Cu")
		(net "P5VC_VREG")
	)
	(segment
		(start 4.889246 -499.9482)
		(end 4.393946 -499.4529)
		(width 0.508)
		(layer "F.Cu")
		(net "P5VC_VREG")
	)
	(segment
		(start 11.302746 -498.9322)
		(end 11.175746 -499.0592)
		(width 0.254)
		(layer "F.Cu")
		(net "P5VC_VREG")
	)
	(segment
		(start 11.039348 -498.073172)
		(end 11.039348 -498.13464)
		(width 0.254)
		(layer "F.Cu")
		(net "P5VC_VREG")
	)
	(via
		(at 11.039348 -498.13464)
		(size 0.5588)
		(drill 0.3048)
		(layers "F.Cu" "B.Cu")
		(net "P5VC_VREG")
	)
	(via
		(at 4.444746 -498.1067)
		(size 0.5588)
		(drill 0.3048)
		(layers "F.Cu" "B.Cu")
		(net "P5VC_VREG")
	)
	(via
		(at 3.809746 -491.7567)
		(size 0.5588)
		(drill 0.3048)
		(layers "F.Cu" "B.Cu")
		(net "P5VC_VREG")
	)
	(via
		(at 8.381746 -498.995446)
		(size 0.7112)
		(drill 0.3556)
		(layers "F.Cu" "B.Cu")
		(net "P5VC_VREG")
	)
	(segment
		(start 11.039348 -498.13464)
		(end 10.178542 -498.995446)
		(width 0.508)
		(layer "B.Cu")
		(net "P5VC_VREG")
	)
	(segment
		(start 10.178542 -498.995446)
		(end 8.381746 -498.995446)
		(width 0.508)
		(layer "B.Cu")
		(net "P5VC_VREG")
	)
	(segment
		(start 8.381746 -498.995446)
		(end 5.206492 -498.995446)
		(width 0.508)
		(layer "B.Cu")
		(net "P5VC_VREG")
	)
	(segment
		(start 4.647946 -497.0145)
		(end 4.647946 -492.5949)
		(width 0.508)
		(layer "B.Cu")
		(net "P5VC_VREG")
	)
	(segment
		(start 4.317746 -497.3447)
		(end 4.647946 -497.0145)
		(width 0.508)
		(layer "B.Cu")
		(net "P5VC_VREG")
	)
	(segment
		(start 5.206492 -498.995446)
		(end 4.444746 -498.2337)
		(width 0.508)
		(layer "B.Cu")
		(net "P5VC_VREG")
	)
	(segment
		(start 4.444746 -498.1067)
		(end 4.317746 -497.9797)
		(width 0.508)
		(layer "B.Cu")
		(net "P5VC_VREG")
	)
	(segment
		(start 4.647946 -492.5949)
		(end 3.809746 -491.7567)
		(width 0.508)
		(layer "B.Cu")
		(net "P5VC_VREG")
	)
	(segment
		(start 4.444746 -498.2337)
		(end 4.444746 -498.1067)
		(width 0.508)
		(layer "B.Cu")
		(net "P5VC_VREG")
	)
	(segment
		(start 4.317746 -497.9797)
		(end 4.317746 -497.3447)
		(width 0.508)
		(layer "B.Cu")
		(net "P5VC_VREG")
	)
	(segment
		(start 5.524246 -492.7727)
		(end 5.524246 -493.7887)
		(width 0.508)
		(layer "F.Cu")
		(net "P5VC_EN")
	)
	(segment
		(start 6.857746 -493.1537)
		(end 6.476746 -492.7727)
		(width 0.508)
		(layer "F.Cu")
		(net "P5VC_EN")
	)
	(segment
		(start 8.508746 -491.1217)
		(end 7.314946 -492.3155)
		(width 0.254)
		(layer "F.Cu")
		(net "P5VC_EN")
	)
	(segment
		(start 6.476746 -492.7727)
		(end 5.524246 -492.7727)
		(width 0.508)
		(layer "F.Cu")
		(net "P5VC_EN")
	)
	(segment
		(start 7.314946 -492.3155)
		(end 7.314946 -492.6965)
		(width 0.254)
		(layer "F.Cu")
		(net "P5VC_EN")
	)
	(segment
		(start 7.314946 -492.6965)
		(end 6.857746 -493.1537)
		(width 0.254)
		(layer "F.Cu")
		(net "P5VC_EN")
	)
	(segment
		(start 9.269476 -492.015526)
		(end 9.269476 -491.24743)
		(width 0.254)
		(layer "F.Cu")
		(net "P5VC_EN")
	)
	(segment
		(start 9.269476 -491.24743)
		(end 9.143746 -491.1217)
		(width 0.254)
		(layer "F.Cu")
		(net "P5VC_EN")
	)
	(segment
		(start 9.143746 -491.1217)
		(end 8.508746 -491.1217)
		(width 0.254)
		(layer "F.Cu")
		(net "P5VC_EN")
	)
	(segment
		(start 12.191746 -501.4087)
		(end 12.173204 -501.4087)
		(width 0.508)
		(layer "F.Cu")
		(net "P5VC_VDD")
	)
	(segment
		(start 10.508234 -501.0404)
		(end 10.327894 -501.0404)
		(width 0.508)
		(layer "F.Cu")
		(net "P5VC_VDD")
	)
	(segment
		(start 11.088878 -501.621044)
		(end 10.508234 -501.0404)
		(width 0.508)
		(layer "F.Cu")
		(net "P5VC_VDD")
	)
	(segment
		(start 10.269474 -499.444772)
		(end 10.269474 -496.91417)
		(width 0.254)
		(layer "F.Cu")
		(net "P5VC_VDD")
	)
	(segment
		(start 10.264394 -500.9769)
		(end 10.235946 -500.9769)
		(width 0.508)
		(layer "F.Cu")
		(net "P5VC_VDD")
	)
	(segment
		(start 10.327894 -501.0404)
		(end 10.264394 -500.9769)
		(width 0.508)
		(layer "F.Cu")
		(net "P5VC_VDD")
	)
	(segment
		(start 11.96086 -501.621044)
		(end 11.334496 -501.621044)
		(width 0.508)
		(layer "F.Cu")
		(net "P5VC_VDD")
	)
	(segment
		(start 9.651746 -500.3927)
		(end 9.651746 -500.0625)
		(width 0.508)
		(layer "F.Cu")
		(net "P5VC_VDD")
	)
	(segment
		(start 10.235946 -500.9769)
		(end 9.651746 -500.3927)
		(width 0.508)
		(layer "F.Cu")
		(net "P5VC_VDD")
	)
	(segment
		(start 11.334496 -501.621044)
		(end 11.088878 -501.621044)
		(width 0.508)
		(layer "F.Cu")
		(net "P5VC_VDD")
	)
	(segment
		(start 12.699746 -500.9007)
		(end 12.191746 -501.4087)
		(width 0.508)
		(layer "F.Cu")
		(net "P5VC_VDD")
	)
	(segment
		(start 12.173204 -501.4087)
		(end 11.96086 -501.621044)
		(width 0.508)
		(layer "F.Cu")
		(net "P5VC_VDD")
	)
	(segment
		(start 9.651746 -500.0625)
		(end 10.269474 -499.444772)
		(width 0.254)
		(layer "F.Cu")
		(net "P5VC_VDD")
	)
	(via
		(at 11.334496 -501.621044)
		(size 0.7112)
		(drill 0.3556)
		(layers "F.Cu" "B.Cu")
		(net "P5VC_VDD")
	)
	(segment
		(start 4.635246 -493.7887)
		(end 3.835146 -493.7887)
		(width 0.508)
		(layer "F.Cu")
		(net "P5VC_12VIN")
	)
	(via
		(at 20.954746 -497.0907)
		(size 0.7112)
		(drill 0.4064)
		(layers "F.Cu" "B.Cu")
		(net "P5VC_12VIN")
	)
	(via
		(at 3.835146 -493.7887)
		(size 0.5588)
		(drill 0.3048)
		(layers "F.Cu" "B.Cu")
		(net "P5VC_12VIN")
	)
	(via
		(at 14.985746 -497.3447)
		(size 0.7112)
		(drill 0.4064)
		(layers "F.Cu" "B.Cu")
		(net "P5VC_12VIN")
	)
	(via
		(at 16.890746 -497.0907)
		(size 0.7112)
		(drill 0.4064)
		(layers "F.Cu" "B.Cu")
		(net "P5VC_12VIN")
	)
	(via
		(at 23.494746 -497.5987)
		(size 0.7112)
		(drill 0.4064)
		(layers "F.Cu" "B.Cu")
		(net "P5VC_12VIN")
	)
	(via
		(at 12.826746 -498.2337)
		(size 0.5588)
		(drill 0.3048)
		(layers "F.Cu" "B.Cu")
		(net "P5VC_12VIN")
	)
	(via
		(at 18.668746 -497.0907)
		(size 0.7112)
		(drill 0.4064)
		(layers "F.Cu" "B.Cu")
		(net "P5VC_12VIN")
	)
	(via
		(at 9.524746 -499.808246)
		(size 0.7112)
		(drill 0.3556)
		(layers "F.Cu" "B.Cu")
		(net "P5VC_12VIN")
	)
	(segment
		(start 3.835146 -493.7887)
		(end 3.835146 -496.1255)
		(width 0.508)
		(layer "B.Cu")
		(net "P5VC_12VIN")
	)
	(segment
		(start 3.504946 -496.4557)
		(end 3.504946 -498.443504)
		(width 0.508)
		(layer "B.Cu")
		(net "P5VC_12VIN")
	)
	(segment
		(start 4.869688 -499.808246)
		(end 9.524746 -499.808246)
		(width 0.508)
		(layer "B.Cu")
		(net "P5VC_12VIN")
	)
	(segment
		(start 3.504946 -498.443504)
		(end 4.869688 -499.808246)
		(width 0.508)
		(layer "B.Cu")
		(net "P5VC_12VIN")
	)
	(segment
		(start 10.515346 -499.808246)
		(end 9.524746 -499.808246)
		(width 0.508)
		(layer "B.Cu")
		(net "P5VC_12VIN")
	)
	(segment
		(start 3.835146 -496.1255)
		(end 3.504946 -496.4557)
		(width 0.508)
		(layer "B.Cu")
		(net "P5VC_12VIN")
	)
	(segment
		(start 12.089892 -498.2337)
		(end 10.515346 -499.808246)
		(width 0.508)
		(layer "B.Cu")
		(net "P5VC_12VIN")
	)
	(segment
		(start 52.196746 -25.7302)
		(end 52.196746 -26.8097)
		(width 0.508)
		(layer "F.Cu")
		(net "P5VB_12VIN")
	)
	(via
		(at 56.1086 -9.8552)
		(size 0.7112)
		(drill 0.3556)
		(layers "F.Cu" "B.Cu")
		(net "P5VB_12VIN")
	)
	(via
		(at 52.196746 -26.8097)
		(size 0.5588)
		(drill 0.3048)
		(layers "F.Cu" "B.Cu")
		(net "P5VB_12VIN")
	)
	(via
		(at 57.276746 -14.7447)
		(size 0.7112)
		(drill 0.4064)
		(layers "F.Cu" "B.Cu")
		(net "P5VB_12VIN")
	)
	(via
		(at 58.8264 -16.1798)
		(size 0.7112)
		(drill 0.3556)
		(layers "F.Cu" "B.Cu")
		(net "P5VB_12VIN")
	)
	(via
		(at 57.276746 -17.4117)
		(size 0.5588)
		(drill 0.3048)
		(layers "F.Cu" "B.Cu")
		(net "P5VB_12VIN")
	)
	(via
		(at 57.276746 -11.8237)
		(size 0.7112)
		(drill 0.4064)
		(layers "F.Cu" "B.Cu")
		(net "P5VB_12VIN")
	)
	(via
		(at 57.276746 -13.3477)
		(size 0.7112)
		(drill 0.4064)
		(layers "F.Cu" "B.Cu")
		(net "P5VB_12VIN")
	)
	(via
		(at 58.4708 -9.9314)
		(size 0.7112)
		(drill 0.3556)
		(layers "F.Cu" "B.Cu")
		(net "P5VB_12VIN")
	)
	(via
		(at 57.276746 -16.1417)
		(size 0.7112)
		(drill 0.4064)
		(layers "F.Cu" "B.Cu")
		(net "P5VB_12VIN")
	)
	(segment
		(start 57.276746 -24.682704)
		(end 54.56555 -27.3939)
		(width 0.508)
		(layer "B.Cu")
		(net "P5VB_12VIN")
	)
	(segment
		(start 53.206142 -26.8097)
		(end 52.196746 -26.8097)
		(width 0.508)
		(layer "B.Cu")
		(net "P5VB_12VIN")
	)
	(segment
		(start 54.56555 -27.3939)
		(end 53.790342 -27.3939)
		(width 0.508)
		(layer "B.Cu")
		(net "P5VB_12VIN")
	)
	(segment
		(start 53.790342 -27.3939)
		(end 53.206142 -26.8097)
		(width 0.508)
		(layer "B.Cu")
		(net "P5VB_12VIN")
	)
	(segment
		(start 57.276746 -17.4117)
		(end 57.276746 -24.682704)
		(width 0.508)
		(layer "B.Cu")
		(net "P5VB_12VIN")
	)
	(segment
		(start 5.016246 -491.0582)
		(end 5.524246 -491.5662)
		(width 0.254)
		(layer "F.Cu")
		(net "P5VC_PGD")
	)
	(segment
		(start 2.158746 -492.1377)
		(end 3.238246 -491.0582)
		(width 0.254)
		(layer "F.Cu")
		(net "P5VC_PGD")
	)
	(segment
		(start 8.254746 -490.4867)
		(end 7.111746 -491.6297)
		(width 0.254)
		(layer "F.Cu")
		(net "P5VC_PGD")
	)
	(segment
		(start 7.111746 -491.6297)
		(end 6.730746 -491.6297)
		(width 0.254)
		(layer "F.Cu")
		(net "P5VC_PGD")
	)
	(segment
		(start 6.603746 -491.7567)
		(end 6.730746 -491.6297)
		(width 0.254)
		(layer "F.Cu")
		(net "P5VC_PGD")
	)
	(segment
		(start 5.524246 -491.5662)
		(end 5.524246 -491.7567)
		(width 0.254)
		(layer "F.Cu")
		(net "P5VC_PGD")
	)
	(segment
		(start 5.524246 -491.7567)
		(end 6.603746 -491.7567)
		(width 0.254)
		(layer "F.Cu")
		(net "P5VC_PGD")
	)
	(segment
		(start 8.127746 -502.6279)
		(end 8.076946 -502.6787)
		(width 0.508)
		(layer "F.Cu")
		(net "P5VC_PGD")
	)
	(segment
		(start 9.270746 -490.4867)
		(end 8.254746 -490.4867)
		(width 0.254)
		(layer "F.Cu")
		(net "P5VC_PGD")
	)
	(segment
		(start 9.769348 -490.985302)
		(end 9.270746 -490.4867)
		(width 0.254)
		(layer "F.Cu")
		(net "P5VC_PGD")
	)
	(segment
		(start 3.238246 -491.0582)
		(end 5.016246 -491.0582)
		(width 0.254)
		(layer "F.Cu")
		(net "P5VC_PGD")
	)
	(segment
		(start 9.769348 -492.015526)
		(end 9.769348 -490.985302)
		(width 0.254)
		(layer "F.Cu")
		(net "P5VC_PGD")
	)
	(segment
		(start 8.127746 -501.8532)
		(end 8.127746 -502.6279)
		(width 0.508)
		(layer "F.Cu")
		(net "P5VC_PGD")
	)
	(via
		(at 2.158746 -492.1377)
		(size 0.5588)
		(drill 0.3048)
		(layers "F.Cu" "B.Cu")
		(net "P5VC_PGD")
	)
	(via
		(at 8.076946 -502.6787)
		(size 0.5588)
		(drill 0.3048)
		(layers "F.Cu" "B.Cu")
		(net "P5VC_PGD")
	)
	(via
		(at 2.159762 -497.0018)
		(size 0.7112)
		(drill 0.3556)
		(layers "F.Cu" "B.Cu")
		(net "P5VC_PGD")
	)
	(segment
		(start 2.159762 -498.247924)
		(end 2.159762 -497.0018)
		(width 0.508)
		(layer "B.Cu")
		(net "P5VC_PGD")
	)
	(segment
		(start 8.076946 -502.6787)
		(end 6.590538 -502.6787)
		(width 0.508)
		(layer "B.Cu")
		(net "P5VC_PGD")
	)
	(segment
		(start 2.158746 -493.782096)
		(end 2.159762 -493.783112)
		(width 0.508)
		(layer "B.Cu")
		(net "P5VC_PGD")
	)
	(segment
		(start 6.590538 -502.6787)
		(end 2.159762 -498.247924)
		(width 0.508)
		(layer "B.Cu")
		(net "P5VC_PGD")
	)
	(segment
		(start 2.158746 -492.1377)
		(end 2.158746 -493.782096)
		(width 0.508)
		(layer "B.Cu")
		(net "P5VC_PGD")
	)
	(segment
		(start 2.159762 -493.783112)
		(end 2.159762 -497.0018)
		(width 0.508)
		(layer "B.Cu")
		(net "P5VC_PGD")
	)
	(segment
		(start 49.275746 -22.149054)
		(end 49.275746 -20.3327)
		(width 0.254)
		(layer "F.Cu")
		(net "P5VB_PGD")
	)
	(segment
		(start 49.351946 -25.393142)
		(end 49.903888 -24.8412)
		(width 0.508)
		(layer "F.Cu")
		(net "P5VB_PGD")
	)
	(segment
		(start 49.903888 -24.8412)
		(end 50.164746 -24.8412)
		(width 0.508)
		(layer "F.Cu")
		(net "P5VB_PGD")
	)
	(segment
		(start 50.095404 -22.968712)
		(end 49.275746 -22.149054)
		(width 0.254)
		(layer "F.Cu")
		(net "P5VB_PGD")
	)
	(segment
		(start 62.331346 -24.2697)
		(end 63.169546 -25.1079)
		(width 0.508)
		(layer "F.Cu")
		(net "P5VB_PGD")
	)
	(segment
		(start 49.275746 -20.3327)
		(end 49.68621 -19.922236)
		(width 0.254)
		(layer "F.Cu")
		(net "P5VB_PGD")
	)
	(segment
		(start 60.143644 -29.530802)
		(end 50.656744 -29.530802)
		(width 0.508)
		(layer "F.Cu")
		(net "P5VB_PGD")
	)
	(segment
		(start 50.656744 -29.530802)
		(end 49.351946 -28.226004)
		(width 0.508)
		(layer "F.Cu")
		(net "P5VB_PGD")
	)
	(segment
		(start 50.164746 -24.8412)
		(end 50.095404 -24.771858)
		(width 0.254)
		(layer "F.Cu")
		(net "P5VB_PGD")
	)
	(segment
		(start 63.169546 -26.5049)
		(end 60.143644 -29.530802)
		(width 0.508)
		(layer "F.Cu")
		(net "P5VB_PGD")
	)
	(segment
		(start 50.095404 -24.771858)
		(end 50.095404 -22.968712)
		(width 0.254)
		(layer "F.Cu")
		(net "P5VB_PGD")
	)
	(segment
		(start 61.404246 -24.2697)
		(end 62.331346 -24.2697)
		(width 0.508)
		(layer "F.Cu")
		(net "P5VB_PGD")
	)
	(segment
		(start 49.68621 -19.922236)
		(end 51.062382 -19.922236)
		(width 0.254)
		(layer "F.Cu")
		(net "P5VB_PGD")
	)
	(segment
		(start 49.351946 -28.226004)
		(end 49.351946 -25.393142)
		(width 0.508)
		(layer "F.Cu")
		(net "P5VB_PGD")
	)
	(segment
		(start 63.169546 -25.1079)
		(end 63.169546 -26.5049)
		(width 0.508)
		(layer "F.Cu")
		(net "P5VB_PGD")
	)
	(segment
		(start 57.657746 -22.720046)
		(end 57.657746 -21.711412)
		(width 0.254)
		(layer "F.Cu")
		(net "P5VB_MODE")
	)
	(segment
		(start 57.631584 -20.306538)
		(end 57.631584 -20.83943)
		(width 0.254)
		(layer "F.Cu")
		(net "P5VB_MODE")
	)
	(segment
		(start 57.657746 -21.711412)
		(end 57.663588 -21.70557)
		(width 0.254)
		(layer "F.Cu")
		(net "P5VB_MODE")
	)
	(segment
		(start 57.247282 -19.922236)
		(end 57.631584 -20.306538)
		(width 0.254)
		(layer "F.Cu")
		(net "P5VB_MODE")
	)
	(segment
		(start 57.657746 -21.5265)
		(end 57.663588 -21.532342)
		(width 0.254)
		(layer "F.Cu")
		(net "P5VB_MODE")
	)
	(segment
		(start 57.657746 -20.865592)
		(end 57.657746 -21.5265)
		(width 0.254)
		(layer "F.Cu")
		(net "P5VB_MODE")
	)
	(segment
		(start 55.961026 -19.922236)
		(end 57.247282 -19.922236)
		(width 0.254)
		(layer "F.Cu")
		(net "P5VB_MODE")
	)
	(segment
		(start 57.663588 -21.532342)
		(end 57.663588 -21.660612)
		(width 0.254)
		(layer "F.Cu")
		(net "P5VB_MODE")
	)
	(segment
		(start 57.631584 -20.83943)
		(end 57.657746 -20.865592)
		(width 0.254)
		(layer "F.Cu")
		(net "P5VB_MODE")
	)
	(segment
		(start 58.450988 -23.513288)
		(end 57.657746 -22.720046)
		(width 0.254)
		(layer "F.Cu")
		(net "P5VB_MODE")
	)
	(segment
		(start 57.663588 -21.70557)
		(end 57.663588 -21.660612)
		(width 0.254)
		(layer "F.Cu")
		(net "P5VB_MODE")
	)
	(via
		(at 57.663588 -21.660612)
		(size 0.7112)
		(drill 0.3556)
		(layers "F.Cu" "B.Cu")
		(net "P5VB_MODE")
	)
	(segment
		(start 47.116746 -30.6832)
		(end 48.005746 -30.6832)
		(width 0.508)
		(layer "F.Cu")
		(net "P5VB_VFB_NET")
	)
	(segment
		(start 55.244746 -25.7302)
		(end 55.689246 -25.7302)
		(width 0.508)
		(layer "F.Cu")
		(net "P5VB_VFB_NET")
	)
	(segment
		(start 55.689246 -25.7302)
		(end 56.768746 -26.8097)
		(width 0.508)
		(layer "F.Cu")
		(net "P5VB_VFB_NET")
	)
	(segment
		(start 56.768746 -26.8097)
		(end 56.768746 -27.4701)
		(width 0.508)
		(layer "F.Cu")
		(net "P5VB_VFB_NET")
	)
	(via
		(at 48.005746 -30.6832)
		(size 0.5588)
		(drill 0.3048)
		(layers "F.Cu" "B.Cu")
		(net "P5VB_VFB_NET")
	)
	(via
		(at 56.768746 -27.4701)
		(size 0.5588)
		(drill 0.3048)
		(layers "F.Cu" "B.Cu")
		(net "P5VB_VFB_NET")
	)
	(via
		(at 51.942746 -29.6037)
		(size 0.7112)
		(drill 0.3556)
		(layers "F.Cu" "B.Cu")
		(net "P5VB_VFB_NET")
	)
	(segment
		(start 56.768746 -27.4701)
		(end 56.768746 -27.6225)
		(width 0.508)
		(layer "B.Cu")
		(net "P5VB_VFB_NET")
	)
	(segment
		(start 49.212246 -30.6832)
		(end 50.291746 -29.6037)
		(width 0.508)
		(layer "B.Cu")
		(net "P5VB_VFB_NET")
	)
	(segment
		(start 54.787546 -29.6037)
		(end 51.942746 -29.6037)
		(width 0.508)
		(layer "B.Cu")
		(net "P5VB_VFB_NET")
	)
	(segment
		(start 56.768746 -27.6225)
		(end 54.787546 -29.6037)
		(width 0.508)
		(layer "B.Cu")
		(net "P5VB_VFB_NET")
	)
	(segment
		(start 48.005746 -30.6832)
		(end 49.212246 -30.6832)
		(width 0.508)
		(layer "B.Cu")
		(net "P5VB_VFB_NET")
	)
	(segment
		(start 50.291746 -29.6037)
		(end 51.942746 -29.6037)
		(width 0.508)
		(layer "B.Cu")
		(net "P5VB_VFB_NET")
	)
	(segment
		(start 236.854746 -28.835096)
		(end 236.803692 -28.88615)
		(width 0.508)
		(layer "F.Cu")
		(net "P5VA_VFB_NET")
	)
	(segment
		(start 229.488746 -33.4772)
		(end 230.504746 -33.4772)
		(width 0.508)
		(layer "F.Cu")
		(net "P5VA_VFB_NET")
	)
	(segment
		(start 236.803692 -29.152088)
		(end 236.60608 -29.3497)
		(width 0.508)
		(layer "F.Cu")
		(net "P5VA_VFB_NET")
	)
	(segment
		(start 236.803692 -28.88615)
		(end 236.803692 -29.152088)
		(width 0.508)
		(layer "F.Cu")
		(net "P5VA_VFB_NET")
	)
	(segment
		(start 236.854746 -28.3972)
		(end 236.854746 -28.835096)
		(width 0.508)
		(layer "F.Cu")
		(net "P5VA_VFB_NET")
	)
	(segment
		(start 236.60608 -29.3497)
		(end 236.473746 -29.3497)
		(width 0.508)
		(layer "F.Cu")
		(net "P5VA_VFB_NET")
	)
	(via
		(at 236.473746 -29.3497)
		(size 0.5588)
		(drill 0.3048)
		(layers "F.Cu" "B.Cu")
		(net "P5VA_VFB_NET")
	)
	(via
		(at 230.504746 -33.4772)
		(size 0.5588)
		(drill 0.3048)
		(layers "F.Cu" "B.Cu")
		(net "P5VA_VFB_NET")
	)
	(via
		(at 233.563668 -31.497778)
		(size 0.7112)
		(drill 0.3556)
		(layers "F.Cu" "B.Cu")
		(net "P5VA_VFB_NET")
	)
	(segment
		(start 234.949746 -30.1117)
		(end 233.563668 -31.497778)
		(width 0.508)
		(layer "B.Cu")
		(net "P5VA_VFB_NET")
	)
	(segment
		(start 236.473746 -29.3497)
		(end 235.711746 -30.1117)
		(width 0.508)
		(layer "B.Cu")
		(net "P5VA_VFB_NET")
	)
	(segment
		(start 230.504746 -33.4772)
		(end 231.584246 -33.4772)
		(width 0.508)
		(layer "B.Cu")
		(net "P5VA_VFB_NET")
	)
	(segment
		(start 231.584246 -33.4772)
		(end 233.563668 -31.497778)
		(width 0.508)
		(layer "B.Cu")
		(net "P5VA_VFB_NET")
	)
	(segment
		(start 235.711746 -30.1117)
		(end 234.949746 -30.1117)
		(width 0.508)
		(layer "B.Cu")
		(net "P5VA_VFB_NET")
	)
	(segment
		(start 51.561746 -21.848064)
		(end 52.56911 -21.848064)
		(width 0.254)
		(layer "F.Cu")
		(net "P5VB_VFB")
	)
	(segment
		(start 52.56911 -21.848064)
		(end 53.085746 -22.3647)
		(width 0.254)
		(layer "F.Cu")
		(net "P5VB_VFB")
	)
	(segment
		(start 53.212746 -24.8412)
		(end 53.085746 -24.7142)
		(width 0.254)
		(layer "F.Cu")
		(net "P5VB_VFB")
	)
	(segment
		(start 53.085746 -22.3647)
		(end 53.085746 -23.3807)
		(width 0.254)
		(layer "F.Cu")
		(net "P5VB_VFB")
	)
	(segment
		(start 51.062382 -21.3487)
		(end 51.561746 -21.848064)
		(width 0.254)
		(layer "F.Cu")
		(net "P5VB_VFB")
	)
	(segment
		(start 51.062382 -20.922234)
		(end 51.062382 -21.3487)
		(width 0.254)
		(layer "F.Cu")
		(net "P5VB_VFB")
	)
	(segment
		(start 53.085746 -24.7142)
		(end 53.085746 -23.3807)
		(width 0.254)
		(layer "F.Cu")
		(net "P5VB_VFB")
	)
	(segment
		(start 54.228746 -24.8412)
		(end 53.212746 -24.8412)
		(width 0.254)
		(layer "F.Cu")
		(net "P5VB_VFB")
	)
	(segment
		(start 55.244746 -24.8412)
		(end 54.228746 -24.8412)
		(width 0.254)
		(layer "F.Cu")
		(net "P5VB_VFB")
	)
	(via
		(at 53.085746 -23.3807)
		(size 0.7112)
		(drill 0.3556)
		(layers "F.Cu" "B.Cu")
		(net "P5VB_VFB")
	)
	(segment
		(start 44.449746 -18.9992)
		(end 44.449746 -20.0787)
		(width 0.508)
		(layer "F.Cu")
		(net "P5VB_LL_NET")
	)
	(segment
		(start 46.545246 -25.1587)
		(end 47.497746 -25.1587)
		(width 0.508)
		(layer "F.Cu")
		(net "P5VB_LL_NET")
	)
	(segment
		(start 54.228746 -25.7302)
		(end 54.228746 -26.5811)
		(width 0.508)
		(layer "F.Cu")
		(net "P5VB_LL_NET")
	)
	(via
		(at 49.656746 -25.1587)
		(size 0.7112)
		(drill 0.3556)
		(layers "F.Cu" "B.Cu")
		(net "P5VB_LL_NET")
	)
	(via
		(at 47.497746 -25.1587)
		(size 0.5588)
		(drill 0.3048)
		(layers "F.Cu" "B.Cu")
		(net "P5VB_LL_NET")
	)
	(via
		(at 44.449746 -20.0787)
		(size 0.5588)
		(drill 0.3048)
		(layers "F.Cu" "B.Cu")
		(net "P5VB_LL_NET")
	)
	(via
		(at 54.228746 -26.5811)
		(size 0.5588)
		(drill 0.3048)
		(layers "F.Cu" "B.Cu")
		(net "P5VB_LL_NET")
	)
	(segment
		(start 45.128942 -19.2659)
		(end 44.449746 -19.945096)
		(width 0.508)
		(layer "B.Cu")
		(net "P5VB_LL_NET")
	)
	(segment
		(start 47.497746 -25.1587)
		(end 47.378112 -25.039066)
		(width 0.508)
		(layer "B.Cu")
		(net "P5VB_LL_NET")
	)
	(segment
		(start 44.449746 -19.945096)
		(end 44.449746 -20.0787)
		(width 0.508)
		(layer "B.Cu")
		(net "P5VB_LL_NET")
	)
	(segment
		(start 52.806346 -25.1587)
		(end 49.656746 -25.1587)
		(width 0.508)
		(layer "B.Cu")
		(net "P5VB_LL_NET")
	)
	(segment
		(start 49.656746 -25.1587)
		(end 47.497746 -25.1587)
		(width 0.508)
		(layer "B.Cu")
		(net "P5VB_LL_NET")
	)
	(segment
		(start 47.378112 -25.039066)
		(end 47.378112 -20.841462)
		(width 0.508)
		(layer "B.Cu")
		(net "P5VB_LL_NET")
	)
	(segment
		(start 54.228746 -26.5811)
		(end 52.806346 -25.1587)
		(width 0.508)
		(layer "B.Cu")
		(net "P5VB_LL_NET")
	)
	(segment
		(start 45.80255 -19.2659)
		(end 45.128942 -19.2659)
		(width 0.508)
		(layer "B.Cu")
		(net "P5VB_LL_NET")
	)
	(segment
		(start 47.378112 -20.841462)
		(end 45.80255 -19.2659)
		(width 0.508)
		(layer "B.Cu")
		(net "P5VB_LL_NET")
	)
	(segment
		(start 179.958746 -459.393036)
		(end 179.971446 -459.380336)
		(width 0.508)
		(layer "F.Cu")
		(net "P12V_DIV")
	)
	(segment
		(start 180.987446 -459.380336)
		(end 182.88 -459.380336)
		(width 0.508)
		(layer "F.Cu")
		(net "P12V_DIV")
	)
	(segment
		(start 182.88 -459.380336)
		(end 182.9562 -459.456536)
		(width 0.508)
		(layer "F.Cu")
		(net "P12V_DIV")
	)
	(segment
		(start 179.971446 -459.380336)
		(end 180.987446 -459.380336)
		(width 0.508)
		(layer "F.Cu")
		(net "P12V_DIV")
	)
	(segment
		(start 178.002946 -459.393036)
		(end 179.958746 -459.393036)
		(width 0.508)
		(layer "F.Cu")
		(net "P12V_DIV")
	)
	(via
		(at 182.9562 -459.456536)
		(size 0.7112)
		(drill 0.3556)
		(layers "F.Cu" "B.Cu")
		(net "P12V_DIV")
	)
	(segment
		(start 164.858446 -459.964536)
		(end 166.318946 -459.964536)
		(width 0.111252)
		(layer "F.Cu")
		(net "VOL_SEN_ALERT")
	)
	(segment
		(start 169.265346 -460.401416)
		(end 169.257726 -460.409036)
		(width 0.111252)
		(layer "F.Cu")
		(net "VOL_SEN_ALERT")
	)
	(segment
		(start 166.318946 -459.964536)
		(end 166.382446 -459.901036)
		(width 0.111252)
		(layer "F.Cu")
		(net "VOL_SEN_ALERT")
	)
	(segment
		(start 166.890446 -460.409036)
		(end 166.382446 -459.901036)
		(width 0.111252)
		(layer "F.Cu")
		(net "VOL_SEN_ALERT")
	)
	(segment
		(start 169.257726 -460.409036)
		(end 166.890446 -460.409036)
		(width 0.111252)
		(layer "F.Cu")
		(net "VOL_SEN_ALERT")
	)
	(segment
		(start 166.509446 -461.996536)
		(end 167.461946 -462.949036)
		(width 0.111252)
		(layer "F.Cu")
		(net "VOL_SEN_ADDR")
	)
	(segment
		(start 168.795446 -462.949036)
		(end 168.033446 -462.949036)
		(width 0.111252)
		(layer "F.Cu")
		(net "VOL_SEN_ADDR")
	)
	(segment
		(start 167.461946 -462.949036)
		(end 168.033446 -462.949036)
		(width 0.111252)
		(layer "F.Cu")
		(net "VOL_SEN_ADDR")
	)
	(segment
		(start 169.265346 -460.900526)
		(end 169.265346 -462.479136)
		(width 0.111252)
		(layer "F.Cu")
		(net "VOL_SEN_ADDR")
	)
	(segment
		(start 165.429946 -461.933036)
		(end 165.493446 -461.996536)
		(width 0.111252)
		(layer "F.Cu")
		(net "VOL_SEN_ADDR")
	)
	(segment
		(start 169.265346 -462.479136)
		(end 168.795446 -462.949036)
		(width 0.111252)
		(layer "F.Cu")
		(net "VOL_SEN_ADDR")
	)
	(segment
		(start 165.493446 -461.996536)
		(end 166.509446 -461.996536)
		(width 0.111252)
		(layer "F.Cu")
		(net "VOL_SEN_ADDR")
	)
	(via
		(at 168.033446 -462.949036)
		(size 0.7112)
		(drill 0.3556)
		(layers "F.Cu" "B.Cu")
		(net "VOL_SEN_ADDR")
	)
	(segment
		(start 171.487846 -461.137)
		(end 171.487846 -462.25079)
		(width 0.111252)
		(layer "F.Cu")
		(net "VOL_SEN_SCL")
	)
	(segment
		(start 176.047146 -462.872836)
		(end 174.510446 -462.872836)
		(width 0.111252)
		(layer "F.Cu")
		(net "VOL_SEN_SCL")
	)
	(segment
		(start 171.487846 -462.25079)
		(end 172.109892 -462.872836)
		(width 0.111252)
		(layer "F.Cu")
		(net "VOL_SEN_SCL")
	)
	(segment
		(start 172.109892 -462.872836)
		(end 174.510446 -462.872836)
		(width 0.111252)
		(layer "F.Cu")
		(net "VOL_SEN_SCL")
	)
	(segment
		(start 176.224946 -462.695036)
		(end 176.047146 -462.872836)
		(width 0.111252)
		(layer "F.Cu")
		(net "VOL_SEN_SCL")
	)
	(segment
		(start 171.72432 -460.900526)
		(end 171.487846 -461.137)
		(width 0.111252)
		(layer "F.Cu")
		(net "VOL_SEN_SCL")
	)
	(segment
		(start 173.405546 -460.900526)
		(end 171.72432 -460.900526)
		(width 0.111252)
		(layer "F.Cu")
		(net "VOL_SEN_SCL")
	)
	(via
		(at 174.510446 -462.872836)
		(size 0.7112)
		(drill 0.3556)
		(layers "F.Cu" "B.Cu")
		(net "VOL_SEN_SCL")
	)
	(segment
		(start 171.005246 -462.450942)
		(end 172.16374 -463.609436)
		(width 0.111252)
		(layer "F.Cu")
		(net "VOL_SEN_SDA")
	)
	(segment
		(start 176.123346 -463.609436)
		(end 173.113446 -463.609436)
		(width 0.111252)
		(layer "F.Cu")
		(net "VOL_SEN_SDA")
	)
	(segment
		(start 173.405546 -460.401416)
		(end 171.38396 -460.401416)
		(width 0.111252)
		(layer "F.Cu")
		(net "VOL_SEN_SDA")
	)
	(segment
		(start 172.16374 -463.609436)
		(end 173.113446 -463.609436)
		(width 0.111252)
		(layer "F.Cu")
		(net "VOL_SEN_SDA")
	)
	(segment
		(start 171.005246 -460.78013)
		(end 171.005246 -462.450942)
		(width 0.111252)
		(layer "F.Cu")
		(net "VOL_SEN_SDA")
	)
	(segment
		(start 176.224946 -463.711036)
		(end 176.123346 -463.609436)
		(width 0.111252)
		(layer "F.Cu")
		(net "VOL_SEN_SDA")
	)
	(segment
		(start 171.38396 -460.401416)
		(end 171.005246 -460.78013)
		(width 0.111252)
		(layer "F.Cu")
		(net "VOL_SEN_SDA")
	)
	(via
		(at 173.113446 -463.609436)
		(size 0.7112)
		(drill 0.3556)
		(layers "F.Cu" "B.Cu")
		(net "VOL_SEN_SDA")
	)
	(segment
		(start 3.193542 -217.50147)
		(end 3.19024 -217.504772)
		(width 0.111252)
		(layer "F.Cu")
		(net "EXP_A_PRNST_RX")
	)
	(segment
		(start 6.772148 -218.8337)
		(end 6.5151 -218.8337)
		(width 0.111252)
		(layer "F.Cu")
		(net "EXP_A_PRNST_RX")
	)
	(segment
		(start 5.18287 -217.50147)
		(end 3.193542 -217.50147)
		(width 0.111252)
		(layer "F.Cu")
		(net "EXP_A_PRNST_RX")
	)
	(segment
		(start 10.604246 -467.8807)
		(end 11.43 -467.8807)
		(width 0.111252)
		(layer "F.Cu")
		(net "EXP_A_PRNST_RX")
	)
	(segment
		(start 6.5151 -218.8337)
		(end 5.18287 -217.50147)
		(width 0.111252)
		(layer "F.Cu")
		(net "EXP_A_PRNST_RX")
	)
	(segment
		(start 11.43 -467.8807)
		(end 11.980164 -467.330536)
		(width 0.111252)
		(layer "F.Cu")
		(net "EXP_A_PRNST_RX")
	)
	(via
		(at 11.980164 -467.330536)
		(size 0.5588)
		(drill 0.3048)
		(layers "F.Cu" "B.Cu")
		(net "EXP_A_PRNST_RX")
	)
	(via
		(at 12.602464 -468.037418)
		(size 0.7112)
		(drill 0.3556)
		(layers "F.Cu" "B.Cu")
		(net "EXP_A_PRNST_RX")
	)
	(via
		(at 6.772148 -218.8337)
		(size 0.5588)
		(drill 0.3048)
		(layers "F.Cu" "B.Cu")
		(net "EXP_A_PRNST_RX")
	)
	(segment
		(start 11.980164 -467.415118)
		(end 12.602464 -468.037418)
		(width 0.111252)
		(layer "B.Cu")
		(net "EXP_A_PRNST_RX")
	)
	(segment
		(start 11.980164 -467.330536)
		(end 11.980164 -467.415118)
		(width 0.111252)
		(layer "B.Cu")
		(net "EXP_A_PRNST_RX")
	)
	(segment
		(start 6.920992 -378.5616)
		(end 7.493 -379.133608)
		(width 0.14605)
		(layer "In2.Cu")
		(net "EXP_A_PRNST_RX")
	)
	(segment
		(start 9.22909 -363.70514)
		(end 9.094216 -363.840014)
		(width 0.14605)
		(layer "In2.Cu")
		(net "EXP_A_PRNST_RX")
	)
	(segment
		(start 6.862572 -386.307584)
		(end 6.629908 -386.540248)
		(width 0.14605)
		(layer "In2.Cu")
		(net "EXP_A_PRNST_RX")
	)
	(segment
		(start 5.239004 -387.280404)
		(end 5.202936 -387.367526)
		(width 0.14605)
		(layer "In2.Cu")
		(net "EXP_A_PRNST_RX")
	)
	(segment
		(start 9.228836 -269.396972)
		(end 9.22909 -269.397226)
		(width 0.14605)
		(layer "In2.Cu")
		(net "EXP_A_PRNST_RX")
	)
	(segment
		(start 10.000996 -261.014718)
		(end 10.00125 -261.014972)
		(width 0.14605)
		(layer "In2.Cu")
		(net "EXP_A_PRNST_RX")
	)
	(segment
		(start 9.090152 -363.904022)
		(end 9.090152 -365.399066)
		(width 0.14605)
		(layer "In2.Cu")
		(net "EXP_A_PRNST_RX")
	)
	(segment
		(start 6.83514 -458.456792)
		(end 6.83514 -460.947516)
		(width 0.14605)
		(layer "In2.Cu")
		(net "EXP_A_PRNST_RX")
	)
	(segment
		(start 0.842772 -431.493422)
		(end 0.842772 -452.425308)
		(width 0.14605)
		(layer "In2.Cu")
		(net "EXP_A_PRNST_RX")
	)
	(segment
		(start 8.80618 -254.52959)
		(end 8.054594 -255.281176)
		(width 0.14605)
		(layer "In2.Cu")
		(net "EXP_A_PRNST_RX")
	)
	(segment
		(start 6.500368 -371.105684)
		(end 6.500368 -377.696222)
		(width 0.14605)
		(layer "In2.Cu")
		(net "EXP_A_PRNST_RX")
	)
	(segment
		(start 6.480302 -371.036342)
		(end 6.500368 -371.105684)
		(width 0.14605)
		(layer "In2.Cu")
		(net "EXP_A_PRNST_RX")
	)
	(segment
		(start 7.292594 -367.196624)
		(end 7.098284 -367.196624)
		(width 0.14605)
		(layer "In2.Cu")
		(net "EXP_A_PRNST_RX")
	)
	(segment
		(start 5.28955 -387.198616)
		(end 5.28955 -387.204712)
		(width 0.14605)
		(layer "In2.Cu")
		(net "EXP_A_PRNST_RX")
	)
	(segment
		(start 6.825488 -458.408024)
		(end 6.83514 -458.456792)
		(width 0.14605)
		(layer "In2.Cu")
		(net "EXP_A_PRNST_RX")
	)
	(segment
		(start 5.184394 -427.1518)
		(end 0.842772 -431.493422)
		(width 0.14605)
		(layer "In2.Cu")
		(net "EXP_A_PRNST_RX")
	)
	(segment
		(start 5.947918 -386.540248)
		(end 5.28955 -387.198616)
		(width 0.14605)
		(layer "In2.Cu")
		(net "EXP_A_PRNST_RX")
	)
	(segment
		(start 9.090152 -365.399066)
		(end 7.292594 -367.196624)
		(width 0.14605)
		(layer "In2.Cu")
		(net "EXP_A_PRNST_RX")
	)
	(segment
		(start 6.772148 -218.8337)
		(end 8.80618 -220.867732)
		(width 0.14605)
		(layer "In2.Cu")
		(net "EXP_A_PRNST_RX")
	)
	(segment
		(start 9.093962 -363.885226)
		(end 9.090152 -363.904022)
		(width 0.14605)
		(layer "In2.Cu")
		(net "EXP_A_PRNST_RX")
	)
	(segment
		(start 9.483852 -259.874258)
		(end 10.000996 -260.431026)
		(width 0.14605)
		(layer "In2.Cu")
		(net "EXP_A_PRNST_RX")
	)
	(segment
		(start 5.698744 -465.079334)
		(end 7.949946 -467.330536)
		(width 0.14605)
		(layer "In2.Cu")
		(net "EXP_A_PRNST_RX")
	)
	(segment
		(start 6.862572 -380.284228)
		(end 6.862572 -386.307584)
		(width 0.14605)
		(layer "In2.Cu")
		(net "EXP_A_PRNST_RX")
	)
	(segment
		(start 8.054594 -255.281176)
		(end 8.054594 -257.761994)
		(width 0.14605)
		(layer "In2.Cu")
		(net "EXP_A_PRNST_RX")
	)
	(segment
		(start 7.493 -379.133608)
		(end 7.493 -379.6538)
		(width 0.14605)
		(layer "In2.Cu")
		(net "EXP_A_PRNST_RX")
	)
	(segment
		(start 6.480048 -371.035834)
		(end 6.480302 -371.036342)
		(width 0.14605)
		(layer "In2.Cu")
		(net "EXP_A_PRNST_RX")
	)
	(segment
		(start 6.5024 -370.184172)
		(end 6.461252 -370.22532)
		(width 0.14605)
		(layer "In2.Cu")
		(net "EXP_A_PRNST_RX")
	)
	(segment
		(start 6.83514 -460.947516)
		(end 6.825488 -460.996284)
		(width 0.14605)
		(layer "In2.Cu")
		(net "EXP_A_PRNST_RX")
	)
	(segment
		(start 7.493 -379.6538)
		(end 6.862572 -380.284228)
		(width 0.14605)
		(layer "In2.Cu")
		(net "EXP_A_PRNST_RX")
	)
	(segment
		(start 8.80618 -220.867732)
		(end 8.80618 -254.52959)
		(width 0.14605)
		(layer "In2.Cu")
		(net "EXP_A_PRNST_RX")
	)
	(segment
		(start 6.461252 -370.809012)
		(end 6.463284 -370.831872)
		(width 0.14605)
		(layer "In2.Cu")
		(net "EXP_A_PRNST_RX")
	)
	(segment
		(start 6.825488 -460.996284)
		(end 5.698744 -462.123028)
		(width 0.14605)
		(layer "In2.Cu")
		(net "EXP_A_PRNST_RX")
	)
	(segment
		(start 6.920992 -378.116846)
		(end 6.920992 -378.5616)
		(width 0.14605)
		(layer "In2.Cu")
		(net "EXP_A_PRNST_RX")
	)
	(segment
		(start 9.22909 -269.397226)
		(end 9.22909 -363.70514)
		(width 0.14605)
		(layer "In2.Cu")
		(net "EXP_A_PRNST_RX")
	)
	(segment
		(start 8.054594 -257.761994)
		(end 9.483852 -259.191252)
		(width 0.14605)
		(layer "In2.Cu")
		(net "EXP_A_PRNST_RX")
	)
	(segment
		(start 6.480048 -371.035072)
		(end 6.480048 -371.035834)
		(width 0.14605)
		(layer "In2.Cu")
		(net "EXP_A_PRNST_RX")
	)
	(segment
		(start 9.483852 -259.191252)
		(end 9.483852 -259.874258)
		(width 0.14605)
		(layer "In2.Cu")
		(net "EXP_A_PRNST_RX")
	)
	(segment
		(start 7.949946 -467.330536)
		(end 11.980164 -467.330536)
		(width 0.14605)
		(layer "In2.Cu")
		(net "EXP_A_PRNST_RX")
	)
	(segment
		(start 6.629908 -386.540248)
		(end 5.947918 -386.540248)
		(width 0.14605)
		(layer "In2.Cu")
		(net "EXP_A_PRNST_RX")
	)
	(segment
		(start 6.47573 -370.982494)
		(end 6.480048 -371.035072)
		(width 0.14605)
		(layer "In2.Cu")
		(net "EXP_A_PRNST_RX")
	)
	(segment
		(start 10.00125 -261.014972)
		(end 10.00125 -263.390634)
		(width 0.14605)
		(layer "In2.Cu")
		(net "EXP_A_PRNST_RX")
	)
	(segment
		(start 6.500368 -377.696222)
		(end 6.920992 -378.116846)
		(width 0.14605)
		(layer "In2.Cu")
		(net "EXP_A_PRNST_RX")
	)
	(segment
		(start 6.461252 -370.22532)
		(end 6.461252 -370.809012)
		(width 0.14605)
		(layer "In2.Cu")
		(net "EXP_A_PRNST_RX")
	)
	(segment
		(start 5.184394 -387.460236)
		(end 5.184394 -427.1518)
		(width 0.14605)
		(layer "In2.Cu")
		(net "EXP_A_PRNST_RX")
	)
	(segment
		(start 0.842772 -452.425308)
		(end 6.825488 -458.408024)
		(width 0.14605)
		(layer "In2.Cu")
		(net "EXP_A_PRNST_RX")
	)
	(segment
		(start 9.228836 -264.163048)
		(end 9.228836 -269.396972)
		(width 0.14605)
		(layer "In2.Cu")
		(net "EXP_A_PRNST_RX")
	)
	(segment
		(start 5.28955 -387.204712)
		(end 5.239004 -387.280404)
		(width 0.14605)
		(layer "In2.Cu")
		(net "EXP_A_PRNST_RX")
	)
	(segment
		(start 9.094216 -363.840014)
		(end 9.093962 -363.885226)
		(width 0.14605)
		(layer "In2.Cu")
		(net "EXP_A_PRNST_RX")
	)
	(segment
		(start 5.698744 -462.123028)
		(end 5.698744 -465.079334)
		(width 0.14605)
		(layer "In2.Cu")
		(net "EXP_A_PRNST_RX")
	)
	(segment
		(start 6.463284 -370.831872)
		(end 6.47573 -370.982494)
		(width 0.14605)
		(layer "In2.Cu")
		(net "EXP_A_PRNST_RX")
	)
	(segment
		(start 6.5024 -367.792508)
		(end 6.5024 -370.184172)
		(width 0.14605)
		(layer "In2.Cu")
		(net "EXP_A_PRNST_RX")
	)
	(segment
		(start 5.202936 -387.367526)
		(end 5.184394 -387.460236)
		(width 0.14605)
		(layer "In2.Cu")
		(net "EXP_A_PRNST_RX")
	)
	(segment
		(start 10.000996 -260.431026)
		(end 10.000996 -261.014718)
		(width 0.14605)
		(layer "In2.Cu")
		(net "EXP_A_PRNST_RX")
	)
	(segment
		(start 7.098284 -367.196624)
		(end 6.5024 -367.792508)
		(width 0.14605)
		(layer "In2.Cu")
		(net "EXP_A_PRNST_RX")
	)
	(segment
		(start 10.00125 -263.390634)
		(end 9.228836 -264.163048)
		(width 0.14605)
		(layer "In2.Cu")
		(net "EXP_A_PRNST_RX")
	)
	(segment
		(start 11.937746 -465.4677)
		(end 11.061446 -466.344)
		(width 0.111252)
		(layer "F.Cu")
		(net "EXP_B_PRNST_RX")
	)
	(segment
		(start 10.235946 -466.344)
		(end 9.715246 -466.8647)
		(width 0.111252)
		(layer "F.Cu")
		(net "EXP_B_PRNST_RX")
	)
	(segment
		(start 11.061446 -466.344)
		(end 10.235946 -466.344)
		(width 0.111252)
		(layer "F.Cu")
		(net "EXP_B_PRNST_RX")
	)
	(segment
		(start 9.078468 -467.501478)
		(end 3.193542 -467.501478)
		(width 0.111252)
		(layer "F.Cu")
		(net "EXP_B_PRNST_RX")
	)
	(segment
		(start 3.193542 -467.501478)
		(end 3.19024 -467.50478)
		(width 0.111252)
		(layer "F.Cu")
		(net "EXP_B_PRNST_RX")
	)
	(segment
		(start 9.715246 -466.8647)
		(end 9.078468 -467.501478)
		(width 0.111252)
		(layer "F.Cu")
		(net "EXP_B_PRNST_RX")
	)
	(via
		(at 11.937746 -465.4677)
		(size 0.7112)
		(drill 0.3556)
		(layers "F.Cu" "B.Cu")
		(net "EXP_B_PRNST_RX")
	)
	(segment
		(start 10.604246 -466.8647)
		(end 11.429746 -466.8647)
		(width 0.111252)
		(layer "F.Cu")
		(net "EXP_B_PRNST_TX")
	)
	(segment
		(start 11.429746 -466.8647)
		(end 11.810746 -466.4837)
		(width 0.111252)
		(layer "F.Cu")
		(net "EXP_B_PRNST_TX")
	)
	(via
		(at 11.810746 -466.4837)
		(size 0.5588)
		(drill 0.3048)
		(layers "F.Cu" "B.Cu")
		(net "EXP_B_PRNST_TX")
	)
	(via
		(at 12.750546 -466.357208)
		(size 0.7112)
		(drill 0.3556)
		(layers "F.Cu" "B.Cu")
		(net "EXP_B_PRNST_TX")
	)
	(via
		(at 5.917946 -219.2147)
		(size 0.5588)
		(drill 0.3048)
		(layers "F.Cu" "B.Cu")
		(net "EXP_B_PRNST_TX")
	)
	(segment
		(start 2.812542 -217.50147)
		(end 2.80924 -217.504772)
		(width 0.111252)
		(layer "B.Cu")
		(net "EXP_B_PRNST_TX")
	)
	(segment
		(start 5.271516 -217.50147)
		(end 2.812542 -217.50147)
		(width 0.111252)
		(layer "B.Cu")
		(net "EXP_B_PRNST_TX")
	)
	(segment
		(start 5.917946 -219.2147)
		(end 5.917946 -218.1479)
		(width 0.111252)
		(layer "B.Cu")
		(net "EXP_B_PRNST_TX")
	)
	(segment
		(start 12.750546 -466.3567)
		(end 12.750546 -466.357208)
		(width 0.111252)
		(layer "B.Cu")
		(net "EXP_B_PRNST_TX")
	)
	(segment
		(start 11.937746 -466.3567)
		(end 12.750546 -466.3567)
		(width 0.111252)
		(layer "B.Cu")
		(net "EXP_B_PRNST_TX")
	)
	(segment
		(start 5.917946 -218.1479)
		(end 5.271516 -217.50147)
		(width 0.111252)
		(layer "B.Cu")
		(net "EXP_B_PRNST_TX")
	)
	(segment
		(start 11.810746 -466.4837)
		(end 11.937746 -466.3567)
		(width 0.111252)
		(layer "B.Cu")
		(net "EXP_B_PRNST_TX")
	)
	(segment
		(start 9.267698 -404.107396)
		(end 8.774176 -403.613874)
		(width 0.14605)
		(layer "In2.Cu")
		(net "EXP_B_PRNST_TX")
	)
	(segment
		(start 5.870448 -218.156028)
		(end 5.917946 -218.203526)
		(width 0.14605)
		(layer "In2.Cu")
		(net "EXP_B_PRNST_TX")
	)
	(segment
		(start 6.149594 -464.89239)
		(end 6.149594 -462.309972)
		(width 0.14605)
		(layer "In2.Cu")
		(net "EXP_B_PRNST_TX")
	)
	(segment
		(start 8.68045 -389.486902)
		(end 8.680704 -389.486394)
		(width 0.14605)
		(layer "In2.Cu")
		(net "EXP_B_PRNST_TX")
	)
	(segment
		(start 9.371838 -257.605784)
		(end 9.371838 -220.301058)
		(width 0.14605)
		(layer "In2.Cu")
		(net "EXP_B_PRNST_TX")
	)
	(segment
		(start 8.51789 -394.18514)
		(end 8.51789 -390.849358)
		(width 0.14605)
		(layer "In2.Cu")
		(net "EXP_B_PRNST_TX")
	)
	(segment
		(start 9.371838 -220.301058)
		(end 6.548628 -217.477848)
		(width 0.14605)
		(layer "In2.Cu")
		(net "EXP_B_PRNST_TX")
	)
	(segment
		(start 6.548628 -217.477848)
		(end 6.151372 -217.477848)
		(width 0.14605)
		(layer "In2.Cu")
		(net "EXP_B_PRNST_TX")
	)
	(segment
		(start 8.680704 -389.486394)
		(end 8.680958 -389.485378)
		(width 0.14605)
		(layer "In2.Cu")
		(net "EXP_B_PRNST_TX")
	)
	(segment
		(start 9.371584 -257.606038)
		(end 9.371838 -257.605784)
		(width 0.14605)
		(layer "In2.Cu")
		(net "EXP_B_PRNST_TX")
	)
	(segment
		(start 7.933182 -394.769848)
		(end 8.51789 -394.18514)
		(width 0.14605)
		(layer "In2.Cu")
		(net "EXP_B_PRNST_TX")
	)
	(segment
		(start 10.4521 -260.828028)
		(end 10.451846 -260.827774)
		(width 0.14605)
		(layer "In2.Cu")
		(net "EXP_B_PRNST_TX")
	)
	(segment
		(start 9.623298 -387.001512)
		(end 9.623298 -374.189752)
		(width 0.14605)
		(layer "In2.Cu")
		(net "EXP_B_PRNST_TX")
	)
	(segment
		(start 5.870448 -217.758772)
		(end 5.870448 -218.156028)
		(width 0.14605)
		(layer "In2.Cu")
		(net "EXP_B_PRNST_TX")
	)
	(segment
		(start 8.774176 -396.909544)
		(end 7.933182 -396.06855)
		(width 0.14605)
		(layer "In2.Cu")
		(net "EXP_B_PRNST_TX")
	)
	(segment
		(start 7.276338 -461.183228)
		(end 7.28599 -461.13446)
		(width 0.14605)
		(layer "In2.Cu")
		(net "EXP_B_PRNST_TX")
	)
	(segment
		(start 9.623298 -374.189752)
		(end 10.14095 -373.6721)
		(width 0.14605)
		(layer "In2.Cu")
		(net "EXP_B_PRNST_TX")
	)
	(segment
		(start 7.28599 -458.269848)
		(end 7.276338 -458.22108)
		(width 0.14605)
		(layer "In2.Cu")
		(net "EXP_B_PRNST_TX")
	)
	(segment
		(start 9.267698 -407.49982)
		(end 9.267698 -404.107396)
		(width 0.14605)
		(layer "In2.Cu")
		(net "EXP_B_PRNST_TX")
	)
	(segment
		(start 9.934702 -258.542536)
		(end 9.371584 -257.979418)
		(width 0.14605)
		(layer "In2.Cu")
		(net "EXP_B_PRNST_TX")
	)
	(segment
		(start 5.131562 -456.076304)
		(end 5.131562 -438.196482)
		(width 0.14605)
		(layer "In2.Cu")
		(net "EXP_B_PRNST_TX")
	)
	(segment
		(start 9.934702 -259.696966)
		(end 9.934702 -258.542536)
		(width 0.14605)
		(layer "In2.Cu")
		(net "EXP_B_PRNST_TX")
	)
	(segment
		(start 7.933182 -396.06855)
		(end 7.933182 -394.769848)
		(width 0.14605)
		(layer "In2.Cu")
		(net "EXP_B_PRNST_TX")
	)
	(segment
		(start 5.131562 -438.196482)
		(end 9.597644 -433.7304)
		(width 0.14605)
		(layer "In2.Cu")
		(net "EXP_B_PRNST_TX")
	)
	(segment
		(start 10.451846 -260.25348)
		(end 9.934702 -259.696966)
		(width 0.14605)
		(layer "In2.Cu")
		(net "EXP_B_PRNST_TX")
	)
	(segment
		(start 8.680958 -389.485378)
		(end 8.68426 -389.46836)
		(width 0.14605)
		(layer "In2.Cu")
		(net "EXP_B_PRNST_TX")
	)
	(segment
		(start 9.679686 -269.210028)
		(end 9.679686 -264.349992)
		(width 0.14605)
		(layer "In2.Cu")
		(net "EXP_B_PRNST_TX")
	)
	(segment
		(start 10.14095 -373.6721)
		(end 10.14095 -367.742724)
		(width 0.14605)
		(layer "In2.Cu")
		(net "EXP_B_PRNST_TX")
	)
	(segment
		(start 8.667496 -389.518398)
		(end 8.68045 -389.486902)
		(width 0.14605)
		(layer "In2.Cu")
		(net "EXP_B_PRNST_TX")
	)
	(segment
		(start 8.51789 -390.849358)
		(end 8.667496 -390.699752)
		(width 0.14605)
		(layer "In2.Cu")
		(net "EXP_B_PRNST_TX")
	)
	(segment
		(start 10.4521 -263.577578)
		(end 10.4521 -260.828028)
		(width 0.14605)
		(layer "In2.Cu")
		(net "EXP_B_PRNST_TX")
	)
	(segment
		(start 8.698992 -387.925818)
		(end 9.623298 -387.001512)
		(width 0.14605)
		(layer "In2.Cu")
		(net "EXP_B_PRNST_TX")
	)
	(segment
		(start 8.667496 -390.699752)
		(end 8.667496 -389.518398)
		(width 0.14605)
		(layer "In2.Cu")
		(net "EXP_B_PRNST_TX")
	)
	(segment
		(start 9.597644 -433.7304)
		(end 9.597644 -407.829766)
		(width 0.14605)
		(layer "In2.Cu")
		(net "EXP_B_PRNST_TX")
	)
	(segment
		(start 9.597644 -407.829766)
		(end 9.267698 -407.49982)
		(width 0.14605)
		(layer "In2.Cu")
		(net "EXP_B_PRNST_TX")
	)
	(segment
		(start 9.679686 -264.349992)
		(end 10.4521 -263.577578)
		(width 0.14605)
		(layer "In2.Cu")
		(net "EXP_B_PRNST_TX")
	)
	(segment
		(start 6.151372 -217.477848)
		(end 5.870448 -217.758772)
		(width 0.14605)
		(layer "In2.Cu")
		(net "EXP_B_PRNST_TX")
	)
	(segment
		(start 7.28599 -461.13446)
		(end 7.28599 -458.269848)
		(width 0.14605)
		(layer "In2.Cu")
		(net "EXP_B_PRNST_TX")
	)
	(segment
		(start 5.917946 -218.203526)
		(end 5.917946 -219.2147)
		(width 0.14605)
		(layer "In2.Cu")
		(net "EXP_B_PRNST_TX")
	)
	(segment
		(start 8.68426 -389.46836)
		(end 8.698992 -389.394192)
		(width 0.14605)
		(layer "In2.Cu")
		(net "EXP_B_PRNST_TX")
	)
	(segment
		(start 9.67994 -269.210282)
		(end 9.679686 -269.210028)
		(width 0.14605)
		(layer "In2.Cu")
		(net "EXP_B_PRNST_TX")
	)
	(segment
		(start 8.774176 -403.613874)
		(end 8.774176 -396.909544)
		(width 0.14605)
		(layer "In2.Cu")
		(net "EXP_B_PRNST_TX")
	)
	(segment
		(start 6.149594 -462.309972)
		(end 7.276338 -461.183228)
		(width 0.14605)
		(layer "In2.Cu")
		(net "EXP_B_PRNST_TX")
	)
	(segment
		(start 11.810746 -466.4837)
		(end 11.566144 -466.728302)
		(width 0.14605)
		(layer "In2.Cu")
		(net "EXP_B_PRNST_TX")
	)
	(segment
		(start 9.371584 -257.979418)
		(end 9.371584 -257.606038)
		(width 0.14605)
		(layer "In2.Cu")
		(net "EXP_B_PRNST_TX")
	)
	(segment
		(start 10.451846 -260.827774)
		(end 10.451846 -260.25348)
		(width 0.14605)
		(layer "In2.Cu")
		(net "EXP_B_PRNST_TX")
	)
	(segment
		(start 9.67994 -367.281714)
		(end 9.67994 -269.210282)
		(width 0.14605)
		(layer "In2.Cu")
		(net "EXP_B_PRNST_TX")
	)
	(segment
		(start 7.276338 -458.22108)
		(end 5.131562 -456.076304)
		(width 0.14605)
		(layer "In2.Cu")
		(net "EXP_B_PRNST_TX")
	)
	(segment
		(start 7.985506 -466.728302)
		(end 6.149594 -464.89239)
		(width 0.14605)
		(layer "In2.Cu")
		(net "EXP_B_PRNST_TX")
	)
	(segment
		(start 8.698992 -389.394192)
		(end 8.698992 -387.925818)
		(width 0.14605)
		(layer "In2.Cu")
		(net "EXP_B_PRNST_TX")
	)
	(segment
		(start 10.14095 -367.742724)
		(end 9.67994 -367.281714)
		(width 0.14605)
		(layer "In2.Cu")
		(net "EXP_B_PRNST_TX")
	)
	(segment
		(start 11.566144 -466.728302)
		(end 7.985506 -466.728302)
		(width 0.14605)
		(layer "In2.Cu")
		(net "EXP_B_PRNST_TX")
	)
	(segment
		(start 7.321804 -468.0077)
		(end 6.603746 -468.0077)
		(width 0.111252)
		(layer "F.Cu")
		(net "EXP_A_PRNST_TX")
	)
	(segment
		(start 9.588246 -468.0077)
		(end 7.714488 -468.0077)
		(width 0.111252)
		(layer "F.Cu")
		(net "EXP_A_PRNST_TX")
	)
	(segment
		(start 9.715246 -467.8807)
		(end 9.588246 -468.0077)
		(width 0.111252)
		(layer "F.Cu")
		(net "EXP_A_PRNST_TX")
	)
	(segment
		(start 7.32663 -468.002874)
		(end 7.321804 -468.0077)
		(width 0.111252)
		(layer "F.Cu")
		(net "EXP_A_PRNST_TX")
	)
	(segment
		(start 11.810746 -469.9127)
		(end 11.747246 -469.9127)
		(width 0.111252)
		(layer "F.Cu")
		(net "EXP_A_PRNST_TX")
	)
	(segment
		(start 11.747246 -469.9127)
		(end 9.715246 -467.8807)
		(width 0.111252)
		(layer "F.Cu")
		(net "EXP_A_PRNST_TX")
	)
	(segment
		(start 7.709662 -468.002874)
		(end 7.32663 -468.002874)
		(width 0.111252)
		(layer "F.Cu")
		(net "EXP_A_PRNST_TX")
	)
	(segment
		(start 7.714488 -468.0077)
		(end 7.709662 -468.002874)
		(width 0.111252)
		(layer "F.Cu")
		(net "EXP_A_PRNST_TX")
	)
	(via
		(at 11.810746 -469.9127)
		(size 0.7112)
		(drill 0.3556)
		(layers "F.Cu" "B.Cu")
		(net "EXP_A_PRNST_TX")
	)
	(via
		(at 6.603746 -468.0077)
		(size 0.5588)
		(drill 0.3048)
		(layers "F.Cu" "B.Cu")
		(net "EXP_A_PRNST_TX")
	)
	(segment
		(start 6.603746 -468.0077)
		(end 6.097524 -467.501478)
		(width 0.111252)
		(layer "B.Cu")
		(net "EXP_A_PRNST_TX")
	)
	(segment
		(start 6.097524 -467.501478)
		(end 2.812542 -467.501478)
		(width 0.111252)
		(layer "B.Cu")
		(net "EXP_A_PRNST_TX")
	)
	(segment
		(start 2.812542 -467.501478)
		(end 2.80924 -467.50478)
		(width 0.111252)
		(layer "B.Cu")
		(net "EXP_A_PRNST_TX")
	)
	(segment
		(start 12.711938 -148.500338)
		(end 3.19405 -148.500338)
		(width 0.111252)
		(layer "F.Cu")
		(net "SAS2X28_B_HDD15_FLT")
	)
	(segment
		(start 14.5796 -155.1686)
		(end 14.5796 -150.368)
		(width 0.111252)
		(layer "F.Cu")
		(net "SAS2X28_B_HDD15_FLT")
	)
	(segment
		(start 3.19405 -148.500338)
		(end 3.192526 -148.498814)
		(width 0.111252)
		(layer "F.Cu")
		(net "SAS2X28_B_HDD15_FLT")
	)
	(segment
		(start 14.5796 -150.368)
		(end 12.711938 -148.500338)
		(width 0.111252)
		(layer "F.Cu")
		(net "SAS2X28_B_HDD15_FLT")
	)
	(segment
		(start 3.19405 -94.499938)
		(end 3.192526 -94.498414)
		(width 0.111252)
		(layer "F.Cu")
		(net "SAS2X28_B_PRSNT15")
	)
	(segment
		(start 9.877044 -94.499938)
		(end 3.19405 -94.499938)
		(width 0.111252)
		(layer "F.Cu")
		(net "SAS2X28_B_PRSNT15")
	)
	(segment
		(start 9.905746 -94.52864)
		(end 9.877044 -94.499938)
		(width 0.111252)
		(layer "F.Cu")
		(net "SAS2X28_B_PRSNT15")
	)
	(segment
		(start 100.139246 -12.95146)
		(end 101.775006 -12.95146)
		(width 0.111252)
		(layer "F.Cu")
		(net "DRIVE_PWR14")
	)
	(segment
		(start 101.790246 -12.9667)
		(end 101.790246 -12.3952)
		(width 0.111252)
		(layer "F.Cu")
		(net "DRIVE_PWR14")
	)
	(segment
		(start 101.790246 -12.3952)
		(end 102.361746 -11.8237)
		(width 0.111252)
		(layer "F.Cu")
		(net "DRIVE_PWR14")
	)
	(segment
		(start 101.775006 -12.95146)
		(end 101.790246 -12.9667)
		(width 0.111252)
		(layer "F.Cu")
		(net "DRIVE_PWR14")
	)
	(via
		(at 102.361746 -11.8237)
		(size 0.7112)
		(drill 0.3556)
		(layers "F.Cu" "B.Cu")
		(net "DRIVE_PWR14")
	)
	(segment
		(start 38.241986 -110.820962)
		(end 38.241986 -110.074202)
		(width 0.111252)
		(layer "F.Cu")
		(net "DRIVE_PWR13")
	)
	(segment
		(start 38.35019 -110.074202)
		(end 38.241986 -110.074202)
		(width 0.111252)
		(layer "F.Cu")
		(net "DRIVE_PWR13")
	)
	(segment
		(start 37.210746 -111.852202)
		(end 38.241986 -110.820962)
		(width 0.111252)
		(layer "F.Cu")
		(net "DRIVE_PWR13")
	)
	(segment
		(start 39.867586 -108.556806)
		(end 38.35019 -110.074202)
		(width 0.111252)
		(layer "F.Cu")
		(net "DRIVE_PWR13")
	)
	(segment
		(start 39.867586 -108.278168)
		(end 39.867586 -108.556806)
		(width 0.111252)
		(layer "F.Cu")
		(net "DRIVE_PWR13")
	)
	(via
		(at 39.867586 -108.278168)
		(size 0.7112)
		(drill 0.3556)
		(layers "F.Cu" "B.Cu")
		(net "DRIVE_PWR13")
	)
	(segment
		(start 45.338746 -208.4197)
		(end 43.829986 -209.92846)
		(width 0.111252)
		(layer "F.Cu")
		(net "DRIVE_PWR12")
	)
	(segment
		(start 43.829986 -209.92846)
		(end 43.829986 -210.023202)
		(width 0.111252)
		(layer "F.Cu")
		(net "DRIVE_PWR12")
	)
	(segment
		(start 43.814746 -211.674202)
		(end 43.829986 -211.658962)
		(width 0.111252)
		(layer "F.Cu")
		(net "DRIVE_PWR12")
	)
	(segment
		(start 43.829986 -211.658962)
		(end 43.829986 -210.023202)
		(width 0.111252)
		(layer "F.Cu")
		(net "DRIVE_PWR12")
	)
	(segment
		(start 45.592746 -208.4197)
		(end 45.338746 -208.4197)
		(width 0.111252)
		(layer "F.Cu")
		(net "DRIVE_PWR12")
	)
	(via
		(at 45.592746 -208.4197)
		(size 0.7112)
		(drill 0.3556)
		(layers "F.Cu" "B.Cu")
		(net "DRIVE_PWR12")
	)
	(segment
		(start 28.462986 -308.63794)
		(end 28.066746 -308.2417)
		(width 0.111252)
		(layer "F.Cu")
		(net "DRIVE_PWR11")
	)
	(segment
		(start 28.447746 -309.098442)
		(end 28.462986 -309.083202)
		(width 0.111252)
		(layer "F.Cu")
		(net "DRIVE_PWR11")
	)
	(segment
		(start 28.447746 -310.861202)
		(end 28.447746 -309.098442)
		(width 0.111252)
		(layer "F.Cu")
		(net "DRIVE_PWR11")
	)
	(segment
		(start 28.462986 -309.083202)
		(end 28.462986 -308.63794)
		(width 0.111252)
		(layer "F.Cu")
		(net "DRIVE_PWR11")
	)
	(segment
		(start 28.066746 -308.2417)
		(end 25.653746 -308.2417)
		(width 0.111252)
		(layer "F.Cu")
		(net "DRIVE_PWR11")
	)
	(via
		(at 25.653746 -308.2417)
		(size 0.7112)
		(drill 0.3556)
		(layers "F.Cu" "B.Cu")
		(net "DRIVE_PWR11")
	)
	(segment
		(start 5.131054 -344.499946)
		(end 3.19405 -344.499946)
		(width 0.111252)
		(layer "F.Cu")
		(net "SAS2X28_A_PRSNT15")
	)
	(segment
		(start 5.333746 -344.297254)
		(end 5.131054 -344.499946)
		(width 0.111252)
		(layer "F.Cu")
		(net "SAS2X28_A_PRSNT15")
	)
	(segment
		(start 5.333746 -343.4207)
		(end 5.333746 -344.297254)
		(width 0.111252)
		(layer "F.Cu")
		(net "SAS2X28_A_PRSNT15")
	)
	(segment
		(start 5.333746 -334.1497)
		(end 5.206746 -334.0227)
		(width 0.111252)
		(layer "F.Cu")
		(net "SAS2X28_A_PRSNT15")
	)
	(segment
		(start 5.333746 -335.4197)
		(end 5.333746 -334.1497)
		(width 0.111252)
		(layer "F.Cu")
		(net "SAS2X28_A_PRSNT15")
	)
	(segment
		(start 3.19405 -344.499946)
		(end 3.192526 -344.498422)
		(width 0.111252)
		(layer "F.Cu")
		(net "SAS2X28_A_PRSNT15")
	)
	(via
		(at 5.333746 -335.4197)
		(size 0.5588)
		(drill 0.3048)
		(layers "F.Cu" "B.Cu")
		(net "SAS2X28_A_PRSNT15")
	)
	(via
		(at 5.333746 -343.4207)
		(size 0.5588)
		(drill 0.3048)
		(layers "F.Cu" "B.Cu")
		(net "SAS2X28_A_PRSNT15")
	)
	(segment
		(start 5.460746 -335.5467)
		(end 5.333746 -335.4197)
		(width 0.14605)
		(layer "In2.Cu")
		(net "SAS2X28_A_PRSNT15")
	)
	(segment
		(start 5.333746 -343.4207)
		(end 5.460746 -343.2937)
		(width 0.14605)
		(layer "In2.Cu")
		(net "SAS2X28_A_PRSNT15")
	)
	(segment
		(start 5.460746 -343.2937)
		(end 5.460746 -335.5467)
		(width 0.14605)
		(layer "In2.Cu")
		(net "SAS2X28_A_PRSNT15")
	)
	(segment
		(start 35.940746 -437.2102)
		(end 35.066986 -437.2102)
		(width 0.111252)
		(layer "F.Cu")
		(net "DRIVE_PWR10")
	)
	(segment
		(start 36.639246 -434.7972)
		(end 36.639246 -436.5117)
		(width 0.111252)
		(layer "F.Cu")
		(net "DRIVE_PWR10")
	)
	(segment
		(start 36.639246 -436.5117)
		(end 35.940746 -437.2102)
		(width 0.111252)
		(layer "F.Cu")
		(net "DRIVE_PWR10")
	)
	(segment
		(start 36.829746 -434.6067)
		(end 36.639246 -434.7972)
		(width 0.111252)
		(layer "F.Cu")
		(net "DRIVE_PWR10")
	)
	(via
		(at 36.829746 -434.6067)
		(size 0.7112)
		(drill 0.3556)
		(layers "F.Cu" "B.Cu")
		(net "DRIVE_PWR10")
	)
	(segment
		(start 82.269076 -191.2747)
		(end 82.422746 -191.2747)
		(width 0.111252)
		(layer "F.Cu")
		(net "DRIVE_PWR8")
	)
	(segment
		(start 80.532986 -189.51194)
		(end 81.495646 -190.4746)
		(width 0.111252)
		(layer "F.Cu")
		(net "DRIVE_PWR8")
	)
	(segment
		(start 81.495646 -190.50127)
		(end 82.269076 -191.2747)
		(width 0.111252)
		(layer "F.Cu")
		(net "DRIVE_PWR8")
	)
	(segment
		(start 80.454246 -189.51194)
		(end 80.532986 -189.51194)
		(width 0.111252)
		(layer "F.Cu")
		(net "DRIVE_PWR8")
	)
	(segment
		(start 81.495646 -190.4746)
		(end 81.495646 -190.50127)
		(width 0.111252)
		(layer "F.Cu")
		(net "DRIVE_PWR8")
	)
	(segment
		(start 80.439006 -189.4967)
		(end 80.454246 -189.51194)
		(width 0.111252)
		(layer "F.Cu")
		(net "DRIVE_PWR8")
	)
	(segment
		(start 78.803246 -189.4967)
		(end 80.439006 -189.4967)
		(width 0.111252)
		(layer "F.Cu")
		(net "DRIVE_PWR8")
	)
	(via
		(at 82.422746 -191.2747)
		(size 0.7112)
		(drill 0.3556)
		(layers "F.Cu" "B.Cu")
		(net "DRIVE_PWR8")
	)
	(segment
		(start 80.072992 -86.150196)
		(end 80.072992 -86.969346)
		(width 0.111252)
		(layer "F.Cu")
		(net "DRIVE_PWR9")
	)
	(segment
		(start 78.453742 -86.150196)
		(end 80.072992 -86.150196)
		(width 0.111252)
		(layer "F.Cu")
		(net "DRIVE_PWR9")
	)
	(segment
		(start 80.937608 -87.8459)
		(end 81.051908 -87.9602)
		(width 0.111252)
		(layer "F.Cu")
		(net "DRIVE_PWR9")
	)
	(segment
		(start 80.072992 -86.969346)
		(end 80.937608 -87.833962)
		(width 0.111252)
		(layer "F.Cu")
		(net "DRIVE_PWR9")
	)
	(segment
		(start 80.937608 -87.833962)
		(end 80.937608 -87.8459)
		(width 0.111252)
		(layer "F.Cu")
		(net "DRIVE_PWR9")
	)
	(segment
		(start 78.422246 -86.1187)
		(end 78.453742 -86.150196)
		(width 0.111252)
		(layer "F.Cu")
		(net "DRIVE_PWR9")
	)
	(via
		(at 81.051908 -87.9602)
		(size 0.7112)
		(drill 0.3556)
		(layers "F.Cu" "B.Cu")
		(net "DRIVE_PWR9")
	)
	(segment
		(start 28.305506 -279.17394)
		(end 27.876246 -279.17394)
		(width 0.111252)
		(layer "F.Cu")
		(net "DRIVE_PWR7")
	)
	(segment
		(start 25.907746 -276.9362)
		(end 26.034746 -277.0632)
		(width 0.111252)
		(layer "F.Cu")
		(net "DRIVE_PWR7")
	)
	(segment
		(start 28.701746 -277.2537)
		(end 28.701746 -278.7777)
		(width 0.111252)
		(layer "F.Cu")
		(net "DRIVE_PWR7")
	)
	(segment
		(start 26.034746 -277.0632)
		(end 28.511246 -277.0632)
		(width 0.111252)
		(layer "F.Cu")
		(net "DRIVE_PWR7")
	)
	(segment
		(start 28.701746 -278.7777)
		(end 28.305506 -279.17394)
		(width 0.111252)
		(layer "F.Cu")
		(net "DRIVE_PWR7")
	)
	(segment
		(start 27.685746 -279.9207)
		(end 27.876246 -279.7302)
		(width 0.111252)
		(layer "F.Cu")
		(net "DRIVE_PWR7")
	)
	(segment
		(start 27.876246 -279.7302)
		(end 27.876246 -279.17394)
		(width 0.111252)
		(layer "F.Cu")
		(net "DRIVE_PWR7")
	)
	(segment
		(start 28.511246 -277.0632)
		(end 28.701746 -277.2537)
		(width 0.111252)
		(layer "F.Cu")
		(net "DRIVE_PWR7")
	)
	(via
		(at 27.812746 -278.9809)
		(size 0.7112)
		(drill 0.3556)
		(layers "F.Cu" "B.Cu")
		(net "DRIVE_PWR7")
	)
	(via
		(at 27.685746 -279.9207)
		(size 0.5588)
		(drill 0.3048)
		(layers "F.Cu" "B.Cu")
		(net "DRIVE_PWR7")
	)
	(segment
		(start 27.812746 -279.7937)
		(end 27.812746 -278.9809)
		(width 0.111252)
		(layer "B.Cu")
		(net "DRIVE_PWR7")
	)
	(segment
		(start 27.685746 -279.9207)
		(end 27.812746 -279.7937)
		(width 0.111252)
		(layer "B.Cu")
		(net "DRIVE_PWR7")
	)
	(segment
		(start 80.390746 -395.4907)
		(end 80.390746 -393.7127)
		(width 0.111252)
		(layer "F.Cu")
		(net "DRIVE_PWR6")
	)
	(segment
		(start 78.881986 -396.14094)
		(end 79.565246 -396.14094)
		(width 0.111252)
		(layer "F.Cu")
		(net "DRIVE_PWR6")
	)
	(segment
		(start 79.740506 -396.14094)
		(end 80.390746 -395.4907)
		(width 0.111252)
		(layer "F.Cu")
		(net "DRIVE_PWR6")
	)
	(segment
		(start 77.914246 -395.8717)
		(end 78.612746 -395.8717)
		(width 0.111252)
		(layer "F.Cu")
		(net "DRIVE_PWR6")
	)
	(segment
		(start 80.390746 -393.7127)
		(end 80.644746 -393.4587)
		(width 0.111252)
		(layer "F.Cu")
		(net "DRIVE_PWR6")
	)
	(segment
		(start 78.612746 -395.8717)
		(end 78.881986 -396.14094)
		(width 0.111252)
		(layer "F.Cu")
		(net "DRIVE_PWR6")
	)
	(segment
		(start 79.565246 -396.14094)
		(end 79.740506 -396.14094)
		(width 0.111252)
		(layer "F.Cu")
		(net "DRIVE_PWR6")
	)
	(via
		(at 80.644746 -393.4587)
		(size 0.7112)
		(drill 0.3556)
		(layers "F.Cu" "B.Cu")
		(net "DRIVE_PWR6")
	)
	(segment
		(start 80.517746 -495.022886)
		(end 80.659986 -495.165126)
		(width 0.111252)
		(layer "F.Cu")
		(net "DRIVE_PWR5")
	)
	(segment
		(start 82.295746 -492.3917)
		(end 82.2198 -492.467646)
		(width 0.111252)
		(layer "F.Cu")
		(net "DRIVE_PWR5")
	)
	(segment
		(start 82.2198 -492.467646)
		(end 82.2198 -494.753646)
		(width 0.111252)
		(layer "F.Cu")
		(net "DRIVE_PWR5")
	)
	(segment
		(start 81.80832 -495.165126)
		(end 81.399634 -495.165126)
		(width 0.111252)
		(layer "F.Cu")
		(net "DRIVE_PWR5")
	)
	(segment
		(start 79.748634 -495.022886)
		(end 80.517746 -495.022886)
		(width 0.111252)
		(layer "F.Cu")
		(net "DRIVE_PWR5")
	)
	(segment
		(start 82.2198 -494.753646)
		(end 81.80832 -495.165126)
		(width 0.111252)
		(layer "F.Cu")
		(net "DRIVE_PWR5")
	)
	(segment
		(start 80.659986 -495.165126)
		(end 81.399634 -495.165126)
		(width 0.111252)
		(layer "F.Cu")
		(net "DRIVE_PWR5")
	)
	(via
		(at 82.295746 -492.3917)
		(size 0.7112)
		(drill 0.3556)
		(layers "F.Cu" "B.Cu")
		(net "DRIVE_PWR5")
	)
	(segment
		(start 191.700912 -83.774534)
		(end 191.700912 -83.546696)
		(width 0.111252)
		(layer "F.Cu")
		(net "DRIVE_PWR4")
	)
	(segment
		(start 193.336672 -83.546696)
		(end 193.351912 -83.561936)
		(width 0.111252)
		(layer "F.Cu")
		(net "DRIVE_PWR4")
	)
	(segment
		(start 190.893446 -84.582)
		(end 191.700912 -83.774534)
		(width 0.111252)
		(layer "F.Cu")
		(net "DRIVE_PWR4")
	)
	(segment
		(start 191.700912 -83.546696)
		(end 193.336672 -83.546696)
		(width 0.111252)
		(layer "F.Cu")
		(net "DRIVE_PWR4")
	)
	(segment
		(start 189.992 -84.582)
		(end 190.893446 -84.582)
		(width 0.111252)
		(layer "F.Cu")
		(net "DRIVE_PWR4")
	)
	(via
		(at 189.992 -84.582)
		(size 0.7112)
		(drill 0.3556)
		(layers "F.Cu" "B.Cu")
		(net "DRIVE_PWR4")
	)
	(segment
		(start 191.311784 -185.4327)
		(end 191.375284 -185.390028)
		(width 0.111252)
		(layer "F.Cu")
		(net "DRIVE_PWR3")
	)
	(segment
		(start 191.375284 -185.390028)
		(end 191.390524 -185.405268)
		(width 0.111252)
		(layer "F.Cu")
		(net "DRIVE_PWR3")
	)
	(segment
		(start 189.865 -186.375548)
		(end 190.368936 -186.375548)
		(width 0.111252)
		(layer "F.Cu")
		(net "DRIVE_PWR3")
	)
	(segment
		(start 190.368936 -186.375548)
		(end 191.311784 -185.4327)
		(width 0.111252)
		(layer "F.Cu")
		(net "DRIVE_PWR3")
	)
	(segment
		(start 191.390524 -185.405268)
		(end 193.153284 -185.405268)
		(width 0.111252)
		(layer "F.Cu")
		(net "DRIVE_PWR3")
	)
	(via
		(at 189.865 -186.375548)
		(size 0.7112)
		(drill 0.3556)
		(layers "F.Cu" "B.Cu")
		(net "DRIVE_PWR3")
	)
	(segment
		(start 192.803018 -288.539428)
		(end 191.554354 -288.539428)
		(width 0.111252)
		(layer "F.Cu")
		(net "DRIVE_PWR2")
	)
	(segment
		(start 193.188082 -287.388808)
		(end 193.188082 -288.154364)
		(width 0.111252)
		(layer "F.Cu")
		(net "DRIVE_PWR2")
	)
	(segment
		(start 191.537082 -287.373568)
		(end 191.537082 -288.522156)
		(width 0.111252)
		(layer "F.Cu")
		(net "DRIVE_PWR2")
	)
	(segment
		(start 191.537082 -288.522156)
		(end 191.554354 -288.539428)
		(width 0.111252)
		(layer "F.Cu")
		(net "DRIVE_PWR2")
	)
	(segment
		(start 193.188082 -288.154364)
		(end 192.803018 -288.539428)
		(width 0.111252)
		(layer "F.Cu")
		(net "DRIVE_PWR2")
	)
	(via
		(at 191.554354 -288.539428)
		(size 0.7112)
		(drill 0.3556)
		(layers "F.Cu" "B.Cu")
		(net "DRIVE_PWR2")
	)
	(segment
		(start 192.297558 -390.454642)
		(end 191.599312 -391.152888)
		(width 0.111252)
		(layer "F.Cu")
		(net "DRIVE_PWR1")
	)
	(segment
		(start 191.599312 -391.152888)
		(end 191.033146 -391.152888)
		(width 0.111252)
		(layer "F.Cu")
		(net "DRIVE_PWR1")
	)
	(segment
		(start 192.297558 -390.219184)
		(end 192.297558 -390.454642)
		(width 0.111252)
		(layer "F.Cu")
		(net "DRIVE_PWR1")
	)
	(segment
		(start 192.312798 -390.234424)
		(end 192.297558 -390.219184)
		(width 0.111252)
		(layer "F.Cu")
		(net "DRIVE_PWR1")
	)
	(segment
		(start 193.948558 -390.234424)
		(end 192.312798 -390.234424)
		(width 0.111252)
		(layer "F.Cu")
		(net "DRIVE_PWR1")
	)
	(via
		(at 191.033146 -391.152888)
		(size 0.7112)
		(drill 0.3556)
		(layers "F.Cu" "B.Cu")
		(net "DRIVE_PWR1")
	)
	(segment
		(start 190.842392 -493.903)
		(end 191.405256 -493.340136)
		(width 0.111252)
		(layer "F.Cu")
		(net "DRIVE_PWR0")
	)
	(segment
		(start 189.521846 -494.03)
		(end 189.648846 -493.903)
		(width 0.111252)
		(layer "F.Cu")
		(net "DRIVE_PWR0")
	)
	(segment
		(start 191.405256 -493.340136)
		(end 191.405256 -493.322102)
		(width 0.111252)
		(layer "F.Cu")
		(net "DRIVE_PWR0")
	)
	(segment
		(start 193.041016 -493.322102)
		(end 193.056256 -493.337342)
		(width 0.111252)
		(layer "F.Cu")
		(net "DRIVE_PWR0")
	)
	(segment
		(start 189.648846 -493.903)
		(end 190.842392 -493.903)
		(width 0.111252)
		(layer "F.Cu")
		(net "DRIVE_PWR0")
	)
	(segment
		(start 191.405256 -493.322102)
		(end 193.041016 -493.322102)
		(width 0.111252)
		(layer "F.Cu")
		(net "DRIVE_PWR0")
	)
	(via
		(at 189.521846 -494.03)
		(size 0.7112)
		(drill 0.3556)
		(layers "F.Cu" "B.Cu")
		(net "DRIVE_PWR0")
	)
	(segment
		(start 47.423578 -123.391422)
		(end 46.608746 -123.391422)
		(width 0.111252)
		(layer "F.Cu")
		(net "FLT_HDD13_DRIVE")
	)
	(segment
		(start 20.891246 -159.2707)
		(end 20.954746 -159.2707)
		(width 0.111252)
		(layer "F.Cu")
		(net "FLT_HDD13_DRIVE")
	)
	(segment
		(start 20.129246 -163.2077)
		(end 20.700746 -162.6362)
		(width 0.111252)
		(layer "F.Cu")
		(net "FLT_HDD13_DRIVE")
	)
	(segment
		(start 18.034 -165.3032)
		(end 19.367246 -165.3032)
		(width 0.111252)
		(layer "F.Cu")
		(net "FLT_HDD13_DRIVE")
	)
	(segment
		(start 19.367246 -165.3032)
		(end 20.129246 -164.5412)
		(width 0.111252)
		(layer "F.Cu")
		(net "FLT_HDD13_DRIVE")
	)
	(segment
		(start 17.446498 -164.715698)
		(end 18.034 -165.3032)
		(width 0.111252)
		(layer "F.Cu")
		(net "FLT_HDD13_DRIVE")
	)
	(segment
		(start 20.700746 -159.4612)
		(end 20.891246 -159.2707)
		(width 0.111252)
		(layer "F.Cu")
		(net "FLT_HDD13_DRIVE")
	)
	(segment
		(start 47.752 -123.063)
		(end 47.423578 -123.391422)
		(width 0.111252)
		(layer "F.Cu")
		(net "FLT_HDD13_DRIVE")
	)
	(segment
		(start 20.129246 -164.5412)
		(end 20.129246 -163.2077)
		(width 0.111252)
		(layer "F.Cu")
		(net "FLT_HDD13_DRIVE")
	)
	(segment
		(start 20.700746 -162.6362)
		(end 20.700746 -159.4612)
		(width 0.111252)
		(layer "F.Cu")
		(net "FLT_HDD13_DRIVE")
	)
	(segment
		(start 15.366746 -164.715698)
		(end 17.446498 -164.715698)
		(width 0.111252)
		(layer "F.Cu")
		(net "FLT_HDD13_DRIVE")
	)
	(via
		(at 46.7868 -123.0376)
		(size 0.7112)
		(drill 0.3556)
		(layers "F.Cu" "B.Cu")
		(net "FLT_HDD13_DRIVE")
	)
	(via
		(at 20.954746 -159.2707)
		(size 0.5588)
		(drill 0.3048)
		(layers "F.Cu" "B.Cu")
		(net "FLT_HDD13_DRIVE")
	)
	(via
		(at 47.752 -123.063)
		(size 0.5588)
		(drill 0.3048)
		(layers "F.Cu" "B.Cu")
		(net "FLT_HDD13_DRIVE")
	)
	(segment
		(start 47.7266 -123.0376)
		(end 46.7868 -123.0376)
		(width 0.111252)
		(layer "B.Cu")
		(net "FLT_HDD13_DRIVE")
	)
	(segment
		(start 47.752 -123.063)
		(end 47.7266 -123.0376)
		(width 0.111252)
		(layer "B.Cu")
		(net "FLT_HDD13_DRIVE")
	)
	(segment
		(start 39.543228 -167.755824)
		(end 31.510224 -167.755824)
		(width 0.14605)
		(layer "In5.Cu")
		(net "FLT_HDD13_DRIVE")
	)
	(segment
		(start 40.369744 -130.076702)
		(end 40.369744 -149.348698)
		(width 0.14605)
		(layer "In5.Cu")
		(net "FLT_HDD13_DRIVE")
	)
	(segment
		(start 43.306746 -124.557282)
		(end 43.306746 -127.1397)
		(width 0.14605)
		(layer "In5.Cu")
		(net "FLT_HDD13_DRIVE")
	)
	(segment
		(start 47.752 -123.063)
		(end 44.801028 -123.063)
		(width 0.14605)
		(layer "In5.Cu")
		(net "FLT_HDD13_DRIVE")
	)
	(segment
		(start 40.369744 -149.348698)
		(end 41.830752 -150.809706)
		(width 0.14605)
		(layer "In5.Cu")
		(net "FLT_HDD13_DRIVE")
	)
	(segment
		(start 44.801028 -123.063)
		(end 43.306746 -124.557282)
		(width 0.14605)
		(layer "In5.Cu")
		(net "FLT_HDD13_DRIVE")
	)
	(segment
		(start 43.306746 -127.1397)
		(end 40.369744 -130.076702)
		(width 0.14605)
		(layer "In5.Cu")
		(net "FLT_HDD13_DRIVE")
	)
	(segment
		(start 41.830752 -150.809706)
		(end 41.830752 -165.4683)
		(width 0.14605)
		(layer "In5.Cu")
		(net "FLT_HDD13_DRIVE")
	)
	(segment
		(start 23.0251 -159.2707)
		(end 20.954746 -159.2707)
		(width 0.14605)
		(layer "In5.Cu")
		(net "FLT_HDD13_DRIVE")
	)
	(segment
		(start 31.510224 -167.755824)
		(end 23.0251 -159.2707)
		(width 0.14605)
		(layer "In5.Cu")
		(net "FLT_HDD13_DRIVE")
	)
	(segment
		(start 41.830752 -165.4683)
		(end 39.543228 -167.755824)
		(width 0.14605)
		(layer "In5.Cu")
		(net "FLT_HDD13_DRIVE")
	)
	(segment
		(start 8.636 -268.1986)
		(end 14.271244 -262.563356)
		(width 0.111252)
		(layer "F.Cu")
		(net "FLT_HDD12_DRIVE")
	)
	(segment
		(start 39.374826 -223.6597)
		(end 50.848006 -223.6597)
		(width 0.111252)
		(layer "F.Cu")
		(net "FLT_HDD12_DRIVE")
	)
	(segment
		(start 8.636 -268.7955)
		(end 8.636 -268.1986)
		(width 0.111252)
		(layer "F.Cu")
		(net "FLT_HDD12_DRIVE")
	)
	(segment
		(start 38.735 -243.84)
		(end 38.735 -242.963446)
		(width 0.111252)
		(layer "F.Cu")
		(net "FLT_HDD12_DRIVE")
	)
	(segment
		(start 40.893746 -240.607596)
		(end 40.966644 -240.534698)
		(width 0.111252)
		(layer "F.Cu")
		(net "FLT_HDD12_DRIVE")
	)
	(segment
		(start 38.4556 -234.937554)
		(end 38.4556 -224.578926)
		(width 0.111252)
		(layer "F.Cu")
		(net "FLT_HDD12_DRIVE")
	)
	(segment
		(start 51.673506 -224.4852)
		(end 51.673506 -224.8662)
		(width 0.111252)
		(layer "F.Cu")
		(net "FLT_HDD12_DRIVE")
	)
	(segment
		(start 15.426944 -261.5184)
		(end 14.271244 -260.3627)
		(width 0.111252)
		(layer "F.Cu")
		(net "FLT_HDD12_DRIVE")
	)
	(segment
		(start 38.4556 -224.578926)
		(end 39.374826 -223.6597)
		(width 0.111252)
		(layer "F.Cu")
		(net "FLT_HDD12_DRIVE")
	)
	(segment
		(start 40.893746 -237.3757)
		(end 38.4556 -234.937554)
		(width 0.111252)
		(layer "F.Cu")
		(net "FLT_HDD12_DRIVE")
	)
	(segment
		(start 38.735 -242.963446)
		(end 40.893746 -240.8047)
		(width 0.111252)
		(layer "F.Cu")
		(net "FLT_HDD12_DRIVE")
	)
	(segment
		(start 14.271244 -262.563356)
		(end 14.271244 -260.3627)
		(width 0.111252)
		(layer "F.Cu")
		(net "FLT_HDD12_DRIVE")
	)
	(segment
		(start 16.129 -261.5184)
		(end 15.426944 -261.5184)
		(width 0.111252)
		(layer "F.Cu")
		(net "FLT_HDD12_DRIVE")
	)
	(segment
		(start 50.848006 -223.6597)
		(end 51.673506 -224.4852)
		(width 0.111252)
		(layer "F.Cu")
		(net "FLT_HDD12_DRIVE")
	)
	(segment
		(start 40.893746 -239.783366)
		(end 40.893746 -239.4077)
		(width 0.111252)
		(layer "F.Cu")
		(net "FLT_HDD12_DRIVE")
	)
	(segment
		(start 40.966644 -240.534698)
		(end 40.966644 -240.457736)
		(width 0.111252)
		(layer "F.Cu")
		(net "FLT_HDD12_DRIVE")
	)
	(segment
		(start 40.966644 -240.457736)
		(end 41.0464 -240.37798)
		(width 0.111252)
		(layer "F.Cu")
		(net "FLT_HDD12_DRIVE")
	)
	(segment
		(start 40.893746 -240.8047)
		(end 40.893746 -240.607596)
		(width 0.111252)
		(layer "F.Cu")
		(net "FLT_HDD12_DRIVE")
	)
	(segment
		(start 40.893746 -239.4077)
		(end 40.893746 -237.3757)
		(width 0.111252)
		(layer "F.Cu")
		(net "FLT_HDD12_DRIVE")
	)
	(segment
		(start 41.0464 -240.37798)
		(end 41.0464 -239.93602)
		(width 0.111252)
		(layer "F.Cu")
		(net "FLT_HDD12_DRIVE")
	)
	(segment
		(start 41.0464 -239.93602)
		(end 40.893746 -239.783366)
		(width 0.111252)
		(layer "F.Cu")
		(net "FLT_HDD12_DRIVE")
	)
	(via
		(at 40.893746 -239.4077)
		(size 0.7112)
		(drill 0.3556)
		(layers "F.Cu" "B.Cu")
		(net "FLT_HDD12_DRIVE")
	)
	(via
		(at 38.735 -243.84)
		(size 0.5588)
		(drill 0.3048)
		(layers "F.Cu" "B.Cu")
		(net "FLT_HDD12_DRIVE")
	)
	(via
		(at 26.8224 -271.653)
		(size 0.5588)
		(drill 0.3048)
		(layers "F.Cu" "B.Cu")
		(net "FLT_HDD12_DRIVE")
	)
	(via
		(at 28.625546 -268.979396)
		(size 0.5588)
		(drill 0.3048)
		(layers "F.Cu" "B.Cu")
		(net "FLT_HDD12_DRIVE")
	)
	(via
		(at 16.129 -261.5184)
		(size 0.5588)
		(drill 0.3048)
		(layers "F.Cu" "B.Cu")
		(net "FLT_HDD12_DRIVE")
	)
	(segment
		(start 26.8224 -271.653)
		(end 28.575 -269.9004)
		(width 0.111252)
		(layer "B.Cu")
		(net "FLT_HDD12_DRIVE")
	)
	(segment
		(start 28.575 -269.9004)
		(end 28.575 -269.029942)
		(width 0.111252)
		(layer "B.Cu")
		(net "FLT_HDD12_DRIVE")
	)
	(segment
		(start 28.575 -269.029942)
		(end 28.625546 -268.979396)
		(width 0.111252)
		(layer "B.Cu")
		(net "FLT_HDD12_DRIVE")
	)
	(segment
		(start 26.5684 -266.92225)
		(end 28.625546 -268.979396)
		(width 0.14605)
		(layer "In5.Cu")
		(net "FLT_HDD12_DRIVE")
	)
	(segment
		(start 16.141446 -261.5184)
		(end 26.276046 -271.653)
		(width 0.14605)
		(layer "In5.Cu")
		(net "FLT_HDD12_DRIVE")
	)
	(segment
		(start 26.5684 -256.0066)
		(end 26.5684 -266.92225)
		(width 0.14605)
		(layer "In5.Cu")
		(net "FLT_HDD12_DRIVE")
	)
	(segment
		(start 16.129 -261.5184)
		(end 16.141446 -261.5184)
		(width 0.14605)
		(layer "In5.Cu")
		(net "FLT_HDD12_DRIVE")
	)
	(segment
		(start 38.735 -243.84)
		(end 26.5684 -256.0066)
		(width 0.14605)
		(layer "In5.Cu")
		(net "FLT_HDD12_DRIVE")
	)
	(segment
		(start 26.276046 -271.653)
		(end 26.8224 -271.653)
		(width 0.14605)
		(layer "In5.Cu")
		(net "FLT_HDD12_DRIVE")
	)
	(segment
		(start 27.711146 -332.6638)
		(end 27.711146 -333.045054)
		(width 0.111252)
		(layer "F.Cu")
		(net "FLT_HDD11_DRIVE")
	)
	(segment
		(start 32.448246 -340.8807)
		(end 32.194246 -341.1347)
		(width 0.111252)
		(layer "F.Cu")
		(net "FLT_HDD11_DRIVE")
	)
	(segment
		(start 25.527 -335.2292)
		(end 25.527 -336.0166)
		(width 0.111252)
		(layer "F.Cu")
		(net "FLT_HDD11_DRIVE")
	)
	(segment
		(start 29.194506 -331.5462)
		(end 28.828746 -331.5462)
		(width 0.111252)
		(layer "F.Cu")
		(net "FLT_HDD11_DRIVE")
	)
	(segment
		(start 28.991814 -337.5787)
		(end 28.574746 -337.5787)
		(width 0.111252)
		(layer "F.Cu")
		(net "FLT_HDD11_DRIVE")
	)
	(segment
		(start 25.527 -336.0166)
		(end 26.3144 -336.804)
		(width 0.111252)
		(layer "F.Cu")
		(net "FLT_HDD11_DRIVE")
	)
	(segment
		(start 31.432246 -341.1347)
		(end 31.432246 -340.019132)
		(width 0.111252)
		(layer "F.Cu")
		(net "FLT_HDD11_DRIVE")
	)
	(segment
		(start 26.3144 -336.804)
		(end 27.800046 -336.804)
		(width 0.111252)
		(layer "F.Cu")
		(net "FLT_HDD11_DRIVE")
	)
	(segment
		(start 27.800046 -336.804)
		(end 28.574746 -337.5787)
		(width 0.111252)
		(layer "F.Cu")
		(net "FLT_HDD11_DRIVE")
	)
	(segment
		(start 28.828746 -331.5462)
		(end 27.711146 -332.6638)
		(width 0.111252)
		(layer "F.Cu")
		(net "FLT_HDD11_DRIVE")
	)
	(segment
		(start 27.711146 -333.045054)
		(end 25.527 -335.2292)
		(width 0.111252)
		(layer "F.Cu")
		(net "FLT_HDD11_DRIVE")
	)
	(segment
		(start 32.194246 -341.1347)
		(end 31.432246 -341.1347)
		(width 0.111252)
		(layer "F.Cu")
		(net "FLT_HDD11_DRIVE")
	)
	(segment
		(start 31.432246 -340.019132)
		(end 28.991814 -337.5787)
		(width 0.111252)
		(layer "F.Cu")
		(net "FLT_HDD11_DRIVE")
	)
	(via
		(at 28.574746 -337.5787)
		(size 0.7112)
		(drill 0.3556)
		(layers "F.Cu" "B.Cu")
		(net "FLT_HDD11_DRIVE")
	)
	(segment
		(start 24.484076 -468.1347)
		(end 22.363176 -470.2556)
		(width 0.111252)
		(layer "F.Cu")
		(net "FLT_HDD10_DRIVE")
	)
	(segment
		(start 18.732246 -469.7222)
		(end 18.732246 -469.6587)
		(width 0.111252)
		(layer "F.Cu")
		(net "FLT_HDD10_DRIVE")
	)
	(segment
		(start 24.891746 -468.1347)
		(end 24.484076 -468.1347)
		(width 0.111252)
		(layer "F.Cu")
		(net "FLT_HDD10_DRIVE")
	)
	(segment
		(start 18.008346 -470.3826)
		(end 18.732246 -469.6587)
		(width 0.111252)
		(layer "F.Cu")
		(net "FLT_HDD10_DRIVE")
	)
	(segment
		(start 22.363176 -470.2556)
		(end 19.265646 -470.2556)
		(width 0.111252)
		(layer "F.Cu")
		(net "FLT_HDD10_DRIVE")
	)
	(segment
		(start 17.106646 -470.3826)
		(end 18.008346 -470.3826)
		(width 0.111252)
		(layer "F.Cu")
		(net "FLT_HDD10_DRIVE")
	)
	(segment
		(start 31.432246 -435.60746)
		(end 31.432246 -434.7337)
		(width 0.111252)
		(layer "F.Cu")
		(net "FLT_HDD10_DRIVE")
	)
	(segment
		(start 19.265646 -470.2556)
		(end 18.732246 -469.7222)
		(width 0.111252)
		(layer "F.Cu")
		(net "FLT_HDD10_DRIVE")
	)
	(via
		(at 24.891746 -468.1347)
		(size 0.5588)
		(drill 0.3048)
		(layers "F.Cu" "B.Cu")
		(net "FLT_HDD10_DRIVE")
	)
	(via
		(at 32.384746 -433.8955)
		(size 0.7112)
		(drill 0.3556)
		(layers "F.Cu" "B.Cu")
		(net "FLT_HDD10_DRIVE")
	)
	(via
		(at 26.39568 -465.608416)
		(size 0.7112)
		(drill 0.3556)
		(layers "F.Cu" "B.Cu")
		(net "FLT_HDD10_DRIVE")
	)
	(via
		(at 31.432246 -434.7337)
		(size 0.5588)
		(drill 0.3048)
		(layers "F.Cu" "B.Cu")
		(net "FLT_HDD10_DRIVE")
	)
	(segment
		(start 24.891746 -467.11235)
		(end 26.39568 -465.608416)
		(width 0.111252)
		(layer "B.Cu")
		(net "FLT_HDD10_DRIVE")
	)
	(segment
		(start 36.16452 -443.592712)
		(end 36.16452 -436.167022)
		(width 0.111252)
		(layer "B.Cu")
		(net "FLT_HDD10_DRIVE")
	)
	(segment
		(start 24.891746 -468.1347)
		(end 24.891746 -467.11235)
		(width 0.111252)
		(layer "B.Cu")
		(net "FLT_HDD10_DRIVE")
	)
	(segment
		(start 31.432246 -434.7337)
		(end 32.270446 -433.8955)
		(width 0.111252)
		(layer "B.Cu")
		(net "FLT_HDD10_DRIVE")
	)
	(segment
		(start 34.748216 -433.890674)
		(end 32.389572 -433.890674)
		(width 0.111252)
		(layer "B.Cu")
		(net "FLT_HDD10_DRIVE")
	)
	(segment
		(start 36.403026 -435.928516)
		(end 36.403026 -435.545484)
		(width 0.111252)
		(layer "B.Cu")
		(net "FLT_HDD10_DRIVE")
	)
	(segment
		(start 26.39568 -465.608416)
		(end 36.7538 -455.250296)
		(width 0.111252)
		(layer "B.Cu")
		(net "FLT_HDD10_DRIVE")
	)
	(segment
		(start 36.7538 -444.181992)
		(end 36.16452 -443.592712)
		(width 0.111252)
		(layer "B.Cu")
		(net "FLT_HDD10_DRIVE")
	)
	(segment
		(start 32.389572 -433.890674)
		(end 32.384746 -433.8955)
		(width 0.111252)
		(layer "B.Cu")
		(net "FLT_HDD10_DRIVE")
	)
	(segment
		(start 32.270446 -433.8955)
		(end 32.384746 -433.8955)
		(width 0.111252)
		(layer "B.Cu")
		(net "FLT_HDD10_DRIVE")
	)
	(segment
		(start 36.403026 -435.545484)
		(end 34.748216 -433.890674)
		(width 0.111252)
		(layer "B.Cu")
		(net "FLT_HDD10_DRIVE")
	)
	(segment
		(start 36.7538 -455.250296)
		(end 36.7538 -444.181992)
		(width 0.111252)
		(layer "B.Cu")
		(net "FLT_HDD10_DRIVE")
	)
	(segment
		(start 36.16452 -436.167022)
		(end 36.403026 -435.928516)
		(width 0.111252)
		(layer "B.Cu")
		(net "FLT_HDD10_DRIVE")
	)
	(segment
		(start 3.193542 -215.501474)
		(end 7.30758 -215.501474)
		(width 0.111252)
		(layer "F.Cu")
		(net "SAS_EXP_B_PWR15")
	)
	(segment
		(start 3.19024 -215.504776)
		(end 3.193542 -215.501474)
		(width 0.111252)
		(layer "F.Cu")
		(net "SAS_EXP_B_PWR15")
	)
	(segment
		(start 7.30758 -215.501474)
		(end 7.619746 -215.81364)
		(width 0.111252)
		(layer "F.Cu")
		(net "SAS_EXP_B_PWR15")
	)
	(segment
		(start 46.519846 -38.3286)
		(end 46.900846 -37.9476)
		(width 0.111252)
		(layer "F.Cu")
		(net "FLT_HDD9_DRIVE")
	)
	(segment
		(start 74.675746 -74.5617)
		(end 74.421746 -74.8157)
		(width 0.111252)
		(layer "F.Cu")
		(net "FLT_HDD9_DRIVE")
	)
	(segment
		(start 46.519846 -39.0271)
		(end 46.519846 -38.608)
		(width 0.111252)
		(layer "F.Cu")
		(net "FLT_HDD9_DRIVE")
	)
	(segment
		(start 45.783246 -39.7637)
		(end 46.519846 -39.0271)
		(width 0.111252)
		(layer "F.Cu")
		(net "FLT_HDD9_DRIVE")
	)
	(segment
		(start 55.498746 -39.7637)
		(end 55.498746 -46.4947)
		(width 0.111252)
		(layer "F.Cu")
		(net "FLT_HDD9_DRIVE")
	)
	(segment
		(start 71.348346 -81.8261)
		(end 70.850506 -82.32394)
		(width 0.111252)
		(layer "F.Cu")
		(net "FLT_HDD9_DRIVE")
	)
	(segment
		(start 46.519846 -38.608)
		(end 46.519846 -38.3286)
		(width 0.111252)
		(layer "F.Cu")
		(net "FLT_HDD9_DRIVE")
	)
	(segment
		(start 74.421746 -74.8157)
		(end 74.421746 -80.5307)
		(width 0.111252)
		(layer "F.Cu")
		(net "FLT_HDD9_DRIVE")
	)
	(segment
		(start 53.682646 -37.9476)
		(end 55.498746 -39.7637)
		(width 0.111252)
		(layer "F.Cu")
		(net "FLT_HDD9_DRIVE")
	)
	(segment
		(start 73.126346 -81.8261)
		(end 71.348346 -81.8261)
		(width 0.111252)
		(layer "F.Cu")
		(net "FLT_HDD9_DRIVE")
	)
	(segment
		(start 70.850506 -82.32394)
		(end 70.850506 -83.1342)
		(width 0.111252)
		(layer "F.Cu")
		(net "FLT_HDD9_DRIVE")
	)
	(segment
		(start 74.421746 -80.5307)
		(end 73.126346 -81.8261)
		(width 0.111252)
		(layer "F.Cu")
		(net "FLT_HDD9_DRIVE")
	)
	(segment
		(start 46.900846 -37.9476)
		(end 53.682646 -37.9476)
		(width 0.111252)
		(layer "F.Cu")
		(net "FLT_HDD9_DRIVE")
	)
	(segment
		(start 55.498746 -48.3997)
		(end 55.498746 -46.4947)
		(width 0.111252)
		(layer "F.Cu")
		(net "FLT_HDD9_DRIVE")
	)
	(via
		(at 55.498746 -46.4947)
		(size 0.7112)
		(drill 0.3556)
		(layers "F.Cu" "B.Cu")
		(net "FLT_HDD9_DRIVE")
	)
	(via
		(at 55.498746 -48.3997)
		(size 0.5588)
		(drill 0.3048)
		(layers "F.Cu" "B.Cu")
		(net "FLT_HDD9_DRIVE")
	)
	(via
		(at 74.675746 -74.5617)
		(size 0.5588)
		(drill 0.3048)
		(layers "F.Cu" "B.Cu")
		(net "FLT_HDD9_DRIVE")
	)
	(segment
		(start 55.498746 -48.3997)
		(end 74.421746 -67.3227)
		(width 0.14605)
		(layer "In2.Cu")
		(net "FLT_HDD9_DRIVE")
	)
	(segment
		(start 74.421746 -67.3227)
		(end 74.421746 -74.3077)
		(width 0.14605)
		(layer "In2.Cu")
		(net "FLT_HDD9_DRIVE")
	)
	(segment
		(start 74.421746 -74.3077)
		(end 74.675746 -74.5617)
		(width 0.14605)
		(layer "In2.Cu")
		(net "FLT_HDD9_DRIVE")
	)
	(segment
		(start 45.211746 -142.0622)
		(end 46.519846 -142.0622)
		(width 0.111252)
		(layer "F.Cu")
		(net "FLT_HDD8_DRIVE")
	)
	(segment
		(start 46.519846 -141.3383)
		(end 46.608746 -141.2494)
		(width 0.111252)
		(layer "F.Cu")
		(net "FLT_HDD8_DRIVE")
	)
	(segment
		(start 46.519846 -142.0622)
		(end 46.519846 -141.3383)
		(width 0.111252)
		(layer "F.Cu")
		(net "FLT_HDD8_DRIVE")
	)
	(segment
		(start 45.211746 -142.6972)
		(end 45.211746 -142.0622)
		(width 0.111252)
		(layer "F.Cu")
		(net "FLT_HDD8_DRIVE")
	)
	(segment
		(start 45.783246 -143.2687)
		(end 45.211746 -142.6972)
		(width 0.111252)
		(layer "F.Cu")
		(net "FLT_HDD8_DRIVE")
	)
	(segment
		(start 71.104506 -186.3852)
		(end 71.104506 -185.06694)
		(width 0.111252)
		(layer "F.Cu")
		(net "FLT_HDD8_DRIVE")
	)
	(via
		(at 45.211746 -142.0622)
		(size 0.7112)
		(drill 0.3556)
		(layers "F.Cu" "B.Cu")
		(net "FLT_HDD8_DRIVE")
	)
	(via
		(at 71.104506 -185.06694)
		(size 0.5588)
		(drill 0.3048)
		(layers "F.Cu" "B.Cu")
		(net "FLT_HDD8_DRIVE")
	)
	(via
		(at 46.608746 -141.2494)
		(size 0.5588)
		(drill 0.3048)
		(layers "F.Cu" "B.Cu")
		(net "FLT_HDD8_DRIVE")
	)
	(segment
		(start 72.1868 -166.827454)
		(end 72.1868 -183.984646)
		(width 0.14605)
		(layer "In5.Cu")
		(net "FLT_HDD8_DRIVE")
	)
	(segment
		(start 72.1868 -183.984646)
		(end 71.104506 -185.06694)
		(width 0.14605)
		(layer "In5.Cu")
		(net "FLT_HDD8_DRIVE")
	)
	(segment
		(start 46.608746 -141.2494)
		(end 72.1868 -166.827454)
		(width 0.14605)
		(layer "In5.Cu")
		(net "FLT_HDD8_DRIVE")
	)
	(segment
		(start 43.8277 -244.2337)
		(end 45.465746 -244.2337)
		(width 0.111252)
		(layer "F.Cu")
		(net "FLT_HDD7_DRIVE")
	)
	(segment
		(start 45.783246 -245.7577)
		(end 46.646846 -244.8941)
		(width 0.111252)
		(layer "F.Cu")
		(net "FLT_HDD7_DRIVE")
	)
	(segment
		(start 46.646846 -244.8941)
		(end 46.646846 -244.6274)
		(width 0.111252)
		(layer "F.Cu")
		(net "FLT_HDD7_DRIVE")
	)
	(segment
		(start 46.253146 -244.2337)
		(end 45.465746 -244.2337)
		(width 0.111252)
		(layer "F.Cu")
		(net "FLT_HDD7_DRIVE")
	)
	(segment
		(start 43.688 -244.094)
		(end 43.8277 -244.2337)
		(width 0.111252)
		(layer "F.Cu")
		(net "FLT_HDD7_DRIVE")
	)
	(segment
		(start 29.6418 -270.129)
		(end 29.6418 -273.076924)
		(width 0.111252)
		(layer "F.Cu")
		(net "FLT_HDD7_DRIVE")
	)
	(segment
		(start 30.454346 -273.88947)
		(end 30.454346 -274.625054)
		(width 0.111252)
		(layer "F.Cu")
		(net "FLT_HDD7_DRIVE")
	)
	(segment
		(start 46.646846 -244.6274)
		(end 46.253146 -244.2337)
		(width 0.111252)
		(layer "F.Cu")
		(net "FLT_HDD7_DRIVE")
	)
	(segment
		(start 29.6418 -273.076924)
		(end 30.454346 -273.88947)
		(width 0.111252)
		(layer "F.Cu")
		(net "FLT_HDD7_DRIVE")
	)
	(segment
		(start 30.454346 -274.625054)
		(end 29.2862 -275.7932)
		(width 0.111252)
		(layer "F.Cu")
		(net "FLT_HDD7_DRIVE")
	)
	(segment
		(start 29.2862 -275.7932)
		(end 29.097986 -275.7932)
		(width 0.111252)
		(layer "F.Cu")
		(net "FLT_HDD7_DRIVE")
	)
	(via
		(at 43.688 -244.094)
		(size 0.5588)
		(drill 0.3048)
		(layers "F.Cu" "B.Cu")
		(net "FLT_HDD7_DRIVE")
	)
	(via
		(at 29.6418 -270.129)
		(size 0.5588)
		(drill 0.3048)
		(layers "F.Cu" "B.Cu")
		(net "FLT_HDD7_DRIVE")
	)
	(via
		(at 45.465746 -244.2337)
		(size 0.7112)
		(drill 0.3556)
		(layers "F.Cu" "B.Cu")
		(net "FLT_HDD7_DRIVE")
	)
	(segment
		(start 39.504874 -249.183398)
		(end 39.785798 -248.902474)
		(width 0.14605)
		(layer "In5.Cu")
		(net "FLT_HDD7_DRIVE")
	)
	(segment
		(start 39.785798 -248.902474)
		(end 39.785798 -248.885202)
		(width 0.14605)
		(layer "In5.Cu")
		(net "FLT_HDD7_DRIVE")
	)
	(segment
		(start 43.5483 -244.2337)
		(end 43.688 -244.094)
		(width 0.14605)
		(layer "In5.Cu")
		(net "FLT_HDD7_DRIVE")
	)
	(segment
		(start 29.6418 -270.129)
		(end 29.6418 -259.0292)
		(width 0.14605)
		(layer "In5.Cu")
		(net "FLT_HDD7_DRIVE")
	)
	(segment
		(start 39.487602 -249.183398)
		(end 39.504874 -249.183398)
		(width 0.14605)
		(layer "In5.Cu")
		(net "FLT_HDD7_DRIVE")
	)
	(segment
		(start 39.785798 -248.885202)
		(end 43.5483 -245.1227)
		(width 0.14605)
		(layer "In5.Cu")
		(net "FLT_HDD7_DRIVE")
	)
	(segment
		(start 43.5483 -245.1227)
		(end 43.5483 -244.2337)
		(width 0.14605)
		(layer "In5.Cu")
		(net "FLT_HDD7_DRIVE")
	)
	(segment
		(start 29.6418 -259.0292)
		(end 39.487602 -249.183398)
		(width 0.14605)
		(layer "In5.Cu")
		(net "FLT_HDD7_DRIVE")
	)
	(segment
		(start 70.865746 -390.398254)
		(end 70.865746 -392.36396)
		(width 0.111252)
		(layer "F.Cu")
		(net "FLT_HDD6_DRIVE")
	)
	(segment
		(start 70.865746 -392.36396)
		(end 70.850506 -392.3792)
		(width 0.111252)
		(layer "F.Cu")
		(net "FLT_HDD6_DRIVE")
	)
	(segment
		(start 50.583846 -345.4908)
		(end 50.291746 -345.1987)
		(width 0.111252)
		(layer "F.Cu")
		(net "FLT_HDD6_DRIVE")
	)
	(segment
		(start 50.583846 -346.1766)
		(end 50.583846 -345.4908)
		(width 0.111252)
		(layer "F.Cu")
		(net "FLT_HDD6_DRIVE")
	)
	(segment
		(start 74.93 -384.302)
		(end 74.93 -386.334)
		(width 0.111252)
		(layer "F.Cu")
		(net "FLT_HDD6_DRIVE")
	)
	(segment
		(start 50.583846 -347.3196)
		(end 50.583846 -346.1766)
		(width 0.111252)
		(layer "F.Cu")
		(net "FLT_HDD6_DRIVE")
	)
	(segment
		(start 74.93 -386.334)
		(end 70.865746 -390.398254)
		(width 0.111252)
		(layer "F.Cu")
		(net "FLT_HDD6_DRIVE")
	)
	(segment
		(start 49.466246 -348.7547)
		(end 49.466246 -348.4372)
		(width 0.111252)
		(layer "F.Cu")
		(net "FLT_HDD6_DRIVE")
	)
	(segment
		(start 49.466246 -348.4372)
		(end 50.583846 -347.3196)
		(width 0.111252)
		(layer "F.Cu")
		(net "FLT_HDD6_DRIVE")
	)
	(via
		(at 50.291746 -345.1987)
		(size 0.7112)
		(drill 0.3556)
		(layers "F.Cu" "B.Cu")
		(net "FLT_HDD6_DRIVE")
	)
	(via
		(at 74.93 -384.302)
		(size 0.5588)
		(drill 0.3048)
		(layers "F.Cu" "B.Cu")
		(net "FLT_HDD6_DRIVE")
	)
	(via
		(at 50.583846 -346.1766)
		(size 0.5588)
		(drill 0.3048)
		(layers "F.Cu" "B.Cu")
		(net "FLT_HDD6_DRIVE")
	)
	(segment
		(start 74.041 -367.919)
		(end 52.2986 -346.1766)
		(width 0.14605)
		(layer "In2.Cu")
		(net "FLT_HDD6_DRIVE")
	)
	(segment
		(start 74.041 -383.413)
		(end 74.041 -367.919)
		(width 0.14605)
		(layer "In2.Cu")
		(net "FLT_HDD6_DRIVE")
	)
	(segment
		(start 74.93 -384.302)
		(end 74.041 -383.413)
		(width 0.14605)
		(layer "In2.Cu")
		(net "FLT_HDD6_DRIVE")
	)
	(segment
		(start 52.2986 -346.1766)
		(end 50.583846 -346.1766)
		(width 0.14605)
		(layer "In2.Cu")
		(net "FLT_HDD6_DRIVE")
	)
	(segment
		(start 49.529746 -449.0847)
		(end 50.926746 -450.4817)
		(width 0.111252)
		(layer "F.Cu")
		(net "FLT_HDD5_DRIVE")
	)
	(segment
		(start 72.516746 -490.2327)
		(end 72.031606 -490.71784)
		(width 0.111252)
		(layer "F.Cu")
		(net "FLT_HDD5_DRIVE")
	)
	(segment
		(start 45.926756 -450.85889)
		(end 46.392846 -450.3928)
		(width 0.111252)
		(layer "F.Cu")
		(net "FLT_HDD5_DRIVE")
	)
	(segment
		(start 72.031606 -490.71784)
		(end 72.031606 -491.7948)
		(width 0.111252)
		(layer "F.Cu")
		(net "FLT_HDD5_DRIVE")
	)
	(segment
		(start 50.926746 -450.4817)
		(end 50.926746 -452.1327)
		(width 0.111252)
		(layer "F.Cu")
		(net "FLT_HDD5_DRIVE")
	)
	(segment
		(start 50.926746 -452.1327)
		(end 51.180746 -452.3867)
		(width 0.111252)
		(layer "F.Cu")
		(net "FLT_HDD5_DRIVE")
	)
	(segment
		(start 46.989746 -449.0847)
		(end 49.529746 -449.0847)
		(width 0.111252)
		(layer "F.Cu")
		(net "FLT_HDD5_DRIVE")
	)
	(segment
		(start 46.392846 -449.6816)
		(end 46.989746 -449.0847)
		(width 0.111252)
		(layer "F.Cu")
		(net "FLT_HDD5_DRIVE")
	)
	(segment
		(start 45.926756 -451.767702)
		(end 45.926756 -450.85889)
		(width 0.111252)
		(layer "F.Cu")
		(net "FLT_HDD5_DRIVE")
	)
	(segment
		(start 46.392846 -450.3928)
		(end 46.392846 -449.6816)
		(width 0.111252)
		(layer "F.Cu")
		(net "FLT_HDD5_DRIVE")
	)
	(via
		(at 72.516746 -490.2327)
		(size 0.5588)
		(drill 0.3048)
		(layers "F.Cu" "B.Cu")
		(net "FLT_HDD5_DRIVE")
	)
	(via
		(at 62.802008 -464.007962)
		(size 0.7112)
		(drill 0.3556)
		(layers "F.Cu" "B.Cu")
		(net "FLT_HDD5_DRIVE")
	)
	(via
		(at 51.180746 -452.3867)
		(size 0.5588)
		(drill 0.3048)
		(layers "F.Cu" "B.Cu")
		(net "FLT_HDD5_DRIVE")
	)
	(segment
		(start 62.802008 -464.007962)
		(end 51.180746 -452.3867)
		(width 0.111252)
		(layer "B.Cu")
		(net "FLT_HDD5_DRIVE")
	)
	(segment
		(start 73.243694 -489.505752)
		(end 73.243694 -474.449648)
		(width 0.111252)
		(layer "B.Cu")
		(net "FLT_HDD5_DRIVE")
	)
	(segment
		(start 72.516746 -490.2327)
		(end 73.243694 -489.505752)
		(width 0.111252)
		(layer "B.Cu")
		(net "FLT_HDD5_DRIVE")
	)
	(segment
		(start 73.243694 -474.449648)
		(end 62.802008 -464.007962)
		(width 0.111252)
		(layer "B.Cu")
		(net "FLT_HDD5_DRIVE")
	)
	(segment
		(start 198.881746 -83.5787)
		(end 198.881746 -82.0547)
		(width 0.111252)
		(layer "F.Cu")
		(net "FLT_HDD4_DRIVE")
	)
	(segment
		(start 198.881746 -82.0547)
		(end 199.326246 -81.6102)
		(width 0.111252)
		(layer "F.Cu")
		(net "FLT_HDD4_DRIVE")
	)
	(segment
		(start 234.441746 -40.2717)
		(end 235.610146 -40.2717)
		(width 0.111252)
		(layer "F.Cu")
		(net "FLT_HDD4_DRIVE")
	)
	(segment
		(start 218.947746 -50.3047)
		(end 213.486746 -55.7657)
		(width 0.111252)
		(layer "F.Cu")
		(net "FLT_HDD4_DRIVE")
	)
	(segment
		(start 235.622846 -39.8526)
		(end 235.902246 -39.5732)
		(width 0.111252)
		(layer "F.Cu")
		(net "FLT_HDD4_DRIVE")
	)
	(segment
		(start 213.486746 -55.7657)
		(end 212.851746 -55.7657)
		(width 0.111252)
		(layer "F.Cu")
		(net "FLT_HDD4_DRIVE")
	)
	(segment
		(start 235.198412 -41.763696)
		(end 234.441746 -41.00703)
		(width 0.111252)
		(layer "F.Cu")
		(net "FLT_HDD4_DRIVE")
	)
	(segment
		(start 234.441746 -41.00703)
		(end 234.441746 -40.2717)
		(width 0.111252)
		(layer "F.Cu")
		(net "FLT_HDD4_DRIVE")
	)
	(segment
		(start 235.622846 -40.259)
		(end 235.622846 -39.8526)
		(width 0.111252)
		(layer "F.Cu")
		(net "FLT_HDD4_DRIVE")
	)
	(segment
		(start 199.326246 -81.6102)
		(end 199.501506 -81.6102)
		(width 0.111252)
		(layer "F.Cu")
		(net "FLT_HDD4_DRIVE")
	)
	(segment
		(start 238.627158 -39.5732)
		(end 241.045746 -41.991788)
		(width 0.111252)
		(layer "F.Cu")
		(net "FLT_HDD4_DRIVE")
	)
	(segment
		(start 237.870746 -46.1137)
		(end 231.393746 -46.1137)
		(width 0.111252)
		(layer "F.Cu")
		(net "FLT_HDD4_DRIVE")
	)
	(segment
		(start 198.627746 -83.8327)
		(end 198.881746 -83.5787)
		(width 0.111252)
		(layer "F.Cu")
		(net "FLT_HDD4_DRIVE")
	)
	(segment
		(start 198.246746 -83.8327)
		(end 198.627746 -83.8327)
		(width 0.111252)
		(layer "F.Cu")
		(net "FLT_HDD4_DRIVE")
	)
	(segment
		(start 231.393746 -46.1137)
		(end 227.202746 -50.3047)
		(width 0.111252)
		(layer "F.Cu")
		(net "FLT_HDD4_DRIVE")
	)
	(segment
		(start 235.610146 -40.2717)
		(end 235.622846 -40.259)
		(width 0.111252)
		(layer "F.Cu")
		(net "FLT_HDD4_DRIVE")
	)
	(segment
		(start 241.045746 -42.95648)
		(end 238.898176 -45.10405)
		(width 0.111252)
		(layer "F.Cu")
		(net "FLT_HDD4_DRIVE")
	)
	(segment
		(start 238.880396 -45.10405)
		(end 237.870746 -46.1137)
		(width 0.111252)
		(layer "F.Cu")
		(net "FLT_HDD4_DRIVE")
	)
	(segment
		(start 241.045746 -41.991788)
		(end 241.045746 -42.95648)
		(width 0.111252)
		(layer "F.Cu")
		(net "FLT_HDD4_DRIVE")
	)
	(segment
		(start 235.902246 -39.5732)
		(end 238.627158 -39.5732)
		(width 0.111252)
		(layer "F.Cu")
		(net "FLT_HDD4_DRIVE")
	)
	(segment
		(start 227.202746 -50.3047)
		(end 218.947746 -50.3047)
		(width 0.111252)
		(layer "F.Cu")
		(net "FLT_HDD4_DRIVE")
	)
	(segment
		(start 238.898176 -45.10405)
		(end 238.880396 -45.10405)
		(width 0.111252)
		(layer "F.Cu")
		(net "FLT_HDD4_DRIVE")
	)
	(via
		(at 212.851746 -55.7657)
		(size 0.5588)
		(drill 0.3048)
		(layers "F.Cu" "B.Cu")
		(net "FLT_HDD4_DRIVE")
	)
	(via
		(at 234.441746 -40.2717)
		(size 0.7112)
		(drill 0.3556)
		(layers "F.Cu" "B.Cu")
		(net "FLT_HDD4_DRIVE")
	)
	(via
		(at 198.246746 -83.8327)
		(size 0.5588)
		(drill 0.3048)
		(layers "F.Cu" "B.Cu")
		(net "FLT_HDD4_DRIVE")
	)
	(segment
		(start 198.246746 -83.8327)
		(end 198.246746 -70.3707)
		(width 0.14605)
		(layer "In5.Cu")
		(net "FLT_HDD4_DRIVE")
	)
	(segment
		(start 198.246746 -70.3707)
		(end 212.851746 -55.7657)
		(width 0.14605)
		(layer "In5.Cu")
		(net "FLT_HDD4_DRIVE")
	)
	(segment
		(start 198.627746 -184.2897)
		(end 199.374506 -183.54294)
		(width 0.111252)
		(layer "F.Cu")
		(net "FLT_HDD3_DRIVE")
	)
	(segment
		(start 230.808784 -142.972028)
		(end 230.808784 -141.921738)
		(width 0.111252)
		(layer "F.Cu")
		(net "FLT_HDD3_DRIVE")
	)
	(segment
		(start 231.812846 -141.6812)
		(end 231.812846 -141.967966)
		(width 0.111252)
		(layer "F.Cu")
		(net "FLT_HDD3_DRIVE")
	)
	(segment
		(start 199.374506 -183.54294)
		(end 199.374506 -183.4642)
		(width 0.111252)
		(layer "F.Cu")
		(net "FLT_HDD3_DRIVE")
	)
	(segment
		(start 230.123746 -141.2367)
		(end 230.377746 -141.4907)
		(width 0.111252)
		(layer "F.Cu")
		(net "FLT_HDD3_DRIVE")
	)
	(segment
		(start 230.808784 -141.921738)
		(end 230.377746 -141.4907)
		(width 0.111252)
		(layer "F.Cu")
		(net "FLT_HDD3_DRIVE")
	)
	(segment
		(start 231.812846 -141.967966)
		(end 230.808784 -142.972028)
		(width 0.111252)
		(layer "F.Cu")
		(net "FLT_HDD3_DRIVE")
	)
	(segment
		(start 229.361746 -141.2367)
		(end 230.123746 -141.2367)
		(width 0.111252)
		(layer "F.Cu")
		(net "FLT_HDD3_DRIVE")
	)
	(via
		(at 198.627746 -184.2897)
		(size 0.5588)
		(drill 0.3048)
		(layers "F.Cu" "B.Cu")
		(net "FLT_HDD3_DRIVE")
	)
	(via
		(at 229.361746 -141.2367)
		(size 0.5588)
		(drill 0.3048)
		(layers "F.Cu" "B.Cu")
		(net "FLT_HDD3_DRIVE")
	)
	(via
		(at 230.377746 -141.4907)
		(size 0.7112)
		(drill 0.3556)
		(layers "F.Cu" "B.Cu")
		(net "FLT_HDD3_DRIVE")
	)
	(segment
		(start 198.1708 -168.04386)
		(end 224.97796 -141.2367)
		(width 0.14605)
		(layer "In5.Cu")
		(net "FLT_HDD3_DRIVE")
	)
	(segment
		(start 198.1708 -183.832754)
		(end 198.1708 -168.04386)
		(width 0.14605)
		(layer "In5.Cu")
		(net "FLT_HDD3_DRIVE")
	)
	(segment
		(start 224.97796 -141.2367)
		(end 229.361746 -141.2367)
		(width 0.14605)
		(layer "In5.Cu")
		(net "FLT_HDD3_DRIVE")
	)
	(segment
		(start 198.627746 -184.2897)
		(end 198.1708 -183.832754)
		(width 0.14605)
		(layer "In5.Cu")
		(net "FLT_HDD3_DRIVE")
	)
	(segment
		(start 230.849678 -245.463568)
		(end 231.939846 -244.3734)
		(width 0.111252)
		(layer "F.Cu")
		(net "FLT_HDD2_DRIVE")
	)
	(segment
		(start 197.992746 -287.2867)
		(end 199.247506 -286.03194)
		(width 0.111252)
		(layer "F.Cu")
		(net "FLT_HDD2_DRIVE")
	)
	(segment
		(start 231.939846 -244.3734)
		(end 231.165146 -243.5987)
		(width 0.111252)
		(layer "F.Cu")
		(net "FLT_HDD2_DRIVE")
	)
	(segment
		(start 230.780082 -245.463568)
		(end 230.849678 -245.463568)
		(width 0.111252)
		(layer "F.Cu")
		(net "FLT_HDD2_DRIVE")
	)
	(segment
		(start 199.247506 -286.03194)
		(end 199.247506 -285.8262)
		(width 0.111252)
		(layer "F.Cu")
		(net "FLT_HDD2_DRIVE")
	)
	(segment
		(start 229.501446 -243.5987)
		(end 228.726746 -244.3734)
		(width 0.111252)
		(layer "F.Cu")
		(net "FLT_HDD2_DRIVE")
	)
	(segment
		(start 231.165146 -243.5987)
		(end 229.501446 -243.5987)
		(width 0.111252)
		(layer "F.Cu")
		(net "FLT_HDD2_DRIVE")
	)
	(via
		(at 228.726746 -244.3734)
		(size 0.5588)
		(drill 0.3048)
		(layers "F.Cu" "B.Cu")
		(net "FLT_HDD2_DRIVE")
	)
	(via
		(at 198.798688 -286.803084)
		(size 0.7112)
		(drill 0.3556)
		(layers "F.Cu" "B.Cu")
		(net "FLT_HDD2_DRIVE")
	)
	(via
		(at 197.992746 -287.2867)
		(size 0.5588)
		(drill 0.3048)
		(layers "F.Cu" "B.Cu")
		(net "FLT_HDD2_DRIVE")
	)
	(segment
		(start 198.476362 -286.803084)
		(end 198.798688 -286.803084)
		(width 0.111252)
		(layer "B.Cu")
		(net "FLT_HDD2_DRIVE")
	)
	(segment
		(start 197.992746 -287.2867)
		(end 198.476362 -286.803084)
		(width 0.111252)
		(layer "B.Cu")
		(net "FLT_HDD2_DRIVE")
	)
	(segment
		(start 228.726746 -244.3734)
		(end 227.8634 -244.3734)
		(width 0.14605)
		(layer "In5.Cu")
		(net "FLT_HDD2_DRIVE")
	)
	(segment
		(start 227.8634 -244.3734)
		(end 197.992746 -274.244054)
		(width 0.14605)
		(layer "In5.Cu")
		(net "FLT_HDD2_DRIVE")
	)
	(segment
		(start 197.992746 -274.244054)
		(end 197.992746 -287.2867)
		(width 0.14605)
		(layer "In5.Cu")
		(net "FLT_HDD2_DRIVE")
	)
	(segment
		(start 199.262746 -388.3787)
		(end 199.282558 -388.398512)
		(width 0.111252)
		(layer "F.Cu")
		(net "FLT_HDD1_DRIVE")
	)
	(segment
		(start 219.328746 -347.3577)
		(end 218.909646 -347.7768)
		(width 0.111252)
		(layer "F.Cu")
		(net "FLT_HDD1_DRIVE")
	)
	(segment
		(start 220.916246 -347.3577)
		(end 219.328746 -347.3577)
		(width 0.111252)
		(layer "F.Cu")
		(net "FLT_HDD1_DRIVE")
	)
	(segment
		(start 199.282558 -388.398512)
		(end 200.074022 -388.398512)
		(width 0.111252)
		(layer "F.Cu")
		(net "FLT_HDD1_DRIVE")
	)
	(segment
		(start 218.909646 -347.7768)
		(end 218.909646 -348.5388)
		(width 0.111252)
		(layer "F.Cu")
		(net "FLT_HDD1_DRIVE")
	)
	(segment
		(start 218.909646 -348.5388)
		(end 218.909646 -349.5167)
		(width 0.111252)
		(layer "F.Cu")
		(net "FLT_HDD1_DRIVE")
	)
	(via
		(at 218.909646 -349.5167)
		(size 0.5588)
		(drill 0.3048)
		(layers "F.Cu" "B.Cu")
		(net "FLT_HDD1_DRIVE")
	)
	(via
		(at 218.909646 -351.409)
		(size 0.7112)
		(drill 0.3556)
		(layers "F.Cu" "B.Cu")
		(net "FLT_HDD1_DRIVE")
	)
	(via
		(at 199.262746 -388.3787)
		(size 0.5588)
		(drill 0.3048)
		(layers "F.Cu" "B.Cu")
		(net "FLT_HDD1_DRIVE")
	)
	(segment
		(start 224.345246 -373.5832)
		(end 224.345246 -369.6462)
		(width 0.111252)
		(layer "B.Cu")
		(net "FLT_HDD1_DRIVE")
	)
	(segment
		(start 218.909646 -351.409)
		(end 218.909646 -349.5167)
		(width 0.111252)
		(layer "B.Cu")
		(net "FLT_HDD1_DRIVE")
	)
	(segment
		(start 199.262746 -388.3787)
		(end 200.533 -387.108446)
		(width 0.111252)
		(layer "B.Cu")
		(net "FLT_HDD1_DRIVE")
	)
	(segment
		(start 200.533 -378.980446)
		(end 202.729846 -376.7836)
		(width 0.111252)
		(layer "B.Cu")
		(net "FLT_HDD1_DRIVE")
	)
	(segment
		(start 202.729846 -376.7836)
		(end 221.144846 -376.7836)
		(width 0.111252)
		(layer "B.Cu")
		(net "FLT_HDD1_DRIVE")
	)
	(segment
		(start 224.345246 -369.6462)
		(end 218.909646 -364.2106)
		(width 0.111252)
		(layer "B.Cu")
		(net "FLT_HDD1_DRIVE")
	)
	(segment
		(start 200.533 -387.108446)
		(end 200.533 -378.980446)
		(width 0.111252)
		(layer "B.Cu")
		(net "FLT_HDD1_DRIVE")
	)
	(segment
		(start 221.144846 -376.7836)
		(end 224.345246 -373.5832)
		(width 0.111252)
		(layer "B.Cu")
		(net "FLT_HDD1_DRIVE")
	)
	(segment
		(start 218.909646 -364.2106)
		(end 218.909646 -351.409)
		(width 0.111252)
		(layer "B.Cu")
		(net "FLT_HDD1_DRIVE")
	)
	(segment
		(start 199.199246 -491.6932)
		(end 199.628506 -491.6932)
		(width 0.111252)
		(layer "F.Cu")
		(net "FLT_HDD0_DRIVE")
	)
	(segment
		(start 230.711756 -451.513702)
		(end 232.667302 -451.513702)
		(width 0.111252)
		(layer "F.Cu")
		(net "FLT_HDD0_DRIVE")
	)
	(segment
		(start 231.812846 -450.412612)
		(end 230.711756 -451.513702)
		(width 0.111252)
		(layer "F.Cu")
		(net "FLT_HDD0_DRIVE")
	)
	(segment
		(start 231.812846 -450.0118)
		(end 231.812846 -450.412612)
		(width 0.111252)
		(layer "F.Cu")
		(net "FLT_HDD0_DRIVE")
	)
	(segment
		(start 232.667302 -451.513702)
		(end 233.044746 -451.891146)
		(width 0.111252)
		(layer "F.Cu")
		(net "FLT_HDD0_DRIVE")
	)
	(segment
		(start 233.044746 -451.891146)
		(end 233.044746 -456.3237)
		(width 0.111252)
		(layer "F.Cu")
		(net "FLT_HDD0_DRIVE")
	)
	(segment
		(start 198.881746 -492.0107)
		(end 199.199246 -491.6932)
		(width 0.111252)
		(layer "F.Cu")
		(net "FLT_HDD0_DRIVE")
	)
	(via
		(at 233.044746 -456.3237)
		(size 0.5588)
		(drill 0.3048)
		(layers "F.Cu" "B.Cu")
		(net "FLT_HDD0_DRIVE")
	)
	(via
		(at 211.835746 -478.2947)
		(size 0.7112)
		(drill 0.3556)
		(layers "F.Cu" "B.Cu")
		(net "FLT_HDD0_DRIVE")
	)
	(via
		(at 198.881746 -492.0107)
		(size 0.5588)
		(drill 0.3048)
		(layers "F.Cu" "B.Cu")
		(net "FLT_HDD0_DRIVE")
	)
	(segment
		(start 219.843096 -474.98635)
		(end 216.534746 -478.2947)
		(width 0.111252)
		(layer "B.Cu")
		(net "FLT_HDD0_DRIVE")
	)
	(segment
		(start 233.044746 -462.000854)
		(end 220.05925 -474.98635)
		(width 0.111252)
		(layer "B.Cu")
		(net "FLT_HDD0_DRIVE")
	)
	(segment
		(start 198.881746 -486.537254)
		(end 207.1243 -478.2947)
		(width 0.111252)
		(layer "B.Cu")
		(net "FLT_HDD0_DRIVE")
	)
	(segment
		(start 216.534746 -478.2947)
		(end 211.835746 -478.2947)
		(width 0.111252)
		(layer "B.Cu")
		(net "FLT_HDD0_DRIVE")
	)
	(segment
		(start 207.1243 -478.2947)
		(end 211.835746 -478.2947)
		(width 0.111252)
		(layer "B.Cu")
		(net "FLT_HDD0_DRIVE")
	)
	(segment
		(start 233.044746 -456.3237)
		(end 233.044746 -462.000854)
		(width 0.111252)
		(layer "B.Cu")
		(net "FLT_HDD0_DRIVE")
	)
	(segment
		(start 198.881746 -492.0107)
		(end 198.881746 -486.537254)
		(width 0.111252)
		(layer "B.Cu")
		(net "FLT_HDD0_DRIVE")
	)
	(segment
		(start 220.05925 -474.98635)
		(end 219.843096 -474.98635)
		(width 0.111252)
		(layer "B.Cu")
		(net "FLT_HDD0_DRIVE")
	)
	(segment
		(start 210.935062 -49.054766)
		(end 210.935062 -50.824384)
		(width 0.111252)
		(layer "F.Cu")
		(net "TMP4_SCL")
	)
	(segment
		(start 210.692746 -52.0192)
		(end 210.819746 -51.8922)
		(width 0.111252)
		(layer "F.Cu")
		(net "TMP4_SCL")
	)
	(segment
		(start 210.819746 -51.8922)
		(end 210.819746 -50.9397)
		(width 0.111252)
		(layer "F.Cu")
		(net "TMP4_SCL")
	)
	(segment
		(start 210.935062 -50.824384)
		(end 210.819746 -50.9397)
		(width 0.111252)
		(layer "F.Cu")
		(net "TMP4_SCL")
	)
	(via
		(at 210.819746 -50.9397)
		(size 0.7112)
		(drill 0.3556)
		(layers "F.Cu" "B.Cu")
		(net "TMP4_SCL")
	)
	(segment
		(start 212.927946 -52.0192)
		(end 211.835746 -52.0192)
		(width 0.111252)
		(layer "F.Cu")
		(net "TMP4_SDA")
	)
	(segment
		(start 211.835746 -52.0192)
		(end 211.585302 -51.768756)
		(width 0.111252)
		(layer "F.Cu")
		(net "TMP4_SDA")
	)
	(segment
		(start 211.585302 -51.768756)
		(end 211.585302 -49.054766)
		(width 0.111252)
		(layer "F.Cu")
		(net "TMP4_SDA")
	)
	(via
		(at 212.927946 -52.0192)
		(size 0.7112)
		(drill 0.3556)
		(layers "F.Cu" "B.Cu")
		(net "TMP4_SDA")
	)
	(segment
		(start 210.047586 -462.8642)
		(end 207.771746 -462.8642)
		(width 0.111252)
		(layer "F.Cu")
		(net "TMP3_SCL")
	)
	(segment
		(start 207.581246 -462.6737)
		(end 207.581246 -461.9752)
		(width 0.111252)
		(layer "F.Cu")
		(net "TMP3_SCL")
	)
	(segment
		(start 207.581246 -461.9752)
		(end 207.136746 -461.5307)
		(width 0.111252)
		(layer "F.Cu")
		(net "TMP3_SCL")
	)
	(segment
		(start 210.935062 -461.054958)
		(end 210.935062 -461.976724)
		(width 0.111252)
		(layer "F.Cu")
		(net "TMP3_SCL")
	)
	(segment
		(start 210.935062 -461.976724)
		(end 210.047586 -462.8642)
		(width 0.111252)
		(layer "F.Cu")
		(net "TMP3_SCL")
	)
	(segment
		(start 207.771746 -462.8642)
		(end 207.581246 -462.6737)
		(width 0.111252)
		(layer "F.Cu")
		(net "TMP3_SCL")
	)
	(via
		(at 207.136746 -461.5307)
		(size 0.7112)
		(drill 0.3556)
		(layers "F.Cu" "B.Cu")
		(net "TMP3_SCL")
	)
	(segment
		(start 207.708246 -463.5627)
		(end 209.168746 -463.5627)
		(width 0.111252)
		(layer "F.Cu")
		(net "TMP3_SDA")
	)
	(segment
		(start 211.585302 -462.009236)
		(end 210.031838 -463.5627)
		(width 0.111252)
		(layer "F.Cu")
		(net "TMP3_SDA")
	)
	(segment
		(start 207.581246 -463.6897)
		(end 207.708246 -463.5627)
		(width 0.111252)
		(layer "F.Cu")
		(net "TMP3_SDA")
	)
	(segment
		(start 211.585302 -461.054958)
		(end 211.585302 -462.009236)
		(width 0.111252)
		(layer "F.Cu")
		(net "TMP3_SDA")
	)
	(segment
		(start 210.031838 -463.5627)
		(end 209.168746 -463.5627)
		(width 0.111252)
		(layer "F.Cu")
		(net "TMP3_SDA")
	)
	(via
		(at 209.168746 -463.5627)
		(size 0.7112)
		(drill 0.3556)
		(layers "F.Cu" "B.Cu")
		(net "TMP3_SDA")
	)
	(segment
		(start 42.925238 -138.302238)
		(end 42.925238 -139.564872)
		(width 0.111252)
		(layer "F.Cu")
		(net "TMP2_SCL")
	)
	(segment
		(start 42.545 -137.922)
		(end 42.925238 -138.302238)
		(width 0.111252)
		(layer "F.Cu")
		(net "TMP2_SCL")
	)
	(segment
		(start 40.017446 -138.2395)
		(end 40.334946 -137.922)
		(width 0.111252)
		(layer "F.Cu")
		(net "TMP2_SCL")
	)
	(segment
		(start 40.334946 -137.922)
		(end 42.545 -137.922)
		(width 0.111252)
		(layer "F.Cu")
		(net "TMP2_SCL")
	)
	(segment
		(start 40.017446 -139.065)
		(end 40.017446 -138.2395)
		(width 0.111252)
		(layer "F.Cu")
		(net "TMP2_SCL")
	)
	(segment
		(start 39.750746 -139.3317)
		(end 40.017446 -139.065)
		(width 0.111252)
		(layer "F.Cu")
		(net "TMP2_SCL")
	)
	(via
		(at 39.750746 -139.3317)
		(size 0.7112)
		(drill 0.3556)
		(layers "F.Cu" "B.Cu")
		(net "TMP2_SCL")
	)
	(segment
		(start 43.575478 -138.269726)
		(end 43.575478 -139.564872)
		(width 0.111252)
		(layer "F.Cu")
		(net "TMP2_SDA")
	)
	(segment
		(start 40.284146 -137.4394)
		(end 42.745152 -137.4394)
		(width 0.111252)
		(layer "F.Cu")
		(net "TMP2_SDA")
	)
	(segment
		(start 42.745152 -137.4394)
		(end 43.575478 -138.269726)
		(width 0.111252)
		(layer "F.Cu")
		(net "TMP2_SDA")
	)
	(segment
		(start 39.623746 -136.08685)
		(end 39.623746 -136.2837)
		(width 0.111252)
		(layer "F.Cu")
		(net "TMP2_SDA")
	)
	(segment
		(start 39.623746 -136.2837)
		(end 40.017446 -136.6774)
		(width 0.111252)
		(layer "F.Cu")
		(net "TMP2_SDA")
	)
	(segment
		(start 40.017446 -137.1727)
		(end 40.284146 -137.4394)
		(width 0.111252)
		(layer "F.Cu")
		(net "TMP2_SDA")
	)
	(segment
		(start 40.017446 -136.6774)
		(end 40.017446 -137.1727)
		(width 0.111252)
		(layer "F.Cu")
		(net "TMP2_SDA")
	)
	(via
		(at 39.623746 -136.08685)
		(size 0.7112)
		(drill 0.3556)
		(layers "F.Cu" "B.Cu")
		(net "TMP2_SDA")
	)
	(segment
		(start 28.600146 -383.5654)
		(end 28.82519 -383.340356)
		(width 0.111252)
		(layer "F.Cu")
		(net "TMP1_SCL")
	)
	(segment
		(start 27.432 -384.760216)
		(end 28.600146 -383.59207)
		(width 0.111252)
		(layer "F.Cu")
		(net "TMP1_SCL")
	)
	(segment
		(start 28.600146 -383.59207)
		(end 28.600146 -383.5654)
		(width 0.111252)
		(layer "F.Cu")
		(net "TMP1_SCL")
	)
	(segment
		(start 28.82519 -383.340356)
		(end 28.82519 -381.294894)
		(width 0.111252)
		(layer "F.Cu")
		(net "TMP1_SCL")
	)
	(segment
		(start 27.432 -385.318)
		(end 27.432 -384.760216)
		(width 0.111252)
		(layer "F.Cu")
		(net "TMP1_SCL")
	)
	(via
		(at 27.432 -385.318)
		(size 0.7112)
		(drill 0.3556)
		(layers "F.Cu" "B.Cu")
		(net "TMP1_SCL")
	)
	(segment
		(start 13.467334 -55.923688)
		(end 13.169646 -55.626)
		(width 0.111252)
		(layer "F.Cu")
		(net "FLT_HDD14_DRIVE")
	)
	(segment
		(start 16.640556 -55.344314)
		(end 16.640556 -55.364888)
		(width 0.111252)
		(layer "F.Cu")
		(net "FLT_HDD14_DRIVE")
	)
	(segment
		(start 91.850464 -14.968982)
		(end 91.185746 -15.6337)
		(width 0.111252)
		(layer "F.Cu")
		(net "FLT_HDD14_DRIVE")
	)
	(segment
		(start 16.763746 -54.8767)
		(end 16.763746 -55.221124)
		(width 0.111252)
		(layer "F.Cu")
		(net "FLT_HDD14_DRIVE")
	)
	(segment
		(start 16.081756 -55.923688)
		(end 13.467334 -55.923688)
		(width 0.111252)
		(layer "F.Cu")
		(net "FLT_HDD14_DRIVE")
	)
	(segment
		(start 14.160246 -54.1528)
		(end 13.169646 -55.1434)
		(width 0.111252)
		(layer "F.Cu")
		(net "FLT_HDD14_DRIVE")
	)
	(segment
		(start 14.160246 -53.7337)
		(end 14.160246 -54.1528)
		(width 0.111252)
		(layer "F.Cu")
		(net "FLT_HDD14_DRIVE")
	)
	(segment
		(start 16.763746 -55.221124)
		(end 16.640556 -55.344314)
		(width 0.111252)
		(layer "F.Cu")
		(net "FLT_HDD14_DRIVE")
	)
	(segment
		(start 91.185746 -15.6337)
		(end 91.073986 -15.74546)
		(width 0.111252)
		(layer "F.Cu")
		(net "FLT_HDD14_DRIVE")
	)
	(segment
		(start 16.640556 -55.364888)
		(end 16.081756 -55.923688)
		(width 0.111252)
		(layer "F.Cu")
		(net "FLT_HDD14_DRIVE")
	)
	(segment
		(start 13.169646 -55.626)
		(end 13.169646 -55.1434)
		(width 0.111252)
		(layer "F.Cu")
		(net "FLT_HDD14_DRIVE")
	)
	(segment
		(start 91.073986 -15.74546)
		(end 89.979246 -15.74546)
		(width 0.111252)
		(layer "F.Cu")
		(net "FLT_HDD14_DRIVE")
	)
	(via
		(at 91.185746 -15.6337)
		(size 0.5588)
		(drill 0.3048)
		(layers "F.Cu" "B.Cu")
		(net "FLT_HDD14_DRIVE")
	)
	(via
		(at 16.763746 -54.8767)
		(size 0.5588)
		(drill 0.3048)
		(layers "F.Cu" "B.Cu")
		(net "FLT_HDD14_DRIVE")
	)
	(via
		(at 91.850464 -14.968982)
		(size 0.7112)
		(drill 0.3556)
		(layers "F.Cu" "B.Cu")
		(net "FLT_HDD14_DRIVE")
	)
	(segment
		(start 24.351488 -54.8767)
		(end 16.763746 -54.8767)
		(width 0.14605)
		(layer "In2.Cu")
		(net "FLT_HDD14_DRIVE")
	)
	(segment
		(start 82.3976 -24.82469)
		(end 82.3976 -25.5524)
		(width 0.14605)
		(layer "In2.Cu")
		(net "FLT_HDD14_DRIVE")
	)
	(segment
		(start 57.2516 -40.9194)
		(end 38.30828 -40.9194)
		(width 0.14605)
		(layer "In2.Cu")
		(net "FLT_HDD14_DRIVE")
	)
	(segment
		(start 67.1068 -40.8432)
		(end 59.2328 -40.8432)
		(width 0.14605)
		(layer "In2.Cu")
		(net "FLT_HDD14_DRIVE")
	)
	(segment
		(start 37.22624 -42.00144)
		(end 33.030668 -46.19752)
		(width 0.14605)
		(layer "In2.Cu")
		(net "FLT_HDD14_DRIVE")
	)
	(segment
		(start 59.2328 -40.8432)
		(end 58.4962 -41.5798)
		(width 0.14605)
		(layer "In2.Cu")
		(net "FLT_HDD14_DRIVE")
	)
	(segment
		(start 57.912 -41.5798)
		(end 57.2516 -40.9194)
		(width 0.14605)
		(layer "In2.Cu")
		(net "FLT_HDD14_DRIVE")
	)
	(segment
		(start 82.3976 -25.5524)
		(end 67.1068 -40.8432)
		(width 0.14605)
		(layer "In2.Cu")
		(net "FLT_HDD14_DRIVE")
	)
	(segment
		(start 91.185746 -16.036544)
		(end 82.3976 -24.82469)
		(width 0.14605)
		(layer "In2.Cu")
		(net "FLT_HDD14_DRIVE")
	)
	(segment
		(start 91.185746 -15.6337)
		(end 91.185746 -16.036544)
		(width 0.14605)
		(layer "In2.Cu")
		(net "FLT_HDD14_DRIVE")
	)
	(segment
		(start 58.4962 -41.5798)
		(end 57.912 -41.5798)
		(width 0.14605)
		(layer "In2.Cu")
		(net "FLT_HDD14_DRIVE")
	)
	(segment
		(start 33.030668 -46.19752)
		(end 24.351488 -54.8767)
		(width 0.14605)
		(layer "In2.Cu")
		(net "FLT_HDD14_DRIVE")
	)
	(segment
		(start 38.30828 -40.9194)
		(end 37.22624 -42.00144)
		(width 0.14605)
		(layer "In2.Cu")
		(net "FLT_HDD14_DRIVE")
	)
	(segment
		(start 9.1186 -465.5058)
		(end 8.8646 -465.7598)
		(width 0.111252)
		(layer "F.Cu")
		(net "SAS_EXP_A_PWR15")
	)
	(segment
		(start 6.6294 -465.501482)
		(end 3.193542 -465.501482)
		(width 0.111252)
		(layer "F.Cu")
		(net "SAS_EXP_A_PWR15")
	)
	(segment
		(start 6.887718 -465.7598)
		(end 6.6294 -465.501482)
		(width 0.111252)
		(layer "F.Cu")
		(net "SAS_EXP_A_PWR15")
	)
	(segment
		(start 8.8646 -465.7598)
		(end 6.887718 -465.7598)
		(width 0.111252)
		(layer "F.Cu")
		(net "SAS_EXP_A_PWR15")
	)
	(segment
		(start 3.193542 -465.501482)
		(end 3.19024 -465.504784)
		(width 0.111252)
		(layer "F.Cu")
		(net "SAS_EXP_A_PWR15")
	)
	(segment
		(start 199.592946 -457.361036)
		(end 199.425306 -457.528676)
		(width 0.111252)
		(layer "F.Cu")
		(net "EEPROM_SDA")
	)
	(segment
		(start 199.592946 -456.091036)
		(end 199.592946 -457.361036)
		(width 0.111252)
		(layer "F.Cu")
		(net "EEPROM_SDA")
	)
	(segment
		(start 199.425306 -457.528676)
		(end 197.141846 -457.528676)
		(width 0.111252)
		(layer "F.Cu")
		(net "EEPROM_SDA")
	)
	(via
		(at 199.592946 -456.091036)
		(size 0.7112)
		(drill 0.3556)
		(layers "F.Cu" "B.Cu")
		(net "EEPROM_SDA")
	)
	(segment
		(start 29.654246 -383.5654)
		(end 29.47543 -383.386584)
		(width 0.111252)
		(layer "F.Cu")
		(net "TMP1_SDA")
	)
	(segment
		(start 30.619446 -383.5654)
		(end 29.654246 -383.5654)
		(width 0.111252)
		(layer "F.Cu")
		(net "TMP1_SDA")
	)
	(segment
		(start 30.860746 -383.8067)
		(end 30.619446 -383.5654)
		(width 0.111252)
		(layer "F.Cu")
		(net "TMP1_SDA")
	)
	(segment
		(start 29.47543 -383.386584)
		(end 29.47543 -381.294894)
		(width 0.111252)
		(layer "F.Cu")
		(net "TMP1_SDA")
	)
	(via
		(at 30.860746 -383.8067)
		(size 0.7112)
		(drill 0.3556)
		(layers "F.Cu" "B.Cu")
		(net "TMP1_SDA")
	)
	(segment
		(start 199.394826 -458.178916)
		(end 199.592946 -458.377036)
		(width 0.111252)
		(layer "F.Cu")
		(net "EEPROM_SCL")
	)
	(segment
		(start 199.592946 -458.377036)
		(end 199.592946 -459.240636)
		(width 0.111252)
		(layer "F.Cu")
		(net "EEPROM_SCL")
	)
	(segment
		(start 199.592946 -459.240636)
		(end 199.821546 -459.469236)
		(width 0.111252)
		(layer "F.Cu")
		(net "EEPROM_SCL")
	)
	(segment
		(start 197.141846 -458.178916)
		(end 199.394826 -458.178916)
		(width 0.111252)
		(layer "F.Cu")
		(net "EEPROM_SCL")
	)
	(via
		(at 199.821546 -459.469236)
		(size 0.7112)
		(drill 0.3556)
		(layers "F.Cu" "B.Cu")
		(net "EEPROM_SCL")
	)
	(segment
		(start 8.337296 -399.98015)
		(end 5.869178 -399.98015)
		(width 0.111252)
		(layer "F.Cu")
		(net "SAS2X28_A_HDD15_FLT")
	)
	(segment
		(start 5.345938 -399.45691)
		(end 5.345938 -399.234914)
		(width 0.111252)
		(layer "F.Cu")
		(net "SAS2X28_A_HDD15_FLT")
	)
	(segment
		(start 5.345938 -399.234914)
		(end 4.61137 -398.500346)
		(width 0.111252)
		(layer "F.Cu")
		(net "SAS2X28_A_HDD15_FLT")
	)
	(segment
		(start 5.869178 -399.98015)
		(end 5.345938 -399.45691)
		(width 0.111252)
		(layer "F.Cu")
		(net "SAS2X28_A_HDD15_FLT")
	)
	(segment
		(start 4.61137 -398.500346)
		(end 3.19405 -398.500346)
		(width 0.111252)
		(layer "F.Cu")
		(net "SAS2X28_A_HDD15_FLT")
	)
	(segment
		(start 8.889746 -399.4277)
		(end 8.337296 -399.98015)
		(width 0.111252)
		(layer "F.Cu")
		(net "SAS2X28_A_HDD15_FLT")
	)
	(segment
		(start 3.19405 -398.500346)
		(end 3.192526 -398.498822)
		(width 0.111252)
		(layer "F.Cu")
		(net "SAS2X28_A_HDD15_FLT")
	)
	(segment
		(start 42.5196 -247.0404)
		(end 42.5196 -245.732554)
		(width 0.111252)
		(layer "F.Cu")
		(net "DRV_ACT_7")
	)
	(segment
		(start 41.769792 -247.566434)
		(end 41.993566 -247.566434)
		(width 0.111252)
		(layer "F.Cu")
		(net "DRV_ACT_7")
	)
	(segment
		(start 40.195246 -247.7897)
		(end 40.421814 -247.563132)
		(width 0.111252)
		(layer "F.Cu")
		(net "DRV_ACT_7")
	)
	(segment
		(start 42.5196 -245.732554)
		(end 41.909746 -245.1227)
		(width 0.111252)
		(layer "F.Cu")
		(net "DRV_ACT_7")
	)
	(segment
		(start 41.993566 -247.566434)
		(end 42.5196 -247.0404)
		(width 0.111252)
		(layer "F.Cu")
		(net "DRV_ACT_7")
	)
	(segment
		(start 41.76649 -247.563132)
		(end 41.769792 -247.566434)
		(width 0.111252)
		(layer "F.Cu")
		(net "DRV_ACT_7")
	)
	(segment
		(start 40.421814 -247.563132)
		(end 41.76649 -247.563132)
		(width 0.111252)
		(layer "F.Cu")
		(net "DRV_ACT_7")
	)
	(via
		(at 41.909746 -245.1227)
		(size 0.7112)
		(drill 0.3556)
		(layers "F.Cu" "B.Cu")
		(net "DRV_ACT_7")
	)
	(segment
		(start 227.456746 -144.1577)
		(end 227.865432 -144.566386)
		(width 0.111252)
		(layer "F.Cu")
		(net "DRV_ACT_NET3")
	)
	(segment
		(start 229.919784 -143.988028)
		(end 229.341426 -144.566386)
		(width 0.111252)
		(layer "F.Cu")
		(net "DRV_ACT_NET3")
	)
	(segment
		(start 227.1268 -142.3416)
		(end 227.139754 -142.3416)
		(width 0.111252)
		(layer "F.Cu")
		(net "DRV_ACT_NET3")
	)
	(segment
		(start 227.865432 -144.566386)
		(end 228.230176 -144.566386)
		(width 0.111252)
		(layer "F.Cu")
		(net "DRV_ACT_NET3")
	)
	(segment
		(start 229.341426 -144.566386)
		(end 228.230176 -144.566386)
		(width 0.111252)
		(layer "F.Cu")
		(net "DRV_ACT_NET3")
	)
	(segment
		(start 227.456746 -142.658592)
		(end 227.456746 -144.1577)
		(width 0.111252)
		(layer "F.Cu")
		(net "DRV_ACT_NET3")
	)
	(segment
		(start 227.139754 -142.3416)
		(end 227.456746 -142.658592)
		(width 0.111252)
		(layer "F.Cu")
		(net "DRV_ACT_NET3")
	)
	(via
		(at 227.1268 -142.3416)
		(size 0.7112)
		(drill 0.3556)
		(layers "F.Cu" "B.Cu")
		(net "DRV_ACT_NET3")
	)
	(segment
		(start 41.990518 -350.566482)
		(end 42.544746 -350.012254)
		(width 0.111252)
		(layer "F.Cu")
		(net "DRV_ACT_6")
	)
	(segment
		(start 41.769792 -350.566482)
		(end 41.990518 -350.566482)
		(width 0.111252)
		(layer "F.Cu")
		(net "DRV_ACT_6")
	)
	(segment
		(start 42.544746 -348.7547)
		(end 43.179746 -348.1197)
		(width 0.111252)
		(layer "F.Cu")
		(net "DRV_ACT_6")
	)
	(segment
		(start 46.8884 -349.6437)
		(end 46.8884 -349.879666)
		(width 0.111252)
		(layer "F.Cu")
		(net "DRV_ACT_6")
	)
	(segment
		(start 46.618652 -350.149414)
		(end 45.59046 -350.149414)
		(width 0.111252)
		(layer "F.Cu")
		(net "DRV_ACT_6")
	)
	(segment
		(start 45.59046 -350.149414)
		(end 43.560746 -348.1197)
		(width 0.111252)
		(layer "F.Cu")
		(net "DRV_ACT_6")
	)
	(segment
		(start 46.8884 -349.879666)
		(end 46.618652 -350.149414)
		(width 0.111252)
		(layer "F.Cu")
		(net "DRV_ACT_6")
	)
	(segment
		(start 42.544746 -350.012254)
		(end 42.544746 -348.7547)
		(width 0.111252)
		(layer "F.Cu")
		(net "DRV_ACT_6")
	)
	(segment
		(start 43.179746 -348.1197)
		(end 43.560746 -348.1197)
		(width 0.111252)
		(layer "F.Cu")
		(net "DRV_ACT_6")
	)
	(via
		(at 43.560746 -348.1197)
		(size 0.7112)
		(drill 0.3556)
		(layers "F.Cu" "B.Cu")
		(net "DRV_ACT_6")
	)
	(segment
		(start 229.891082 -246.479568)
		(end 228.804216 -247.566434)
		(width 0.111252)
		(layer "F.Cu")
		(net "DRV_ACT_NET2")
	)
	(segment
		(start 228.804216 -247.566434)
		(end 228.230176 -247.566434)
		(width 0.111252)
		(layer "F.Cu")
		(net "DRV_ACT_NET2")
	)
	(segment
		(start 227.456746 -247.4087)
		(end 227.456746 -244.7417)
		(width 0.111252)
		(layer "F.Cu")
		(net "DRV_ACT_NET2")
	)
	(segment
		(start 228.230176 -247.566434)
		(end 227.61448 -247.566434)
		(width 0.111252)
		(layer "F.Cu")
		(net "DRV_ACT_NET2")
	)
	(segment
		(start 227.61448 -247.566434)
		(end 227.456746 -247.4087)
		(width 0.111252)
		(layer "F.Cu")
		(net "DRV_ACT_NET2")
	)
	(segment
		(start 227.456746 -244.7417)
		(end 227.329746 -244.6147)
		(width 0.111252)
		(layer "F.Cu")
		(net "DRV_ACT_NET2")
	)
	(via
		(at 227.329746 -244.6147)
		(size 0.7112)
		(drill 0.3556)
		(layers "F.Cu" "B.Cu")
		(net "DRV_ACT_NET2")
	)
	(segment
		(start 38.480746 -421.865298)
		(end 38.480746 -425.0817)
		(width 0.508)
		(layer "F.Cu")
		(net "P12V_HDD10")
	)
	(via
		(at 38.480746 -425.0817)
		(size 0.7112)
		(drill 0.3556)
		(layers "F.Cu" "B.Cu")
		(net "P12V_HDD10")
	)
	(via
		(at 34.3916 -412.5214)
		(size 0.7112)
		(drill 0.3556)
		(layers "F.Cu" "B.Cu")
		(net "P12V_HDD10")
	)
	(segment
		(start 41.769792 -453.566276)
		(end 42.12717 -453.566276)
		(width 0.111252)
		(layer "F.Cu")
		(net "DRV_ACT_5")
	)
	(segment
		(start 40.188134 -453.874886)
		(end 41.461182 -453.874886)
		(width 0.111252)
		(layer "F.Cu")
		(net "DRV_ACT_5")
	)
	(segment
		(start 41.461182 -453.874886)
		(end 41.769792 -453.566276)
		(width 0.111252)
		(layer "F.Cu")
		(net "DRV_ACT_5")
	)
	(segment
		(start 42.12717 -453.566276)
		(end 42.417746 -453.2757)
		(width 0.111252)
		(layer "F.Cu")
		(net "DRV_ACT_5")
	)
	(segment
		(start 42.417746 -453.2757)
		(end 42.417746 -450.7357)
		(width 0.111252)
		(layer "F.Cu")
		(net "DRV_ACT_5")
	)
	(via
		(at 42.417746 -450.7357)
		(size 0.7112)
		(drill 0.3556)
		(layers "F.Cu" "B.Cu")
		(net "DRV_ACT_5")
	)
	(segment
		(start 226.567746 -346.3417)
		(end 221.805246 -346.3417)
		(width 0.111252)
		(layer "F.Cu")
		(net "DRV_ACT_NET1")
	)
	(segment
		(start 229.615746 -349.86722)
		(end 229.615746 -347.2307)
		(width 0.111252)
		(layer "F.Cu")
		(net "DRV_ACT_NET1")
	)
	(segment
		(start 228.916484 -350.566482)
		(end 229.615746 -349.86722)
		(width 0.111252)
		(layer "F.Cu")
		(net "DRV_ACT_NET1")
	)
	(segment
		(start 229.615746 -347.2307)
		(end 228.726746 -346.3417)
		(width 0.111252)
		(layer "F.Cu")
		(net "DRV_ACT_NET1")
	)
	(segment
		(start 228.230176 -350.566482)
		(end 228.916484 -350.566482)
		(width 0.111252)
		(layer "F.Cu")
		(net "DRV_ACT_NET1")
	)
	(segment
		(start 228.726746 -346.3417)
		(end 226.567746 -346.3417)
		(width 0.111252)
		(layer "F.Cu")
		(net "DRV_ACT_NET1")
	)
	(via
		(at 226.567746 -346.3417)
		(size 0.7112)
		(drill 0.3556)
		(layers "F.Cu" "B.Cu")
		(net "DRV_ACT_NET1")
	)
	(segment
		(start 224.630742 -41.636696)
		(end 224.916746 -41.9227)
		(width 0.111252)
		(layer "F.Cu")
		(net "DRV_ACT_4")
	)
	(segment
		(start 222.244412 -41.636696)
		(end 224.630742 -41.636696)
		(width 0.111252)
		(layer "F.Cu")
		(net "DRV_ACT_4")
	)
	(segment
		(start 226.766374 -41.563036)
		(end 225.27641 -41.563036)
		(width 0.111252)
		(layer "F.Cu")
		(net "DRV_ACT_4")
	)
	(segment
		(start 226.769676 -41.566338)
		(end 226.766374 -41.563036)
		(width 0.111252)
		(layer "F.Cu")
		(net "DRV_ACT_4")
	)
	(segment
		(start 225.27641 -41.563036)
		(end 224.916746 -41.9227)
		(width 0.111252)
		(layer "F.Cu")
		(net "DRV_ACT_4")
	)
	(via
		(at 224.916746 -41.9227)
		(size 0.7112)
		(drill 0.3556)
		(layers "F.Cu" "B.Cu")
		(net "DRV_ACT_4")
	)
	(segment
		(start 201.802746 -493.0267)
		(end 201.485246 -493.3442)
		(width 0.111252)
		(layer "F.Cu")
		(net "SAS2X28_B_HDD0_FLT")
	)
	(segment
		(start 202.420474 -493.875822)
		(end 202.420474 -493.644428)
		(width 0.111252)
		(layer "F.Cu")
		(net "SAS2X28_B_HDD0_FLT")
	)
	(segment
		(start 201.485246 -493.3442)
		(end 200.928986 -493.3442)
		(width 0.111252)
		(layer "F.Cu")
		(net "SAS2X28_B_HDD0_FLT")
	)
	(segment
		(start 202.420474 -493.644428)
		(end 201.802746 -493.0267)
		(width 0.111252)
		(layer "F.Cu")
		(net "SAS2X28_B_HDD0_FLT")
	)
	(via
		(at 97.916746 -440.7027)
		(size 0.5588)
		(drill 0.3048)
		(layers "F.Cu" "B.Cu")
		(net "SAS2X28_B_HDD0_FLT")
	)
	(via
		(at 201.802746 -493.0267)
		(size 0.5588)
		(drill 0.3048)
		(layers "F.Cu" "B.Cu")
		(net "SAS2X28_B_HDD0_FLT")
	)
	(via
		(at 7.035546 -145.7325)
		(size 0.5588)
		(drill 0.3048)
		(layers "F.Cu" "B.Cu")
		(net "SAS2X28_B_HDD0_FLT")
	)
	(via
		(at 192.150746 -493.4077)
		(size 0.7112)
		(drill 0.3556)
		(layers "F.Cu" "B.Cu")
		(net "SAS2X28_B_HDD0_FLT")
	)
	(segment
		(start 201.802746 -493.0267)
		(end 201.421746 -493.4077)
		(width 0.111252)
		(layer "B.Cu")
		(net "SAS2X28_B_HDD0_FLT")
	)
	(segment
		(start 201.421746 -493.4077)
		(end 192.150746 -493.4077)
		(width 0.111252)
		(layer "B.Cu")
		(net "SAS2X28_B_HDD0_FLT")
	)
	(segment
		(start 2.81305 -145.500344)
		(end 2.811526 -145.49882)
		(width 0.111252)
		(layer "B.Cu")
		(net "SAS2X28_B_HDD0_FLT")
	)
	(segment
		(start 97.916746 -440.7027)
		(end 133.470396 -440.7027)
		(width 0.111252)
		(layer "B.Cu")
		(net "SAS2X28_B_HDD0_FLT")
	)
	(segment
		(start 7.035546 -145.7325)
		(end 6.80339 -145.500344)
		(width 0.111252)
		(layer "B.Cu")
		(net "SAS2X28_B_HDD0_FLT")
	)
	(segment
		(start 186.175396 -493.4077)
		(end 192.150746 -493.4077)
		(width 0.111252)
		(layer "B.Cu")
		(net "SAS2X28_B_HDD0_FLT")
	)
	(segment
		(start 6.80339 -145.500344)
		(end 2.81305 -145.500344)
		(width 0.111252)
		(layer "B.Cu")
		(net "SAS2X28_B_HDD0_FLT")
	)
	(segment
		(start 133.470396 -440.7027)
		(end 186.175396 -493.4077)
		(width 0.111252)
		(layer "B.Cu")
		(net "SAS2X28_B_HDD0_FLT")
	)
	(segment
		(start 8.433054 -133.706362)
		(end 8.486648 -133.652768)
		(width 0.14605)
		(layer "In5.Cu")
		(net "SAS2X28_B_HDD0_FLT")
	)
	(segment
		(start 9.325102 -108.495846)
		(end 20.5867 -97.234248)
		(width 0.14605)
		(layer "In5.Cu")
		(net "SAS2X28_B_HDD0_FLT")
	)
	(segment
		(start 8.500364 -133.086856)
		(end 8.500364 -131.200144)
		(width 0.14605)
		(layer "In5.Cu")
		(net "SAS2X28_B_HDD0_FLT")
	)
	(segment
		(start 7.052564 -140.059918)
		(end 8.14197 -138.970512)
		(width 0.14605)
		(layer "In5.Cu")
		(net "SAS2X28_B_HDD0_FLT")
	)
	(segment
		(start 8.486648 -133.100572)
		(end 8.500364 -133.086856)
		(width 0.14605)
		(layer "In5.Cu")
		(net "SAS2X28_B_HDD0_FLT")
	)
	(segment
		(start 8.14197 -136.457944)
		(end 8.433054 -136.16686)
		(width 0.14605)
		(layer "In5.Cu")
		(net "SAS2X28_B_HDD0_FLT")
	)
	(segment
		(start 20.5867 -97.234248)
		(end 88.590882 -97.234248)
		(width 0.14605)
		(layer "In5.Cu")
		(net "SAS2X28_B_HDD0_FLT")
	)
	(segment
		(start 9.325102 -130.375406)
		(end 9.325102 -108.495846)
		(width 0.14605)
		(layer "In5.Cu")
		(net "SAS2X28_B_HDD0_FLT")
	)
	(segment
		(start 88.590882 -97.234248)
		(end 97.916746 -106.560112)
		(width 0.14605)
		(layer "In5.Cu")
		(net "SAS2X28_B_HDD0_FLT")
	)
	(segment
		(start 8.500364 -131.200144)
		(end 9.325102 -130.375406)
		(width 0.14605)
		(layer "In5.Cu")
		(net "SAS2X28_B_HDD0_FLT")
	)
	(segment
		(start 8.433054 -136.16686)
		(end 8.433054 -133.706362)
		(width 0.14605)
		(layer "In5.Cu")
		(net "SAS2X28_B_HDD0_FLT")
	)
	(segment
		(start 97.916746 -106.560112)
		(end 97.916746 -440.7027)
		(width 0.14605)
		(layer "In5.Cu")
		(net "SAS2X28_B_HDD0_FLT")
	)
	(segment
		(start 8.486648 -133.652768)
		(end 8.486648 -133.100572)
		(width 0.14605)
		(layer "In5.Cu")
		(net "SAS2X28_B_HDD0_FLT")
	)
	(segment
		(start 7.035546 -145.7325)
		(end 7.052564 -145.715482)
		(width 0.14605)
		(layer "In5.Cu")
		(net "SAS2X28_B_HDD0_FLT")
	)
	(segment
		(start 7.052564 -145.715482)
		(end 7.052564 -140.059918)
		(width 0.14605)
		(layer "In5.Cu")
		(net "SAS2X28_B_HDD0_FLT")
	)
	(segment
		(start 8.14197 -138.970512)
		(end 8.14197 -136.457944)
		(width 0.14605)
		(layer "In5.Cu")
		(net "SAS2X28_B_HDD0_FLT")
	)
	(segment
		(start 228.55047 -451.257416)
		(end 228.498146 -451.257416)
		(width 0.111252)
		(layer "F.Cu")
		(net "DRV_ACT_NET0")
	)
	(segment
		(start 229.200456 -453.152256)
		(end 229.822756 -452.529702)
		(width 0.111252)
		(layer "F.Cu")
		(net "DRV_ACT_NET0")
	)
	(segment
		(start 229.822756 -452.529702)
		(end 228.55047 -451.257416)
		(width 0.111252)
		(layer "F.Cu")
		(net "DRV_ACT_NET0")
	)
	(segment
		(start 228.786436 -453.566276)
		(end 229.200456 -453.152256)
		(width 0.111252)
		(layer "F.Cu")
		(net "DRV_ACT_NET0")
	)
	(segment
		(start 228.230176 -453.566276)
		(end 228.786436 -453.566276)
		(width 0.111252)
		(layer "F.Cu")
		(net "DRV_ACT_NET0")
	)
	(via
		(at 228.498146 -451.257416)
		(size 0.7112)
		(drill 0.3556)
		(layers "F.Cu" "B.Cu")
		(net "DRV_ACT_NET0")
	)
	(segment
		(start 23.118318 -35.88004)
		(end 23.138384 -35.897312)
		(width 0.09525)
		(layer "F.Cu")
		(net "SAS2X28_DRIVE_RX_P_A14")
	)
	(segment
		(start 23.273766 -36.316412)
		(end 24.714708 -36.316412)
		(width 0.09525)
		(layer "F.Cu")
		(net "SAS2X28_DRIVE_RX_P_A14")
	)
	(segment
		(start 23.172166 -35.969956)
		(end 23.172166 -36.214812)
		(width 0.09525)
		(layer "F.Cu")
		(net "SAS2X28_DRIVE_RX_P_A14")
	)
	(segment
		(start 21.75002 -35.849814)
		(end 23.0632 -35.849814)
		(width 0.09525)
		(layer "F.Cu")
		(net "SAS2X28_DRIVE_RX_P_A14")
	)
	(segment
		(start 23.0632 -35.849814)
		(end 23.073106 -35.853624)
		(width 0.09525)
		(layer "F.Cu")
		(net "SAS2X28_DRIVE_RX_P_A14")
	)
	(arc
		(start 24.714708 -36.316412)
		(mid 25.188566 -36.222156)
		(end 25.590246 -35.9537)
		(width 0.09525)
		(layer "F.Cu")
		(net "SAS2X28_DRIVE_RX_P_A14")
	)
	(arc
		(start 23.172166 -36.214812)
		(mid 23.190993 -36.273729)
		(end 23.240492 -36.310824)
		(width 0.09525)
		(layer "F.Cu")
		(net "SAS2X28_DRIVE_RX_P_A14")
	)
	(arc
		(start 23.138384 -35.897312)
		(mid 23.163308 -35.929899)
		(end 23.172166 -35.969956)
		(width 0.09525)
		(layer "F.Cu")
		(net "SAS2X28_DRIVE_RX_P_A14")
	)
	(arc
		(start 23.240492 -36.310824)
		(mid 23.256896 -36.315006)
		(end 23.273766 -36.316412)
		(width 0.09525)
		(layer "F.Cu")
		(net "SAS2X28_DRIVE_RX_P_A14")
	)
	(arc
		(start 23.073106 -35.853624)
		(mid 23.09687 -35.864849)
		(end 23.118318 -35.88004)
		(width 0.09525)
		(layer "F.Cu")
		(net "SAS2X28_DRIVE_RX_P_A14")
	)
	(via
		(at 30.098746 -430.2887)
		(size 0.5588)
		(drill 0.3048)
		(layers "F.Cu" "B.Cu")
		(net "P5V_HDD10")
	)
	(via
		(at 30.098746 -431.2285)
		(size 0.7112)
		(drill 0.3556)
		(layers "F.Cu" "B.Cu")
		(net "P5V_HDD10")
	)
	(via
		(at 36.449 -432.5366)
		(size 0.7112)
		(drill 0.3556)
		(layers "F.Cu" "B.Cu")
		(net "P5V_HDD10")
	)
	(segment
		(start 30.098746 -430.2887)
		(end 30.098746 -431.2285)
		(width 0.508)
		(layer "B.Cu")
		(net "P5V_HDD10")
	)
	(segment
		(start 226.769676 -144.566386)
		(end 225.58756 -144.566386)
		(width 0.111252)
		(layer "F.Cu")
		(net "DRV_ACT_3")
	)
	(segment
		(start 225.234246 -144.4752)
		(end 224.916746 -144.1577)
		(width 0.111252)
		(layer "F.Cu")
		(net "DRV_ACT_3")
	)
	(segment
		(start 225.58756 -144.566386)
		(end 225.234246 -144.9197)
		(width 0.111252)
		(layer "F.Cu")
		(net "DRV_ACT_3")
	)
	(segment
		(start 225.234246 -144.9197)
		(end 225.234246 -144.4752)
		(width 0.111252)
		(layer "F.Cu")
		(net "DRV_ACT_3")
	)
	(segment
		(start 222.757746 -144.1577)
		(end 222.708724 -144.206722)
		(width 0.111252)
		(layer "F.Cu")
		(net "DRV_ACT_3")
	)
	(segment
		(start 224.916746 -144.1577)
		(end 222.757746 -144.1577)
		(width 0.111252)
		(layer "F.Cu")
		(net "DRV_ACT_3")
	)
	(segment
		(start 222.708724 -144.206722)
		(end 222.703898 -144.206722)
		(width 0.111252)
		(layer "F.Cu")
		(net "DRV_ACT_3")
	)
	(via
		(at 222.703898 -144.206722)
		(size 0.7112)
		(drill 0.3556)
		(layers "F.Cu" "B.Cu")
		(net "DRV_ACT_3")
	)
	(segment
		(start 200.405746 -495.0587)
		(end 200.278746 -494.9317)
		(width 0.111252)
		(layer "F.Cu")
		(net "SAS2X28_A_HDD0_FLT")
	)
	(segment
		(start 200.278746 -494.9317)
		(end 200.278746 -493.3442)
		(width 0.111252)
		(layer "F.Cu")
		(net "SAS2X28_A_HDD0_FLT")
	)
	(segment
		(start 202.420474 -494.891822)
		(end 201.461624 -494.891822)
		(width 0.111252)
		(layer "F.Cu")
		(net "SAS2X28_A_HDD0_FLT")
	)
	(segment
		(start 3.19405 -392.500358)
		(end 5.593842 -392.500358)
		(width 0.111252)
		(layer "F.Cu")
		(net "SAS2X28_A_HDD0_FLT")
	)
	(segment
		(start 7.43204 -392.305794)
		(end 7.670546 -392.5443)
		(width 0.111252)
		(layer "F.Cu")
		(net "SAS2X28_A_HDD0_FLT")
	)
	(segment
		(start 3.192526 -392.498834)
		(end 3.19405 -392.500358)
		(width 0.111252)
		(layer "F.Cu")
		(net "SAS2X28_A_HDD0_FLT")
	)
	(segment
		(start 5.593842 -392.500358)
		(end 5.788406 -392.305794)
		(width 0.111252)
		(layer "F.Cu")
		(net "SAS2X28_A_HDD0_FLT")
	)
	(segment
		(start 201.294746 -495.0587)
		(end 200.405746 -495.0587)
		(width 0.111252)
		(layer "F.Cu")
		(net "SAS2X28_A_HDD0_FLT")
	)
	(segment
		(start 5.788406 -392.305794)
		(end 7.43204 -392.305794)
		(width 0.111252)
		(layer "F.Cu")
		(net "SAS2X28_A_HDD0_FLT")
	)
	(segment
		(start 201.461624 -494.891822)
		(end 201.294746 -495.0587)
		(width 0.111252)
		(layer "F.Cu")
		(net "SAS2X28_A_HDD0_FLT")
	)
	(via
		(at 200.874376 -495.89944)
		(size 0.7112)
		(drill 0.3556)
		(layers "F.Cu" "B.Cu")
		(net "SAS2X28_A_HDD0_FLT")
	)
	(via
		(at 201.294746 -495.0587)
		(size 0.5588)
		(drill 0.3048)
		(layers "F.Cu" "B.Cu")
		(net "SAS2X28_A_HDD0_FLT")
	)
	(via
		(at 7.670546 -392.5443)
		(size 0.5588)
		(drill 0.3048)
		(layers "F.Cu" "B.Cu")
		(net "SAS2X28_A_HDD0_FLT")
	)
	(segment
		(start 201.294746 -495.47907)
		(end 200.874376 -495.89944)
		(width 0.111252)
		(layer "B.Cu")
		(net "SAS2X28_A_HDD0_FLT")
	)
	(segment
		(start 201.294746 -495.0587)
		(end 201.294746 -495.47907)
		(width 0.111252)
		(layer "B.Cu")
		(net "SAS2X28_A_HDD0_FLT")
	)
	(segment
		(start 10.241788 -430.148492)
		(end 10.241788 -409.82392)
		(width 0.14605)
		(layer "In5.Cu")
		(net "SAS2X28_A_HDD0_FLT")
	)
	(segment
		(start 11.287252 -398.368266)
		(end 10.277348 -397.358362)
		(width 0.14605)
		(layer "In5.Cu")
		(net "SAS2X28_A_HDD0_FLT")
	)
	(segment
		(start 10.238994 -406.31237)
		(end 10.794492 -405.756872)
		(width 0.14605)
		(layer "In5.Cu")
		(net "SAS2X28_A_HDD0_FLT")
	)
	(segment
		(start 7.670546 -395.693646)
		(end 7.670546 -392.5443)
		(width 0.14605)
		(layer "In5.Cu")
		(net "SAS2X28_A_HDD0_FLT")
	)
	(segment
		(start 8.1026 -466.00491)
		(end 8.1026 -462.231994)
		(width 0.14605)
		(layer "In5.Cu")
		(net "SAS2X28_A_HDD0_FLT")
	)
	(segment
		(start 7.73684 -458.182218)
		(end 6.07695 -456.522328)
		(width 0.14605)
		(layer "In5.Cu")
		(net "SAS2X28_A_HDD0_FLT")
	)
	(segment
		(start 8.1026 -462.231994)
		(end 7.73684 -461.866234)
		(width 0.14605)
		(layer "In5.Cu")
		(net "SAS2X28_A_HDD0_FLT")
	)
	(segment
		(start 34.888678 -474.51899)
		(end 32.596836 -472.227148)
		(width 0.14605)
		(layer "In5.Cu")
		(net "SAS2X28_A_HDD0_FLT")
	)
	(segment
		(start 13.466826 -472.046554)
		(end 9.697212 -468.27694)
		(width 0.14605)
		(layer "In5.Cu")
		(net "SAS2X28_A_HDD0_FLT")
	)
	(segment
		(start 36.255452 -474.545152)
		(end 34.92754 -474.545152)
		(width 0.14605)
		(layer "In5.Cu")
		(net "SAS2X28_A_HDD0_FLT")
	)
	(segment
		(start 10.238994 -409.821126)
		(end 10.238994 -406.31237)
		(width 0.14605)
		(layer "In5.Cu")
		(net "SAS2X28_A_HDD0_FLT")
	)
	(segment
		(start 13.647674 -472.227148)
		(end 13.46708 -472.046554)
		(width 0.14605)
		(layer "In5.Cu")
		(net "SAS2X28_A_HDD0_FLT")
	)
	(segment
		(start 197.484746 -495.0587)
		(end 176.024794 -473.598748)
		(width 0.14605)
		(layer "In5.Cu")
		(net "SAS2X28_A_HDD0_FLT")
	)
	(segment
		(start 201.294746 -495.0587)
		(end 197.484746 -495.0587)
		(width 0.14605)
		(layer "In5.Cu")
		(net "SAS2X28_A_HDD0_FLT")
	)
	(segment
		(start 37.201856 -473.598748)
		(end 36.255452 -474.545152)
		(width 0.14605)
		(layer "In5.Cu")
		(net "SAS2X28_A_HDD0_FLT")
	)
	(segment
		(start 176.024794 -473.598748)
		(end 37.201856 -473.598748)
		(width 0.14605)
		(layer "In5.Cu")
		(net "SAS2X28_A_HDD0_FLT")
	)
	(segment
		(start 6.07695 -443.736984)
		(end 5.229098 -442.889132)
		(width 0.14605)
		(layer "In5.Cu")
		(net "SAS2X28_A_HDD0_FLT")
	)
	(segment
		(start 6.07695 -456.522328)
		(end 6.07695 -443.736984)
		(width 0.14605)
		(layer "In5.Cu")
		(net "SAS2X28_A_HDD0_FLT")
	)
	(segment
		(start 5.229098 -442.889132)
		(end 5.229098 -435.161182)
		(width 0.14605)
		(layer "In5.Cu")
		(net "SAS2X28_A_HDD0_FLT")
	)
	(segment
		(start 32.596836 -472.227148)
		(end 13.647674 -472.227148)
		(width 0.14605)
		(layer "In5.Cu")
		(net "SAS2X28_A_HDD0_FLT")
	)
	(segment
		(start 10.241788 -409.82392)
		(end 10.238994 -409.821126)
		(width 0.14605)
		(layer "In5.Cu")
		(net "SAS2X28_A_HDD0_FLT")
	)
	(segment
		(start 5.229098 -435.161182)
		(end 10.241788 -430.148492)
		(width 0.14605)
		(layer "In5.Cu")
		(net "SAS2X28_A_HDD0_FLT")
	)
	(segment
		(start 10.794492 -400.734276)
		(end 11.287252 -400.241516)
		(width 0.14605)
		(layer "In5.Cu")
		(net "SAS2X28_A_HDD0_FLT")
	)
	(segment
		(start 7.73684 -461.866234)
		(end 7.73684 -458.182218)
		(width 0.14605)
		(layer "In5.Cu")
		(net "SAS2X28_A_HDD0_FLT")
	)
	(segment
		(start 11.287252 -400.241516)
		(end 11.287252 -398.368266)
		(width 0.14605)
		(layer "In5.Cu")
		(net "SAS2X28_A_HDD0_FLT")
	)
	(segment
		(start 9.335262 -397.358362)
		(end 7.670546 -395.693646)
		(width 0.14605)
		(layer "In5.Cu")
		(net "SAS2X28_A_HDD0_FLT")
	)
	(segment
		(start 13.46708 -472.046554)
		(end 13.466826 -472.046554)
		(width 0.14605)
		(layer "In5.Cu")
		(net "SAS2X28_A_HDD0_FLT")
	)
	(segment
		(start 34.92754 -474.545152)
		(end 34.888678 -474.51899)
		(width 0.14605)
		(layer "In5.Cu")
		(net "SAS2X28_A_HDD0_FLT")
	)
	(segment
		(start 9.697212 -468.27694)
		(end 9.697212 -467.599522)
		(width 0.14605)
		(layer "In5.Cu")
		(net "SAS2X28_A_HDD0_FLT")
	)
	(segment
		(start 10.794492 -405.756872)
		(end 10.794492 -400.734276)
		(width 0.14605)
		(layer "In5.Cu")
		(net "SAS2X28_A_HDD0_FLT")
	)
	(segment
		(start 9.697212 -467.599522)
		(end 8.1026 -466.00491)
		(width 0.14605)
		(layer "In5.Cu")
		(net "SAS2X28_A_HDD0_FLT")
	)
	(segment
		(start 10.277348 -397.358362)
		(end 9.335262 -397.358362)
		(width 0.14605)
		(layer "In5.Cu")
		(net "SAS2X28_A_HDD0_FLT")
	)
	(segment
		(start 23.273766 -139.31646)
		(end 24.962104 -139.31646)
		(width 0.09525)
		(layer "F.Cu")
		(net "SAS2X28_DRIVE_RX_P_A13")
	)
	(segment
		(start 23.106634 -138.877802)
		(end 23.138638 -138.908028)
		(width 0.09525)
		(layer "F.Cu")
		(net "SAS2X28_DRIVE_RX_P_A13")
	)
	(segment
		(start 21.75002 -138.849862)
		(end 23.03653 -138.849862)
		(width 0.09525)
		(layer "F.Cu")
		(net "SAS2X28_DRIVE_RX_P_A13")
	)
	(segment
		(start 23.172166 -138.980672)
		(end 23.172166 -139.21486)
		(width 0.09525)
		(layer "F.Cu")
		(net "SAS2X28_DRIVE_RX_P_A13")
	)
	(arc
		(start 23.138638 -138.908028)
		(mid 23.163369 -138.940671)
		(end 23.172166 -138.980672)
		(width 0.09525)
		(layer "F.Cu")
		(net "SAS2X28_DRIVE_RX_P_A13")
	)
	(arc
		(start 24.962104 -139.31646)
		(mid 25.294631 -139.250316)
		(end 25.57653 -139.061952)
		(width 0.09525)
		(layer "F.Cu")
		(net "SAS2X28_DRIVE_RX_P_A13")
	)
	(arc
		(start 23.172166 -139.21486)
		(mid 23.190993 -139.273777)
		(end 23.240492 -139.310872)
		(width 0.09525)
		(layer "F.Cu")
		(net "SAS2X28_DRIVE_RX_P_A13")
	)
	(arc
		(start 23.240492 -139.310872)
		(mid 23.256896 -139.315054)
		(end 23.273766 -139.31646)
		(width 0.09525)
		(layer "F.Cu")
		(net "SAS2X28_DRIVE_RX_P_A13")
	)
	(arc
		(start 23.03653 -138.849862)
		(mid 23.07426 -138.857108)
		(end 23.106634 -138.877802)
		(width 0.09525)
		(layer "F.Cu")
		(net "SAS2X28_DRIVE_RX_P_A13")
	)
	(segment
		(start 226.459542 -247.876568)
		(end 226.769676 -247.566434)
		(width 0.111252)
		(layer "F.Cu")
		(net "DRV_ACT_2")
	)
	(segment
		(start 225.192082 -247.876568)
		(end 226.459542 -247.876568)
		(width 0.111252)
		(layer "F.Cu")
		(net "DRV_ACT_2")
	)
	(segment
		(start 224.789746 -249.1867)
		(end 225.192082 -248.784364)
		(width 0.111252)
		(layer "F.Cu")
		(net "DRV_ACT_2")
	)
	(segment
		(start 223.900746 -249.1867)
		(end 224.789746 -249.1867)
		(width 0.111252)
		(layer "F.Cu")
		(net "DRV_ACT_2")
	)
	(segment
		(start 225.192082 -248.784364)
		(end 225.192082 -247.876568)
		(width 0.111252)
		(layer "F.Cu")
		(net "DRV_ACT_2")
	)
	(segment
		(start 222.884746 -248.1707)
		(end 223.900746 -249.1867)
		(width 0.111252)
		(layer "F.Cu")
		(net "DRV_ACT_2")
	)
	(via
		(at 222.884746 -248.1707)
		(size 0.7112)
		(drill 0.3556)
		(layers "F.Cu" "B.Cu")
		(net "DRV_ACT_2")
	)
	(segment
		(start 22.987 -241.859054)
		(end 22.910038 -241.850926)
		(width 0.09525)
		(layer "F.Cu")
		(net "SAS2X28_DRIVE_RX_P_A12")
	)
	(segment
		(start 22.899624 -241.850418)
		(end 22.698964 -241.850418)
		(width 0.09525)
		(layer "F.Cu")
		(net "SAS2X28_DRIVE_RX_P_A12")
	)
	(segment
		(start 25.488646 -242.316508)
		(end 23.273766 -242.316508)
		(width 0.09525)
		(layer "F.Cu")
		(net "SAS2X28_DRIVE_RX_P_A12")
	)
	(segment
		(start 22.698456 -241.84991)
		(end 21.75002 -241.84991)
		(width 0.09525)
		(layer "F.Cu")
		(net "SAS2X28_DRIVE_RX_P_A12")
	)
	(segment
		(start 22.698964 -241.850418)
		(end 22.698456 -241.84991)
		(width 0.09525)
		(layer "F.Cu")
		(net "SAS2X28_DRIVE_RX_P_A12")
	)
	(segment
		(start 23.172166 -242.214908)
		(end 23.172166 -242.023646)
		(width 0.09525)
		(layer "F.Cu")
		(net "SAS2X28_DRIVE_RX_P_A12")
	)
	(segment
		(start 23.09876 -241.901726)
		(end 23.086822 -241.895376)
		(width 0.09525)
		(layer "F.Cu")
		(net "SAS2X28_DRIVE_RX_P_A12")
	)
	(arc
		(start 23.172166 -242.023646)
		(mid 23.152396 -241.952494)
		(end 23.09876 -241.901726)
		(width 0.09525)
		(layer "F.Cu")
		(net "SAS2X28_DRIVE_RX_P_A12")
	)
	(arc
		(start 23.086822 -241.895376)
		(mid 23.038172 -241.87375)
		(end 22.987 -241.859054)
		(width 0.09525)
		(layer "F.Cu")
		(net "SAS2X28_DRIVE_RX_P_A12")
	)
	(arc
		(start 26.10993 -242.059206)
		(mid 25.824882 -242.249669)
		(end 25.488646 -242.316508)
		(width 0.09525)
		(layer "F.Cu")
		(net "SAS2X28_DRIVE_RX_P_A12")
	)
	(arc
		(start 23.273766 -242.316508)
		(mid 23.201924 -242.28675)
		(end 23.172166 -242.214908)
		(width 0.09525)
		(layer "F.Cu")
		(net "SAS2X28_DRIVE_RX_P_A12")
	)
	(arc
		(start 22.910038 -241.850926)
		(mid 22.904838 -241.85053)
		(end 22.899624 -241.850418)
		(width 0.09525)
		(layer "F.Cu")
		(net "SAS2X28_DRIVE_RX_P_A12")
	)
	(segment
		(start 226.769676 -350.566482)
		(end 223.523048 -350.566482)
		(width 0.111252)
		(layer "F.Cu")
		(net "DRV_ACT_1")
	)
	(segment
		(start 221.983554 -350.56318)
		(end 223.519746 -350.56318)
		(width 0.111252)
		(layer "F.Cu")
		(net "DRV_ACT_1")
	)
	(segment
		(start 221.888558 -350.468184)
		(end 221.983554 -350.56318)
		(width 0.111252)
		(layer "F.Cu")
		(net "DRV_ACT_1")
	)
	(segment
		(start 223.523048 -350.566482)
		(end 223.519746 -350.56318)
		(width 0.111252)
		(layer "F.Cu")
		(net "DRV_ACT_1")
	)
	(via
		(at 223.519746 -350.56318)
		(size 0.7112)
		(drill 0.3556)
		(layers "F.Cu" "B.Cu")
		(net "DRV_ACT_1")
	)
	(segment
		(start 23.37816 -345.316556)
		(end 25.97531 -345.316556)
		(width 0.09525)
		(layer "F.Cu")
		(net "SAS2X28_DRIVE_RX_P_A11")
	)
	(segment
		(start 21.75002 -344.849958)
		(end 23.050754 -344.849958)
		(width 0.09525)
		(layer "F.Cu")
		(net "SAS2X28_DRIVE_RX_P_A11")
	)
	(segment
		(start 23.200106 -344.99931)
		(end 23.200106 -345.148662)
		(width 0.09525)
		(layer "F.Cu")
		(net "SAS2X28_DRIVE_RX_P_A11")
	)
	(segment
		(start 26.300938 -345.181682)
		(end 26.435812 -345.046808)
		(width 0.09525)
		(layer "F.Cu")
		(net "SAS2X28_DRIVE_RX_P_A11")
	)
	(arc
		(start 23.200106 -345.148662)
		(mid 23.249207 -345.267201)
		(end 23.367746 -345.316302)
		(width 0.09525)
		(layer "F.Cu")
		(net "SAS2X28_DRIVE_RX_P_A11")
	)
	(arc
		(start 23.050754 -344.849958)
		(mid 23.156362 -344.893702)
		(end 23.200106 -344.99931)
		(width 0.09525)
		(layer "F.Cu")
		(net "SAS2X28_DRIVE_RX_P_A11")
	)
	(arc
		(start 23.367746 -345.316302)
		(mid 23.372951 -345.316513)
		(end 23.37816 -345.316556)
		(width 0.09525)
		(layer "F.Cu")
		(net "SAS2X28_DRIVE_RX_P_A11")
	)
	(arc
		(start 25.97531 -345.316556)
		(mid 26.151536 -345.281502)
		(end 26.300938 -345.181682)
		(width 0.09525)
		(layer "F.Cu")
		(net "SAS2X28_DRIVE_RX_P_A11")
	)
	(segment
		(start 227.03917 -453.566276)
		(end 227.457 -453.148446)
		(width 0.111252)
		(layer "F.Cu")
		(net "DRV_ACT_0")
	)
	(segment
		(start 225.1329 -453.7202)
		(end 225.286824 -453.566276)
		(width 0.111252)
		(layer "F.Cu")
		(net "DRV_ACT_0")
	)
	(segment
		(start 225.286824 -453.566276)
		(end 226.769676 -453.566276)
		(width 0.111252)
		(layer "F.Cu")
		(net "DRV_ACT_0")
	)
	(segment
		(start 227.457 -453.148446)
		(end 227.457 -451.751954)
		(width 0.111252)
		(layer "F.Cu")
		(net "DRV_ACT_0")
	)
	(segment
		(start 227.457 -451.751954)
		(end 226.821746 -451.1167)
		(width 0.111252)
		(layer "F.Cu")
		(net "DRV_ACT_0")
	)
	(segment
		(start 226.769676 -453.566276)
		(end 227.03917 -453.566276)
		(width 0.111252)
		(layer "F.Cu")
		(net "DRV_ACT_0")
	)
	(via
		(at 226.821746 -451.1167)
		(size 0.7112)
		(drill 0.3556)
		(layers "F.Cu" "B.Cu")
		(net "DRV_ACT_0")
	)
	(segment
		(start 19.213068 -54.229)
		(end 19.748246 -54.229)
		(width 0.111252)
		(layer "F.Cu")
		(net "FLT_HDD14")
	)
	(segment
		(start 19.748246 -54.229)
		(end 19.748246 -52.9717)
		(width 0.111252)
		(layer "F.Cu")
		(net "FLT_HDD14")
	)
	(segment
		(start 18.230342 -53.246274)
		(end 19.213068 -54.229)
		(width 0.111252)
		(layer "F.Cu")
		(net "FLT_HDD14")
	)
	(via
		(at 19.748246 -54.229)
		(size 0.7112)
		(drill 0.3556)
		(layers "F.Cu" "B.Cu")
		(net "FLT_HDD14")
	)
	(segment
		(start 23.139654 -447.964306)
		(end 23.156418 -448.004946)
		(width 0.09525)
		(layer "F.Cu")
		(net "SAS2X28_DRIVE_RX_P_A10")
	)
	(segment
		(start 21.75002 -447.850006)
		(end 22.9616 -447.850006)
		(width 0.09525)
		(layer "F.Cu")
		(net "SAS2X28_DRIVE_RX_P_A10")
	)
	(segment
		(start 23.273766 -448.316604)
		(end 25.753822 -448.316604)
		(width 0.09525)
		(layer "F.Cu")
		(net "SAS2X28_DRIVE_RX_P_A10")
	)
	(segment
		(start 23.172166 -448.083432)
		(end 23.172166 -448.215004)
		(width 0.09525)
		(layer "F.Cu")
		(net "SAS2X28_DRIVE_RX_P_A10")
	)
	(arc
		(start 25.753822 -448.316604)
		(mid 26.077698 -448.252181)
		(end 26.352246 -448.0687)
		(width 0.09525)
		(layer "F.Cu")
		(net "SAS2X28_DRIVE_RX_P_A10")
	)
	(arc
		(start 23.172166 -448.215004)
		(mid 23.19092 -448.273656)
		(end 23.240238 -448.310508)
		(width 0.09525)
		(layer "F.Cu")
		(net "SAS2X28_DRIVE_RX_P_A10")
	)
	(arc
		(start 23.156418 -448.004946)
		(mid 23.16818 -448.04341)
		(end 23.172166 -448.083432)
		(width 0.09525)
		(layer "F.Cu")
		(net "SAS2X28_DRIVE_RX_P_A10")
	)
	(arc
		(start 22.9616 -447.850006)
		(mid 23.039944 -447.86559)
		(end 23.10638 -447.90995)
		(width 0.09525)
		(layer "F.Cu")
		(net "SAS2X28_DRIVE_RX_P_A10")
	)
	(arc
		(start 23.10638 -447.90995)
		(mid 23.125145 -447.935825)
		(end 23.139654 -447.964306)
		(width 0.09525)
		(layer "F.Cu")
		(net "SAS2X28_DRIVE_RX_P_A10")
	)
	(arc
		(start 23.257002 -448.31508)
		(mid 23.25789 -448.315211)
		(end 23.25878 -448.315334)
		(width 0.09525)
		(layer "F.Cu")
		(net "SAS2X28_DRIVE_RX_P_A10")
	)
	(arc
		(start 23.240238 -448.310508)
		(mid 23.241504 -448.311026)
		(end 23.242778 -448.311524)
		(width 0.09525)
		(layer "F.Cu")
		(net "SAS2X28_DRIVE_RX_P_A10")
	)
	(arc
		(start 23.242778 -448.311524)
		(mid 23.249824 -448.313568)
		(end 23.257002 -448.31508)
		(width 0.09525)
		(layer "F.Cu")
		(net "SAS2X28_DRIVE_RX_P_A10")
	)
	(arc
		(start 23.25878 -448.315334)
		(mid 23.26625 -448.316243)
		(end 23.273766 -448.316604)
		(width 0.09525)
		(layer "F.Cu")
		(net "SAS2X28_DRIVE_RX_P_A10")
	)
	(segment
		(start 19.670776 -156.246322)
		(end 18.230342 -156.246322)
		(width 0.111252)
		(layer "F.Cu")
		(net "FLT_HDD13")
	)
	(segment
		(start 18.2372 -158.1658)
		(end 18.230342 -158.158942)
		(width 0.111252)
		(layer "F.Cu")
		(net "FLT_HDD13")
	)
	(segment
		(start 18.230342 -158.158942)
		(end 18.230342 -156.246322)
		(width 0.111252)
		(layer "F.Cu")
		(net "FLT_HDD13")
	)
	(segment
		(start 19.748754 -156.3243)
		(end 19.670776 -156.246322)
		(width 0.111252)
		(layer "F.Cu")
		(net "FLT_HDD13")
	)
	(via
		(at 18.2372 -158.1658)
		(size 0.7112)
		(drill 0.3556)
		(layers "F.Cu" "B.Cu")
		(net "FLT_HDD13")
	)
	(segment
		(start 36.72586 -57.676796)
		(end 34.06267 -57.676796)
		(width 0.09525)
		(layer "F.Cu")
		(net "SAS2X28_DRIVE_RX_P_A9")
	)
	(segment
		(start 38.250114 -58.149998)
		(end 37.013388 -58.149998)
		(width 0.09525)
		(layer "F.Cu")
		(net "SAS2X28_DRIVE_RX_P_A9")
	)
	(segment
		(start 36.82746 -57.964324)
		(end 36.82746 -57.778396)
		(width 0.09525)
		(layer "F.Cu")
		(net "SAS2X28_DRIVE_RX_P_A9")
	)
	(arc
		(start 36.82746 -57.778396)
		(mid 36.797702 -57.706554)
		(end 36.72586 -57.676796)
		(width 0.09525)
		(layer "F.Cu")
		(net "SAS2X28_DRIVE_RX_P_A9")
	)
	(arc
		(start 34.06267 -57.676796)
		(mid 33.738794 -57.741219)
		(end 33.464246 -57.9247)
		(width 0.09525)
		(layer "F.Cu")
		(net "SAS2X28_DRIVE_RX_P_A9")
	)
	(arc
		(start 37.013388 -58.149998)
		(mid 36.881932 -58.095705)
		(end 36.82746 -57.964324)
		(width 0.09525)
		(layer "F.Cu")
		(net "SAS2X28_DRIVE_RX_P_A9")
	)
	(segment
		(start 20.2184 -257.9116)
		(end 19.2786 -258.8514)
		(width 0.111252)
		(layer "F.Cu")
		(net "FLT_HDD12")
	)
	(segment
		(start 20.4089 -257.9116)
		(end 20.2184 -257.9116)
		(width 0.111252)
		(layer "F.Cu")
		(net "FLT_HDD12")
	)
	(segment
		(start 18.88363 -259.24637)
		(end 19.2786 -258.8514)
		(width 0.111252)
		(layer "F.Cu")
		(net "FLT_HDD12")
	)
	(segment
		(start 18.230342 -259.24637)
		(end 18.88363 -259.24637)
		(width 0.111252)
		(layer "F.Cu")
		(net "FLT_HDD12")
	)
	(segment
		(start 21.0185 -257.302)
		(end 20.4089 -257.9116)
		(width 0.111252)
		(layer "F.Cu")
		(net "FLT_HDD12")
	)
	(via
		(at 20.2184 -258.8514)
		(size 0.7112)
		(drill 0.3556)
		(layers "F.Cu" "B.Cu")
		(net "FLT_HDD12")
	)
	(via
		(at 19.2786 -258.8514)
		(size 0.5588)
		(drill 0.3048)
		(layers "F.Cu" "B.Cu")
		(net "FLT_HDD12")
	)
	(segment
		(start 20.2184 -258.8514)
		(end 19.2786 -258.8514)
		(width 0.111252)
		(layer "B.Cu")
		(net "FLT_HDD12")
	)
	(segment
		(start 36.82746 -160.86582)
		(end 36.82746 -160.778444)
		(width 0.09525)
		(layer "F.Cu")
		(net "SAS2X28_DRIVE_RX_P_A8")
	)
	(segment
		(start 36.72586 -160.676844)
		(end 34.938208 -160.676844)
		(width 0.09525)
		(layer "F.Cu")
		(net "SAS2X28_DRIVE_RX_P_A8")
	)
	(segment
		(start 38.250114 -161.150046)
		(end 37.117528 -161.150046)
		(width 0.09525)
		(layer "F.Cu")
		(net "SAS2X28_DRIVE_RX_P_A8")
	)
	(segment
		(start 37.032946 -161.133282)
		(end 36.997894 -161.118804)
		(width 0.09525)
		(layer "F.Cu")
		(net "SAS2X28_DRIVE_RX_P_A8")
	)
	(segment
		(start 36.866068 -160.986724)
		(end 36.838128 -160.918906)
		(width 0.09525)
		(layer "F.Cu")
		(net "SAS2X28_DRIVE_RX_P_A8")
	)
	(arc
		(start 36.82746 -160.778444)
		(mid 36.805143 -160.714819)
		(end 36.747958 -160.67913)
		(width 0.09525)
		(layer "F.Cu")
		(net "SAS2X28_DRIVE_RX_P_A8")
	)
	(arc
		(start 36.997894 -161.118804)
		(mid 36.918875 -161.065851)
		(end 36.866068 -160.986724)
		(width 0.09525)
		(layer "F.Cu")
		(net "SAS2X28_DRIVE_RX_P_A8")
	)
	(arc
		(start 36.747958 -160.67913)
		(mid 36.746564 -160.678738)
		(end 36.745164 -160.678368)
		(width 0.09525)
		(layer "F.Cu")
		(net "SAS2X28_DRIVE_RX_P_A8")
	)
	(arc
		(start 36.745164 -160.678368)
		(mid 36.735548 -160.677156)
		(end 36.72586 -160.676844)
		(width 0.09525)
		(layer "F.Cu")
		(net "SAS2X28_DRIVE_RX_P_A8")
	)
	(arc
		(start 34.938208 -160.676844)
		(mid 34.613263 -160.74148)
		(end 34.337752 -160.92551)
		(width 0.09525)
		(layer "F.Cu")
		(net "SAS2X28_DRIVE_RX_P_A8")
	)
	(arc
		(start 36.838128 -160.918906)
		(mid 36.830193 -160.892887)
		(end 36.82746 -160.86582)
		(width 0.09525)
		(layer "F.Cu")
		(net "SAS2X28_DRIVE_RX_P_A8")
	)
	(arc
		(start 37.117528 -161.150046)
		(mid 37.074408 -161.145844)
		(end 37.032946 -161.133282)
		(width 0.09525)
		(layer "F.Cu")
		(net "SAS2X28_DRIVE_RX_P_A8")
	)
	(segment
		(start 33.4645 -346.71)
		(end 33.43783 -346.71)
		(width 0.111252)
		(layer "F.Cu")
		(net "FLT_HDD11")
	)
	(segment
		(start 18.230342 -362.246418)
		(end 19.001994 -362.246418)
		(width 0.111252)
		(layer "F.Cu")
		(net "FLT_HDD11")
	)
	(segment
		(start 31.1912 -350.057212)
		(end 31.1912 -348.6658)
		(width 0.111252)
		(layer "F.Cu")
		(net "FLT_HDD11")
	)
	(segment
		(start 31.65983 -348.488)
		(end 31.369 -348.488)
		(width 0.111252)
		(layer "F.Cu")
		(net "FLT_HDD11")
	)
	(segment
		(start 31.1912 -348.6658)
		(end 31.369 -348.488)
		(width 0.111252)
		(layer "F.Cu")
		(net "FLT_HDD11")
	)
	(segment
		(start 19.001994 -362.246418)
		(end 31.1912 -350.057212)
		(width 0.111252)
		(layer "F.Cu")
		(net "FLT_HDD11")
	)
	(segment
		(start 33.43783 -346.71)
		(end 31.65983 -348.488)
		(width 0.111252)
		(layer "F.Cu")
		(net "FLT_HDD11")
	)
	(via
		(at 31.369 -348.488)
		(size 0.7112)
		(drill 0.3556)
		(layers "F.Cu" "B.Cu")
		(net "FLT_HDD11")
	)
	(segment
		(start 34.112962 -263.695434)
		(end 34.052002 -263.714992)
		(width 0.09525)
		(layer "F.Cu")
		(net "SAS2X28_DRIVE_RX_P_A7")
	)
	(segment
		(start 36.82746 -264.028428)
		(end 36.82746 -263.778492)
		(width 0.09525)
		(layer "F.Cu")
		(net "SAS2X28_DRIVE_RX_P_A7")
	)
	(segment
		(start 34.416238 -263.675368)
		(end 34.305748 -263.675368)
		(width 0.09525)
		(layer "F.Cu")
		(net "SAS2X28_DRIVE_RX_P_A7")
	)
	(segment
		(start 36.72586 -263.676892)
		(end 34.483548 -263.676892)
		(width 0.09525)
		(layer "F.Cu")
		(net "SAS2X28_DRIVE_RX_P_A7")
	)
	(segment
		(start 38.250114 -264.150094)
		(end 36.947348 -264.150094)
		(width 0.09525)
		(layer "F.Cu")
		(net "SAS2X28_DRIVE_RX_P_A7")
	)
	(segment
		(start 36.883594 -264.123932)
		(end 36.85667 -264.097262)
		(width 0.09525)
		(layer "F.Cu")
		(net "SAS2X28_DRIVE_RX_P_A7")
	)
	(arc
		(start 36.85667 -264.097262)
		(mid 36.835048 -264.065828)
		(end 36.82746 -264.028428)
		(width 0.09525)
		(layer "F.Cu")
		(net "SAS2X28_DRIVE_RX_P_A7")
	)
	(arc
		(start 34.052002 -263.714992)
		(mid 33.872955 -263.796913)
		(end 33.718246 -263.9187)
		(width 0.09525)
		(layer "F.Cu")
		(net "SAS2X28_DRIVE_RX_P_A7")
	)
	(arc
		(start 34.483548 -263.676892)
		(mid 34.449884 -263.676533)
		(end 34.416238 -263.675368)
		(width 0.09525)
		(layer "F.Cu")
		(net "SAS2X28_DRIVE_RX_P_A7")
	)
	(arc
		(start 34.166556 -263.687052)
		(mid 34.139434 -263.689163)
		(end 34.112962 -263.695434)
		(width 0.09525)
		(layer "F.Cu")
		(net "SAS2X28_DRIVE_RX_P_A7")
	)
	(arc
		(start 34.305748 -263.675368)
		(mid 34.235907 -263.678287)
		(end 34.166556 -263.687052)
		(width 0.09525)
		(layer "F.Cu")
		(net "SAS2X28_DRIVE_RX_P_A7")
	)
	(arc
		(start 36.947348 -264.150094)
		(mid 36.912896 -264.143294)
		(end 36.883594 -264.123932)
		(width 0.09525)
		(layer "F.Cu")
		(net "SAS2X28_DRIVE_RX_P_A7")
	)
	(arc
		(start 36.82746 -263.778492)
		(mid 36.797702 -263.70665)
		(end 36.72586 -263.676892)
		(width 0.09525)
		(layer "F.Cu")
		(net "SAS2X28_DRIVE_RX_P_A7")
	)
	(segment
		(start 18.230342 -465.246466)
		(end 19.641312 -465.246466)
		(width 0.111252)
		(layer "F.Cu")
		(net "FLT_HDD10")
	)
	(segment
		(start 20.074128 -465.679282)
		(end 19.811746 -465.4169)
		(width 0.111252)
		(layer "F.Cu")
		(net "FLT_HDD10")
	)
	(segment
		(start 20.759166 -465.679282)
		(end 20.074128 -465.679282)
		(width 0.111252)
		(layer "F.Cu")
		(net "FLT_HDD10")
	)
	(segment
		(start 20.954746 -465.483702)
		(end 20.759166 -465.679282)
		(width 0.111252)
		(layer "F.Cu")
		(net "FLT_HDD10")
	)
	(segment
		(start 19.641312 -465.246466)
		(end 19.811746 -465.4169)
		(width 0.111252)
		(layer "F.Cu")
		(net "FLT_HDD10")
	)
	(via
		(at 19.811746 -465.4169)
		(size 0.7112)
		(drill 0.3556)
		(layers "F.Cu" "B.Cu")
		(net "FLT_HDD10")
	)
	(segment
		(start 36.594796 -366.67694)
		(end 33.681924 -366.67694)
		(width 0.09525)
		(layer "F.Cu")
		(net "SAS2X28_DRIVE_RX_P_A6")
	)
	(segment
		(start 33.30956 -366.92967)
		(end 33.30956 -366.964214)
		(width 0.09525)
		(layer "F.Cu")
		(net "SAS2X28_DRIVE_RX_P_A6")
	)
	(segment
		(start 38.250114 -367.150142)
		(end 37.211508 -367.150142)
		(width 0.09525)
		(layer "F.Cu")
		(net "SAS2X28_DRIVE_RX_P_A6")
	)
	(segment
		(start 33.41878 -366.78616)
		(end 33.333944 -366.870742)
		(width 0.09525)
		(layer "F.Cu")
		(net "SAS2X28_DRIVE_RX_P_A6")
	)
	(segment
		(start 36.900358 -367.033048)
		(end 36.86556 -366.997996)
		(width 0.09525)
		(layer "F.Cu")
		(net "SAS2X28_DRIVE_RX_P_A6")
	)
	(arc
		(start 36.86556 -366.997996)
		(mid 36.839055 -366.958519)
		(end 36.829746 -366.91189)
		(width 0.09525)
		(layer "F.Cu")
		(net "SAS2X28_DRIVE_RX_P_A6")
	)
	(arc
		(start 37.211508 -367.150142)
		(mid 37.045293 -367.119885)
		(end 36.900358 -367.033048)
		(width 0.09525)
		(layer "F.Cu")
		(net "SAS2X28_DRIVE_RX_P_A6")
	)
	(arc
		(start 33.333944 -366.870742)
		(mid 33.315879 -366.897778)
		(end 33.30956 -366.92967)
		(width 0.09525)
		(layer "F.Cu")
		(net "SAS2X28_DRIVE_RX_P_A6")
	)
	(arc
		(start 33.681924 -366.67694)
		(mid 33.53948 -366.705367)
		(end 33.41878 -366.78616)
		(width 0.09525)
		(layer "F.Cu")
		(net "SAS2X28_DRIVE_RX_P_A6")
	)
	(arc
		(start 36.829746 -366.91189)
		(mid 36.760931 -366.745755)
		(end 36.594796 -366.67694)
		(width 0.09525)
		(layer "F.Cu")
		(net "SAS2X28_DRIVE_RX_P_A6")
	)
	(via
		(at 212.118956 -495.5921)
		(size 0.7112)
		(drill 0.3556)
		(layers "F.Cu" "B.Cu")
		(net "P12V_HDD0")
	)
	(via
		(at 203.021438 -497.670582)
		(size 0.7112)
		(drill 0.3556)
		(layers "F.Cu" "B.Cu")
		(net "P12V_HDD0")
	)
	(via
		(at 212.038946 -494.5253)
		(size 0.5588)
		(drill 0.3048)
		(layers "F.Cu" "B.Cu")
		(net "P12V_HDD0")
	)
	(via
		(at 203.733146 -498.3353)
		(size 0.5588)
		(drill 0.3048)
		(layers "F.Cu" "B.Cu")
		(net "P12V_HDD0")
	)
	(segment
		(start 212.038946 -494.5253)
		(end 212.118956 -494.60531)
		(width 0.508)
		(layer "B.Cu")
		(net "P12V_HDD0")
	)
	(segment
		(start 212.118956 -494.60531)
		(end 212.118956 -495.5921)
		(width 0.508)
		(layer "B.Cu")
		(net "P12V_HDD0")
	)
	(segment
		(start 203.686156 -498.3353)
		(end 203.021438 -497.670582)
		(width 0.508)
		(layer "B.Cu")
		(net "P12V_HDD0")
	)
	(segment
		(start 203.733146 -498.3353)
		(end 203.686156 -498.3353)
		(width 0.508)
		(layer "B.Cu")
		(net "P12V_HDD0")
	)
	(segment
		(start 41.769538 -39.750492)
		(end 41.274746 -39.2557)
		(width 0.111252)
		(layer "F.Cu")
		(net "FLT_HDD9")
	)
	(segment
		(start 41.274746 -39.2557)
		(end 41.192958 -39.2557)
		(width 0.111252)
		(layer "F.Cu")
		(net "FLT_HDD9")
	)
	(segment
		(start 41.769792 -40.753538)
		(end 41.769538 -40.753284)
		(width 0.111252)
		(layer "F.Cu")
		(net "FLT_HDD9")
	)
	(segment
		(start 40.893746 -40.2082)
		(end 40.893746 -39.554912)
		(width 0.111252)
		(layer "F.Cu")
		(net "FLT_HDD9")
	)
	(segment
		(start 40.195246 -40.9067)
		(end 40.893746 -40.2082)
		(width 0.111252)
		(layer "F.Cu")
		(net "FLT_HDD9")
	)
	(segment
		(start 41.769538 -40.753284)
		(end 41.769538 -39.750492)
		(width 0.111252)
		(layer "F.Cu")
		(net "FLT_HDD9")
	)
	(segment
		(start 40.893746 -39.554912)
		(end 41.192958 -39.2557)
		(width 0.111252)
		(layer "F.Cu")
		(net "FLT_HDD9")
	)
	(via
		(at 41.192958 -39.2557)
		(size 0.7112)
		(drill 0.3556)
		(layers "F.Cu" "B.Cu")
		(net "FLT_HDD9")
	)
	(segment
		(start 36.834064 -469.983312)
		(end 36.829746 -469.96985)
		(width 0.09525)
		(layer "F.Cu")
		(net "SAS2X28_DRIVE_RX_P_A5")
	)
	(segment
		(start 36.82746 -469.953848)
		(end 36.82746 -469.778588)
		(width 0.09525)
		(layer "F.Cu")
		(net "SAS2X28_DRIVE_RX_P_A5")
	)
	(segment
		(start 36.72586 -469.676988)
		(end 33.875472 -469.676988)
		(width 0.09525)
		(layer "F.Cu")
		(net "SAS2X28_DRIVE_RX_P_A5")
	)
	(segment
		(start 38.250114 -470.15019)
		(end 37.061394 -470.15019)
		(width 0.09525)
		(layer "F.Cu")
		(net "SAS2X28_DRIVE_RX_P_A5")
	)
	(arc
		(start 36.82746 -469.778588)
		(mid 36.807691 -469.71837)
		(end 36.756086 -469.68156)
		(width 0.09525)
		(layer "F.Cu")
		(net "SAS2X28_DRIVE_RX_P_A5")
	)
	(arc
		(start 33.875472 -469.676988)
		(mid 33.665711 -469.718712)
		(end 33.487868 -469.837516)
		(width 0.09525)
		(layer "F.Cu")
		(net "SAS2X28_DRIVE_RX_P_A5")
	)
	(arc
		(start 36.829746 -469.96985)
		(mid 36.828013 -469.961934)
		(end 36.82746 -469.953848)
		(width 0.09525)
		(layer "F.Cu")
		(net "SAS2X28_DRIVE_RX_P_A5")
	)
	(arc
		(start 36.756086 -469.68156)
		(mid 36.741147 -469.678117)
		(end 36.72586 -469.676988)
		(width 0.09525)
		(layer "F.Cu")
		(net "SAS2X28_DRIVE_RX_P_A5")
	)
	(arc
		(start 37.061394 -470.15019)
		(mid 36.920328 -470.104065)
		(end 36.834064 -469.983312)
		(width 0.09525)
		(layer "F.Cu")
		(net "SAS2X28_DRIVE_RX_P_A5")
	)
	(via
		(at 218.694 -487.045)
		(size 0.7112)
		(drill 0.3556)
		(layers "F.Cu" "B.Cu")
		(net "P5V_HDD0")
	)
	(via
		(at 217.703146 -487.0831)
		(size 0.5588)
		(drill 0.3048)
		(layers "F.Cu" "B.Cu")
		(net "P5V_HDD0")
	)
	(via
		(at 210.566 -485.902)
		(size 0.7112)
		(drill 0.3556)
		(layers "F.Cu" "B.Cu")
		(net "P5V_HDD0")
	)
	(segment
		(start 217.703146 -487.0831)
		(end 217.805 -487.045)
		(width 0.508)
		(layer "B.Cu")
		(net "P5V_HDD0")
	)
	(segment
		(start 217.805 -487.045)
		(end 218.694 -487.045)
		(width 0.508)
		(layer "B.Cu")
		(net "P5V_HDD0")
	)
	(segment
		(start 41.769792 -143.753586)
		(end 41.746678 -143.7767)
		(width 0.111252)
		(layer "F.Cu")
		(net "FLT_HDD8")
	)
	(segment
		(start 41.746678 -143.7767)
		(end 40.068246 -143.7767)
		(width 0.111252)
		(layer "F.Cu")
		(net "FLT_HDD8")
	)
	(segment
		(start 40.068246 -143.7767)
		(end 40.068246 -142.748)
		(width 0.111252)
		(layer "F.Cu")
		(net "FLT_HDD8")
	)
	(via
		(at 40.068246 -142.748)
		(size 0.7112)
		(drill 0.3556)
		(layers "F.Cu" "B.Cu")
		(net "FLT_HDD8")
	)
	(segment
		(start 218.623388 -58.019696)
		(end 218.243912 -58.019696)
		(width 0.09525)
		(layer "F.Cu")
		(net "SAS2X28_DRIVE_RX_P_A4")
	)
	(segment
		(start 222.0087 -58.0517)
		(end 221.84614 -57.88914)
		(width 0.09525)
		(layer "F.Cu")
		(net "SAS2X28_DRIVE_RX_P_A4")
	)
	(segment
		(start 221.486984 -57.740296)
		(end 219.298012 -57.740296)
		(width 0.09525)
		(layer "F.Cu")
		(net "SAS2X28_DRIVE_RX_P_A4")
	)
	(segment
		(start 223.249998 -58.149998)
		(end 222.245936 -58.149998)
		(width 0.09525)
		(layer "F.Cu")
		(net "SAS2X28_DRIVE_RX_P_A4")
	)
	(arc
		(start 221.54896 -57.743852)
		(mid 221.518664 -57.741031)
		(end 221.488254 -57.740042)
		(width 0.09525)
		(layer "F.Cu")
		(net "SAS2X28_DRIVE_RX_P_A4")
	)
	(arc
		(start 219.298012 -57.740296)
		(mid 219.115467 -57.776606)
		(end 218.9607 -57.879996)
		(width 0.09525)
		(layer "F.Cu")
		(net "SAS2X28_DRIVE_RX_P_A4")
	)
	(arc
		(start 221.65691 -57.769252)
		(mid 221.651713 -57.767445)
		(end 221.646496 -57.765696)
		(width 0.09525)
		(layer "F.Cu")
		(net "SAS2X28_DRIVE_RX_P_A4")
	)
	(arc
		(start 221.84614 -57.88914)
		(mid 221.75822 -57.818629)
		(end 221.65691 -57.769252)
		(width 0.09525)
		(layer "F.Cu")
		(net "SAS2X28_DRIVE_RX_P_A4")
	)
	(arc
		(start 218.9607 -57.879996)
		(mid 218.80594 -57.983403)
		(end 218.623388 -58.019696)
		(width 0.09525)
		(layer "F.Cu")
		(net "SAS2X28_DRIVE_RX_P_A4")
	)
	(arc
		(start 222.245936 -58.149998)
		(mid 222.117533 -58.124457)
		(end 222.0087 -58.0517)
		(width 0.09525)
		(layer "F.Cu")
		(net "SAS2X28_DRIVE_RX_P_A4")
	)
	(arc
		(start 221.621096 -57.758076)
		(mid 221.585286 -57.749655)
		(end 221.54896 -57.743852)
		(width 0.09525)
		(layer "F.Cu")
		(net "SAS2X28_DRIVE_RX_P_A4")
	)
	(arc
		(start 221.638114 -57.763156)
		(mid 221.629627 -57.760543)
		(end 221.621096 -57.758076)
		(width 0.09525)
		(layer "F.Cu")
		(net "SAS2X28_DRIVE_RX_P_A4")
	)
	(arc
		(start 221.646496 -57.765696)
		(mid 221.64231 -57.764408)
		(end 221.638114 -57.763156)
		(width 0.09525)
		(layer "F.Cu")
		(net "SAS2X28_DRIVE_RX_P_A4")
	)
	(arc
		(start 221.488254 -57.740042)
		(mid 221.487619 -57.740169)
		(end 221.486984 -57.740296)
		(width 0.09525)
		(layer "F.Cu")
		(net "SAS2X28_DRIVE_RX_P_A4")
	)
	(segment
		(start 40.218614 -246.750332)
		(end 40.195246 -246.7737)
		(width 0.111252)
		(layer "F.Cu")
		(net "FLT_HDD7")
	)
	(segment
		(start 41.76649 -246.750332)
		(end 40.218614 -246.750332)
		(width 0.111252)
		(layer "F.Cu")
		(net "FLT_HDD7")
	)
	(segment
		(start 40.195246 -245.884954)
		(end 40.3352 -245.745)
		(width 0.111252)
		(layer "F.Cu")
		(net "FLT_HDD7")
	)
	(segment
		(start 40.195246 -246.7737)
		(end 40.195246 -245.884954)
		(width 0.111252)
		(layer "F.Cu")
		(net "FLT_HDD7")
	)
	(segment
		(start 41.769792 -246.753634)
		(end 41.76649 -246.750332)
		(width 0.111252)
		(layer "F.Cu")
		(net "FLT_HDD7")
	)
	(via
		(at 40.3352 -245.745)
		(size 0.7112)
		(drill 0.3556)
		(layers "F.Cu" "B.Cu")
		(net "FLT_HDD7")
	)
	(segment
		(start 221.684596 -161.080196)
		(end 221.649544 -161.045144)
		(width 0.09525)
		(layer "F.Cu")
		(net "SAS2X28_DRIVE_RX_P_A3")
	)
	(segment
		(start 221.379796 -160.676844)
		(end 218.820746 -160.676844)
		(width 0.09525)
		(layer "F.Cu")
		(net "SAS2X28_DRIVE_RX_P_A3")
	)
	(segment
		(start 223.249998 -161.150046)
		(end 221.853252 -161.150046)
		(width 0.09525)
		(layer "F.Cu")
		(net "SAS2X28_DRIVE_RX_P_A3")
	)
	(segment
		(start 221.614746 -160.96107)
		(end 221.614746 -160.911794)
		(width 0.09525)
		(layer "F.Cu")
		(net "SAS2X28_DRIVE_RX_P_A3")
	)
	(arc
		(start 221.614746 -160.911794)
		(mid 221.586142 -160.799443)
		(end 221.507304 -160.714436)
		(width 0.09525)
		(layer "F.Cu")
		(net "SAS2X28_DRIVE_RX_P_A3")
	)
	(arc
		(start 221.853252 -161.150046)
		(mid 221.76198 -161.131891)
		(end 221.684596 -161.080196)
		(width 0.09525)
		(layer "F.Cu")
		(net "SAS2X28_DRIVE_RX_P_A3")
	)
	(arc
		(start 221.649544 -161.045144)
		(mid 221.62377 -161.006571)
		(end 221.614746 -160.96107)
		(width 0.09525)
		(layer "F.Cu")
		(net "SAS2X28_DRIVE_RX_P_A3")
	)
	(arc
		(start 221.498414 -160.708848)
		(mid 221.441229 -160.684985)
		(end 221.379796 -160.676844)
		(width 0.09525)
		(layer "F.Cu")
		(net "SAS2X28_DRIVE_RX_P_A3")
	)
	(arc
		(start 218.820746 -160.676844)
		(mid 218.512413 -160.766026)
		(end 218.299284 -161.006028)
		(width 0.09525)
		(layer "F.Cu")
		(net "SAS2X28_DRIVE_RX_P_A3")
	)
	(arc
		(start 221.507304 -160.714436)
		(mid 221.502891 -160.711591)
		(end 221.498414 -160.708848)
		(width 0.09525)
		(layer "F.Cu")
		(net "SAS2X28_DRIVE_RX_P_A3")
	)
	(segment
		(start 41.769792 -349.753682)
		(end 41.769538 -349.753428)
		(width 0.111252)
		(layer "F.Cu")
		(net "FLT_HDD6")
	)
	(segment
		(start 43.179746 -347.3577)
		(end 44.957746 -347.3577)
		(width 0.111252)
		(layer "F.Cu")
		(net "FLT_HDD6")
	)
	(segment
		(start 45.847 -349.6437)
		(end 44.957746 -348.754446)
		(width 0.111252)
		(layer "F.Cu")
		(net "FLT_HDD6")
	)
	(segment
		(start 41.769538 -349.753428)
		(end 41.769538 -348.767908)
		(width 0.111252)
		(layer "F.Cu")
		(net "FLT_HDD6")
	)
	(segment
		(start 44.957746 -348.754446)
		(end 44.957746 -347.3577)
		(width 0.111252)
		(layer "F.Cu")
		(net "FLT_HDD6")
	)
	(segment
		(start 41.769538 -348.767908)
		(end 43.179746 -347.3577)
		(width 0.111252)
		(layer "F.Cu")
		(net "FLT_HDD6")
	)
	(via
		(at 44.957746 -347.3577)
		(size 0.7112)
		(drill 0.3556)
		(layers "F.Cu" "B.Cu")
		(net "FLT_HDD6")
	)
	(segment
		(start 218.52382 -264.005568)
		(end 218.207082 -264.005568)
		(width 0.09525)
		(layer "F.Cu")
		(net "SAS2X28_DRIVE_RX_P_A2")
	)
	(segment
		(start 221.729046 -264.01014)
		(end 221.593918 -263.875012)
		(width 0.09525)
		(layer "F.Cu")
		(net "SAS2X28_DRIVE_RX_P_A2")
	)
	(segment
		(start 223.249998 -264.150094)
		(end 222.060008 -264.150094)
		(width 0.09525)
		(layer "F.Cu")
		(net "SAS2X28_DRIVE_RX_P_A2")
	)
	(segment
		(start 222.060008 -264.150094)
		(end 222.054928 -264.145014)
		(width 0.09525)
		(layer "F.Cu")
		(net "SAS2X28_DRIVE_RX_P_A2")
	)
	(segment
		(start 221.234762 -263.726168)
		(end 219.198444 -263.726168)
		(width 0.09525)
		(layer "F.Cu")
		(net "SAS2X28_DRIVE_RX_P_A2")
	)
	(arc
		(start 222.054928 -264.145014)
		(mid 221.87859 -264.109956)
		(end 221.729046 -264.01014)
		(width 0.09525)
		(layer "F.Cu")
		(net "SAS2X28_DRIVE_RX_P_A2")
	)
	(arc
		(start 221.593918 -263.875012)
		(mid 221.42915 -263.764854)
		(end 221.234762 -263.726168)
		(width 0.09525)
		(layer "F.Cu")
		(net "SAS2X28_DRIVE_RX_P_A2")
	)
	(arc
		(start 219.198444 -263.726168)
		(mid 219.015899 -263.762478)
		(end 218.861132 -263.865868)
		(width 0.09525)
		(layer "F.Cu")
		(net "SAS2X28_DRIVE_RX_P_A2")
	)
	(arc
		(start 218.861132 -263.865868)
		(mid 218.706372 -263.969275)
		(end 218.52382 -264.005568)
		(width 0.09525)
		(layer "F.Cu")
		(net "SAS2X28_DRIVE_RX_P_A2")
	)
	(segment
		(start 40.188134 -452.858886)
		(end 41.664382 -452.858886)
		(width 0.111252)
		(layer "F.Cu")
		(net "FLT_HDD5")
	)
	(segment
		(start 41.664382 -452.858886)
		(end 41.769792 -452.753476)
		(width 0.111252)
		(layer "F.Cu")
		(net "FLT_HDD5")
	)
	(segment
		(start 40.138858 -452.80961)
		(end 40.188134 -452.858886)
		(width 0.111252)
		(layer "F.Cu")
		(net "FLT_HDD5")
	)
	(segment
		(start 40.138858 -451.6882)
		(end 40.138858 -452.80961)
		(width 0.111252)
		(layer "F.Cu")
		(net "FLT_HDD5")
	)
	(via
		(at 40.138858 -451.6882)
		(size 0.7112)
		(drill 0.3556)
		(layers "F.Cu" "B.Cu")
		(net "FLT_HDD5")
	)
	(segment
		(start 221.741746 -367.019332)
		(end 221.741746 -366.82934)
		(width 0.09525)
		(layer "F.Cu")
		(net "SAS2X28_DRIVE_RX_P_A1")
	)
	(segment
		(start 223.249998 -367.150142)
		(end 221.872302 -367.150142)
		(width 0.09525)
		(layer "F.Cu")
		(net "SAS2X28_DRIVE_RX_P_A1")
	)
	(segment
		(start 221.589346 -366.67694)
		(end 219.201746 -366.67694)
		(width 0.09525)
		(layer "F.Cu")
		(net "SAS2X28_DRIVE_RX_P_A1")
	)
	(arc
		(start 221.7801 -367.112042)
		(mid 221.751732 -367.069492)
		(end 221.741746 -367.019332)
		(width 0.09525)
		(layer "F.Cu")
		(net "SAS2X28_DRIVE_RX_P_A1")
	)
	(arc
		(start 221.741746 -366.82934)
		(mid 221.697109 -366.721577)
		(end 221.589346 -366.67694)
		(width 0.09525)
		(layer "F.Cu")
		(net "SAS2X28_DRIVE_RX_P_A1")
	)
	(arc
		(start 219.201746 -366.67694)
		(mid 218.88205 -366.721338)
		(end 218.586558 -366.851184)
		(width 0.09525)
		(layer "F.Cu")
		(net "SAS2X28_DRIVE_RX_P_A1")
	)
	(arc
		(start 221.872302 -367.150142)
		(mid 221.822423 -367.140238)
		(end 221.7801 -367.112042)
		(width 0.09525)
		(layer "F.Cu")
		(net "SAS2X28_DRIVE_RX_P_A1")
	)
	(segment
		(start 226.766374 -40.750236)
		(end 224.281746 -40.750236)
		(width 0.111252)
		(layer "F.Cu")
		(net "FLT_HDD4")
	)
	(segment
		(start 222.373952 -40.750236)
		(end 224.281746 -40.750236)
		(width 0.111252)
		(layer "F.Cu")
		(net "FLT_HDD4")
	)
	(segment
		(start 226.769676 -40.753538)
		(end 226.766374 -40.750236)
		(width 0.111252)
		(layer "F.Cu")
		(net "FLT_HDD4")
	)
	(segment
		(start 222.244412 -40.620696)
		(end 222.373952 -40.750236)
		(width 0.111252)
		(layer "F.Cu")
		(net "FLT_HDD4")
	)
	(via
		(at 224.281746 -40.750236)
		(size 0.7112)
		(drill 0.3556)
		(layers "F.Cu" "B.Cu")
		(net "FLT_HDD4")
	)
	(segment
		(start 221.868746 -470.034112)
		(end 221.868746 -469.911938)
		(width 0.09525)
		(layer "F.Cu")
		(net "SAS2X28_DRIVE_RX_P_A0")
	)
	(segment
		(start 221.633796 -469.676988)
		(end 219.698824 -469.676988)
		(width 0.09525)
		(layer "F.Cu")
		(net "SAS2X28_DRIVE_RX_P_A0")
	)
	(segment
		(start 221.9071 -470.111836)
		(end 221.89694 -470.101676)
		(width 0.09525)
		(layer "F.Cu")
		(net "SAS2X28_DRIVE_RX_P_A0")
	)
	(segment
		(start 223.249998 -470.15019)
		(end 221.999302 -470.15019)
		(width 0.09525)
		(layer "F.Cu")
		(net "SAS2X28_DRIVE_RX_P_A0")
	)
	(arc
		(start 221.680024 -469.68156)
		(mid 221.657024 -469.678119)
		(end 221.633796 -469.676988)
		(width 0.09525)
		(layer "F.Cu")
		(net "SAS2X28_DRIVE_RX_P_A0")
	)
	(arc
		(start 219.698824 -469.676988)
		(mid 219.369991 -469.742397)
		(end 219.091256 -469.928702)
		(width 0.09525)
		(layer "F.Cu")
		(net "SAS2X28_DRIVE_RX_P_A0")
	)
	(arc
		(start 221.89694 -470.101676)
		(mid 221.876065 -470.070721)
		(end 221.868746 -470.034112)
		(width 0.09525)
		(layer "F.Cu")
		(net "SAS2X28_DRIVE_RX_P_A0")
	)
	(arc
		(start 221.999302 -470.15019)
		(mid 221.949394 -470.140169)
		(end 221.9071 -470.111836)
		(width 0.09525)
		(layer "F.Cu")
		(net "SAS2X28_DRIVE_RX_P_A0")
	)
	(arc
		(start 221.868746 -469.911938)
		(mid 221.81554 -469.76304)
		(end 221.680024 -469.68156)
		(width 0.09525)
		(layer "F.Cu")
		(net "SAS2X28_DRIVE_RX_P_A0")
	)
	(segment
		(start 91.5035 -11.7475)
		(end 92.202 -11.7475)
		(width 0.111252)
		(layer "F.Cu")
		(net "SW_HDD14_N")
	)
	(segment
		(start 94.234 -9.525)
		(end 94.4753 -9.2837)
		(width 0.111252)
		(layer "F.Cu")
		(net "SW_HDD14_N")
	)
	(segment
		(start 91.44 -13.462)
		(end 91.186 -13.208)
		(width 0.111252)
		(layer "F.Cu")
		(net "SW_HDD14_N")
	)
	(segment
		(start 94.4753 -9.2837)
		(end 95.630746 -9.2837)
		(width 0.111252)
		(layer "F.Cu")
		(net "SW_HDD14_N")
	)
	(segment
		(start 93.218 -11.7475)
		(end 93.2815 -11.811)
		(width 0.111252)
		(layer "F.Cu")
		(net "SW_HDD14_N")
	)
	(segment
		(start 93.2815 -11.811)
		(end 94.1705 -11.811)
		(width 0.111252)
		(layer "F.Cu")
		(net "SW_HDD14_N")
	)
	(segment
		(start 92.202 -11.7475)
		(end 93.218 -11.7475)
		(width 0.111252)
		(layer "F.Cu")
		(net "SW_HDD14_N")
	)
	(segment
		(start 91.186 -12.065)
		(end 91.5035 -11.7475)
		(width 0.111252)
		(layer "F.Cu")
		(net "SW_HDD14_N")
	)
	(segment
		(start 91.186 -13.208)
		(end 91.186 -12.065)
		(width 0.111252)
		(layer "F.Cu")
		(net "SW_HDD14_N")
	)
	(segment
		(start 94.234 -11.7475)
		(end 94.234 -9.525)
		(width 0.111252)
		(layer "F.Cu")
		(net "SW_HDD14_N")
	)
	(segment
		(start 94.1705 -11.811)
		(end 94.234 -11.7475)
		(width 0.111252)
		(layer "F.Cu")
		(net "SW_HDD14_N")
	)
	(via
		(at 91.186 -12.065)
		(size 0.7112)
		(drill 0.3556)
		(layers "F.Cu" "B.Cu")
		(net "SW_HDD14_N")
	)
	(segment
		(start 226.769676 -143.753586)
		(end 225.465132 -143.753586)
		(width 0.111252)
		(layer "F.Cu")
		(net "FLT_HDD3")
	)
	(segment
		(start 225.234246 -143.5227)
		(end 225.234246 -142.367)
		(width 0.111252)
		(layer "F.Cu")
		(net "FLT_HDD3")
	)
	(segment
		(start 225.465132 -143.753586)
		(end 225.234246 -143.5227)
		(width 0.111252)
		(layer "F.Cu")
		(net "FLT_HDD3")
	)
	(via
		(at 225.234246 -142.367)
		(size 0.7112)
		(drill 0.3556)
		(layers "F.Cu" "B.Cu")
		(net "FLT_HDD3")
	)
	(segment
		(start 45.6565 -106.807)
		(end 45.593 -106.807)
		(width 0.111252)
		(layer "F.Cu")
		(net "SW_HDD13_N")
	)
	(segment
		(start 46.736 -106.8705)
		(end 46.6725 -106.807)
		(width 0.111252)
		(layer "F.Cu")
		(net "SW_HDD13_N")
	)
	(segment
		(start 47.752 -106.8705)
		(end 46.736 -106.8705)
		(width 0.111252)
		(layer "F.Cu")
		(net "SW_HDD13_N")
	)
	(segment
		(start 45.593 -106.807)
		(end 44.45 -107.95)
		(width 0.111252)
		(layer "F.Cu")
		(net "SW_HDD13_N")
	)
	(segment
		(start 44.196 -109.232446)
		(end 44.196 -108.204)
		(width 0.111252)
		(layer "F.Cu")
		(net "SW_HDD13_N")
	)
	(segment
		(start 46.6725 -106.807)
		(end 45.6565 -106.807)
		(width 0.111252)
		(layer "F.Cu")
		(net "SW_HDD13_N")
	)
	(segment
		(start 44.196 -108.204)
		(end 44.45 -107.95)
		(width 0.111252)
		(layer "F.Cu")
		(net "SW_HDD13_N")
	)
	(segment
		(start 47.752 -105.918)
		(end 47.752 -106.8705)
		(width 0.111252)
		(layer "F.Cu")
		(net "SW_HDD13_N")
	)
	(segment
		(start 44.195746 -109.2327)
		(end 44.196 -109.232446)
		(width 0.111252)
		(layer "F.Cu")
		(net "SW_HDD13_N")
	)
	(segment
		(start 47.117 -105.283)
		(end 47.752 -105.918)
		(width 0.111252)
		(layer "F.Cu")
		(net "SW_HDD13_N")
	)
	(via
		(at 44.45 -107.95)
		(size 0.7112)
		(drill 0.3556)
		(layers "F.Cu" "B.Cu")
		(net "SW_HDD13_N")
	)
	(segment
		(start 226.766374 -246.750332)
		(end 225.302318 -246.750332)
		(width 0.111252)
		(layer "F.Cu")
		(net "FLT_HDD2")
	)
	(segment
		(start 225.302318 -246.750332)
		(end 225.192082 -246.860568)
		(width 0.111252)
		(layer "F.Cu")
		(net "FLT_HDD2")
	)
	(segment
		(start 226.769676 -246.753634)
		(end 226.766374 -246.750332)
		(width 0.111252)
		(layer "F.Cu")
		(net "FLT_HDD2")
	)
	(segment
		(start 225.192082 -246.860568)
		(end 225.192082 -245.7704)
		(width 0.111252)
		(layer "F.Cu")
		(net "FLT_HDD2")
	)
	(via
		(at 225.192082 -245.7704)
		(size 0.7112)
		(drill 0.3556)
		(layers "F.Cu" "B.Cu")
		(net "FLT_HDD2")
	)
	(segment
		(start 51.689 -208.9785)
		(end 51.816 -208.9785)
		(width 0.111252)
		(layer "F.Cu")
		(net "SW_HDD12_N")
	)
	(segment
		(start 51.689 -209.197448)
		(end 51.689 -208.9785)
		(width 0.111252)
		(layer "F.Cu")
		(net "SW_HDD12_N")
	)
	(segment
		(start 52.705 -208.0895)
		(end 53.721 -208.0895)
		(width 0.111252)
		(layer "F.Cu")
		(net "SW_HDD12_N")
	)
	(segment
		(start 51.816 -208.9785)
		(end 52.705 -208.0895)
		(width 0.111252)
		(layer "F.Cu")
		(net "SW_HDD12_N")
	)
	(segment
		(start 55.245 -206.375)
		(end 53.975 -206.375)
		(width 0.111252)
		(layer "F.Cu")
		(net "SW_HDD12_N")
	)
	(segment
		(start 50.418746 -210.467702)
		(end 51.689 -209.197448)
		(width 0.111252)
		(layer "F.Cu")
		(net "SW_HDD12_N")
	)
	(segment
		(start 53.721 -206.629)
		(end 53.975 -206.375)
		(width 0.111252)
		(layer "F.Cu")
		(net "SW_HDD12_N")
	)
	(segment
		(start 53.721 -208.0895)
		(end 53.721 -206.629)
		(width 0.111252)
		(layer "F.Cu")
		(net "SW_HDD12_N")
	)
	(via
		(at 55.245 -206.375)
		(size 0.7112)
		(drill 0.3556)
		(layers "F.Cu" "B.Cu")
		(net "SW_HDD12_N")
	)
	(segment
		(start 226.769676 -349.753682)
		(end 224.899728 -349.753682)
		(width 0.111252)
		(layer "F.Cu")
		(net "FLT_HDD1")
	)
	(segment
		(start 224.899728 -349.753682)
		(end 224.281746 -349.1357)
		(width 0.111252)
		(layer "F.Cu")
		(net "FLT_HDD1")
	)
	(segment
		(start 221.888558 -349.452184)
		(end 222.205042 -349.1357)
		(width 0.111252)
		(layer "F.Cu")
		(net "FLT_HDD1")
	)
	(segment
		(start 222.205042 -349.1357)
		(end 224.281746 -349.1357)
		(width 0.111252)
		(layer "F.Cu")
		(net "FLT_HDD1")
	)
	(via
		(at 224.281746 -349.1357)
		(size 0.7112)
		(drill 0.3556)
		(layers "F.Cu" "B.Cu")
		(net "FLT_HDD1")
	)
	(segment
		(start 35.178746 -308.892702)
		(end 35.178746 -307.657754)
		(width 0.111252)
		(layer "F.Cu")
		(net "SW_HDD11_N")
	)
	(segment
		(start 37.719 -303.784)
		(end 36.068 -303.784)
		(width 0.111252)
		(layer "F.Cu")
		(net "SW_HDD11_N")
	)
	(segment
		(start 35.4965 -305.308)
		(end 35.4965 -304.3555)
		(width 0.111252)
		(layer "F.Cu")
		(net "SW_HDD11_N")
	)
	(segment
		(start 35.4965 -307.34)
		(end 35.4965 -306.324)
		(width 0.111252)
		(layer "F.Cu")
		(net "SW_HDD11_N")
	)
	(segment
		(start 35.4965 -304.3555)
		(end 36.068 -303.784)
		(width 0.111252)
		(layer "F.Cu")
		(net "SW_HDD11_N")
	)
	(segment
		(start 35.178746 -307.657754)
		(end 35.4965 -307.34)
		(width 0.111252)
		(layer "F.Cu")
		(net "SW_HDD11_N")
	)
	(segment
		(start 35.4965 -306.324)
		(end 35.4965 -305.308)
		(width 0.111252)
		(layer "F.Cu")
		(net "SW_HDD11_N")
	)
	(via
		(at 37.719 -303.784)
		(size 0.7112)
		(drill 0.3556)
		(layers "F.Cu" "B.Cu")
		(net "SW_HDD11_N")
	)
	(segment
		(start 15.90929 -55.507636)
		(end 14.727682 -55.507636)
		(width 0.111252)
		(layer "F.Cu")
		(net "FLT_NET_HDD14")
	)
	(segment
		(start 15.049246 -53.7337)
		(end 15.049246 -54.1782)
		(width 0.111252)
		(layer "F.Cu")
		(net "FLT_NET_HDD14")
	)
	(segment
		(start 16.769842 -53.246274)
		(end 16.769588 -53.246528)
		(width 0.111252)
		(layer "F.Cu")
		(net "FLT_NET_HDD14")
	)
	(segment
		(start 16.769588 -53.246528)
		(end 16.769588 -54.108858)
		(width 0.111252)
		(layer "F.Cu")
		(net "FLT_NET_HDD14")
	)
	(segment
		(start 15.049246 -54.1782)
		(end 14.477746 -54.7497)
		(width 0.111252)
		(layer "F.Cu")
		(net "FLT_NET_HDD14")
	)
	(segment
		(start 16.219678 -54.658514)
		(end 16.219678 -54.741572)
		(width 0.111252)
		(layer "F.Cu")
		(net "FLT_NET_HDD14")
	)
	(segment
		(start 14.477746 -55.2577)
		(end 14.477746 -55.1307)
		(width 0.111252)
		(layer "F.Cu")
		(net "FLT_NET_HDD14")
	)
	(segment
		(start 16.219678 -54.741572)
		(end 16.224504 -54.746398)
		(width 0.111252)
		(layer "F.Cu")
		(net "FLT_NET_HDD14")
	)
	(segment
		(start 16.224504 -54.746398)
		(end 16.224504 -55.192422)
		(width 0.111252)
		(layer "F.Cu")
		(net "FLT_NET_HDD14")
	)
	(segment
		(start 16.769588 -54.108858)
		(end 16.219678 -54.658514)
		(width 0.111252)
		(layer "F.Cu")
		(net "FLT_NET_HDD14")
	)
	(segment
		(start 14.477746 -54.7497)
		(end 14.477746 -55.1307)
		(width 0.111252)
		(layer "F.Cu")
		(net "FLT_NET_HDD14")
	)
	(segment
		(start 14.727682 -55.507636)
		(end 14.477746 -55.2577)
		(width 0.111252)
		(layer "F.Cu")
		(net "FLT_NET_HDD14")
	)
	(segment
		(start 16.224504 -55.192422)
		(end 15.90929 -55.507636)
		(width 0.111252)
		(layer "F.Cu")
		(net "FLT_NET_HDD14")
	)
	(via
		(at 14.477746 -55.1307)
		(size 0.7112)
		(drill 0.3556)
		(layers "F.Cu" "B.Cu")
		(net "FLT_NET_HDD14")
	)
	(segment
		(start 52.5145 -418.973)
		(end 52.5145 -419.6715)
		(width 0.111252)
		(layer "F.Cu")
		(net "SW_HDD10_N")
	)
	(segment
		(start 51.562 -416.8775)
		(end 51.6255 -416.8775)
		(width 0.111252)
		(layer "F.Cu")
		(net "SW_HDD10_N")
	)
	(segment
		(start 52.5145 -417.7665)
		(end 52.5145 -418.973)
		(width 0.111252)
		(layer "F.Cu")
		(net "SW_HDD10_N")
	)
	(segment
		(start 50.546 -416.8775)
		(end 51.562 -416.8775)
		(width 0.111252)
		(layer "F.Cu")
		(net "SW_HDD10_N")
	)
	(segment
		(start 51.6255 -416.8775)
		(end 52.5145 -417.7665)
		(width 0.111252)
		(layer "F.Cu")
		(net "SW_HDD10_N")
	)
	(segment
		(start 47.878746 -416.715702)
		(end 49.53 -416.715702)
		(width 0.111252)
		(layer "F.Cu")
		(net "SW_HDD10_N")
	)
	(segment
		(start 50.384202 -416.715702)
		(end 50.546 -416.8775)
		(width 0.111252)
		(layer "F.Cu")
		(net "SW_HDD10_N")
	)
	(segment
		(start 49.53 -416.715702)
		(end 50.384202 -416.715702)
		(width 0.111252)
		(layer "F.Cu")
		(net "SW_HDD10_N")
	)
	(segment
		(start 52.5145 -419.6715)
		(end 53.34 -420.497)
		(width 0.111252)
		(layer "F.Cu")
		(net "SW_HDD10_N")
	)
	(via
		(at 49.53 -416.715702)
		(size 0.7112)
		(drill 0.3556)
		(layers "F.Cu" "B.Cu")
		(net "SW_HDD10_N")
	)
	(segment
		(start 76.199746 -92.9767)
		(end 76.2 -92.976954)
		(width 0.111252)
		(layer "F.Cu")
		(net "SW_HDD9_N")
	)
	(segment
		(start 76.2 -92.976954)
		(end 76.2 -94.234)
		(width 0.111252)
		(layer "F.Cu")
		(net "SW_HDD9_N")
	)
	(segment
		(start 77.978 -94.9325)
		(end 78.994 -94.9325)
		(width 0.111252)
		(layer "F.Cu")
		(net "SW_HDD9_N")
	)
	(segment
		(start 78.994 -94.9325)
		(end 80.01 -94.9325)
		(width 0.111252)
		(layer "F.Cu")
		(net "SW_HDD9_N")
	)
	(segment
		(start 76.2 -94.234)
		(end 76.708 -94.742)
		(width 0.111252)
		(layer "F.Cu")
		(net "SW_HDD9_N")
	)
	(segment
		(start 80.01 -94.9325)
		(end 80.518 -95.4405)
		(width 0.111252)
		(layer "F.Cu")
		(net "SW_HDD9_N")
	)
	(segment
		(start 76.8985 -94.9325)
		(end 77.978 -94.9325)
		(width 0.111252)
		(layer "F.Cu")
		(net "SW_HDD9_N")
	)
	(segment
		(start 80.518 -95.4405)
		(end 80.518 -96.52)
		(width 0.111252)
		(layer "F.Cu")
		(net "SW_HDD9_N")
	)
	(segment
		(start 76.708 -94.742)
		(end 76.8985 -94.9325)
		(width 0.111252)
		(layer "F.Cu")
		(net "SW_HDD9_N")
	)
	(via
		(at 76.708 -94.742)
		(size 0.7112)
		(drill 0.3556)
		(layers "F.Cu" "B.Cu")
		(net "SW_HDD9_N")
	)
	(segment
		(start 77.36078 -196.2277)
		(end 76.453746 -196.2277)
		(width 0.111252)
		(layer "F.Cu")
		(net "SW_HDD8_N")
	)
	(segment
		(start 77.91958 -196.7865)
		(end 77.36078 -196.2277)
		(width 0.111252)
		(layer "F.Cu")
		(net "SW_HDD8_N")
	)
	(segment
		(start 79.3115 -197.104)
		(end 78.994 -196.7865)
		(width 0.111252)
		(layer "F.Cu")
		(net "SW_HDD8_N")
	)
	(segment
		(start 77.216 -199.517)
		(end 78.867 -199.517)
		(width 0.111252)
		(layer "F.Cu")
		(net "SW_HDD8_N")
	)
	(segment
		(start 79.3115 -197.866)
		(end 79.3115 -197.104)
		(width 0.111252)
		(layer "F.Cu")
		(net "SW_HDD8_N")
	)
	(segment
		(start 79.3115 -199.0725)
		(end 79.3115 -197.866)
		(width 0.111252)
		(layer "F.Cu")
		(net "SW_HDD8_N")
	)
	(segment
		(start 78.994 -196.7865)
		(end 77.978 -196.7865)
		(width 0.111252)
		(layer "F.Cu")
		(net "SW_HDD8_N")
	)
	(segment
		(start 77.978 -196.7865)
		(end 77.91958 -196.7865)
		(width 0.111252)
		(layer "F.Cu")
		(net "SW_HDD8_N")
	)
	(segment
		(start 78.867 -199.517)
		(end 79.3115 -199.0725)
		(width 0.111252)
		(layer "F.Cu")
		(net "SW_HDD8_N")
	)
	(via
		(at 77.216 -199.517)
		(size 0.7112)
		(drill 0.3556)
		(layers "F.Cu" "B.Cu")
		(net "SW_HDD8_N")
	)
	(segment
		(start 14.477746 -164.715698)
		(end 16.769842 -162.423602)
		(width 0.111252)
		(layer "F.Cu")
		(net "FLT_NET_HDD13")
	)
	(segment
		(start 16.769842 -162.423602)
		(end 16.769842 -162.0774)
		(width 0.111252)
		(layer "F.Cu")
		(net "FLT_NET_HDD13")
	)
	(segment
		(start 16.769842 -156.246322)
		(end 16.769842 -162.0774)
		(width 0.111252)
		(layer "F.Cu")
		(net "FLT_NET_HDD13")
	)
	(via
		(at 16.769842 -162.0774)
		(size 0.7112)
		(drill 0.3556)
		(layers "F.Cu" "B.Cu")
		(net "FLT_NET_HDD13")
	)
	(segment
		(start 30.0355 -288.925)
		(end 30.226 -288.7345)
		(width 0.111252)
		(layer "F.Cu")
		(net "SW_HDD7_N")
	)
	(segment
		(start 22.60092 -282.702)
		(end 24.3586 -284.45968)
		(width 0.111252)
		(layer "F.Cu")
		(net "SW_HDD7_N")
	)
	(segment
		(start 31.242 -288.7345)
		(end 32.258 -288.7345)
		(width 0.111252)
		(layer "F.Cu")
		(net "SW_HDD7_N")
	)
	(segment
		(start 25.2857 -288.5567)
		(end 26.669746 -288.5567)
		(width 0.111252)
		(layer "F.Cu")
		(net "SW_HDD7_N")
	)
	(segment
		(start 33.147 -288.29)
		(end 33.147 -286.893)
		(width 0.111252)
		(layer "F.Cu")
		(net "SW_HDD7_N")
	)
	(segment
		(start 32.7025 -288.7345)
		(end 33.147 -288.29)
		(width 0.111252)
		(layer "F.Cu")
		(net "SW_HDD7_N")
	)
	(segment
		(start 32.258 -288.7345)
		(end 32.7025 -288.7345)
		(width 0.111252)
		(layer "F.Cu")
		(net "SW_HDD7_N")
	)
	(segment
		(start 21.844 -282.702)
		(end 22.60092 -282.702)
		(width 0.111252)
		(layer "F.Cu")
		(net "SW_HDD7_N")
	)
	(segment
		(start 30.226 -288.7345)
		(end 31.242 -288.7345)
		(width 0.111252)
		(layer "F.Cu")
		(net "SW_HDD7_N")
	)
	(segment
		(start 26.669746 -288.5567)
		(end 27.758898 -288.5567)
		(width 0.111252)
		(layer "F.Cu")
		(net "SW_HDD7_N")
	)
	(segment
		(start 33.147 -286.893)
		(end 33.398714 -286.641286)
		(width 0.111252)
		(layer "F.Cu")
		(net "SW_HDD7_N")
	)
	(segment
		(start 24.3586 -287.6296)
		(end 25.2857 -288.5567)
		(width 0.111252)
		(layer "F.Cu")
		(net "SW_HDD7_N")
	)
	(segment
		(start 24.3586 -284.45968)
		(end 24.3586 -287.6296)
		(width 0.111252)
		(layer "F.Cu")
		(net "SW_HDD7_N")
	)
	(segment
		(start 27.758898 -288.5567)
		(end 28.127198 -288.925)
		(width 0.111252)
		(layer "F.Cu")
		(net "SW_HDD7_N")
	)
	(segment
		(start 28.127198 -288.925)
		(end 30.0355 -288.925)
		(width 0.111252)
		(layer "F.Cu")
		(net "SW_HDD7_N")
	)
	(segment
		(start 33.398714 -286.641286)
		(end 33.398714 -286.634682)
		(width 0.111252)
		(layer "F.Cu")
		(net "SW_HDD7_N")
	)
	(via
		(at 33.398714 -286.634682)
		(size 0.7112)
		(drill 0.3556)
		(layers "F.Cu" "B.Cu")
		(net "SW_HDD7_N")
	)
	(segment
		(start 77.216 -405.638)
		(end 78.867 -405.638)
		(width 0.111252)
		(layer "F.Cu")
		(net "SW_HDD6_N")
	)
	(segment
		(start 77.851 -402.9075)
		(end 76.885546 -402.9075)
		(width 0.111252)
		(layer "F.Cu")
		(net "SW_HDD6_N")
	)
	(segment
		(start 76.885546 -402.9075)
		(end 76.199746 -402.2217)
		(width 0.111252)
		(layer "F.Cu")
		(net "SW_HDD6_N")
	)
	(segment
		(start 78.867 -405.638)
		(end 79.4385 -405.0665)
		(width 0.111252)
		(layer "F.Cu")
		(net "SW_HDD6_N")
	)
	(segment
		(start 79.4385 -404.114)
		(end 79.4385 -403.479)
		(width 0.111252)
		(layer "F.Cu")
		(net "SW_HDD6_N")
	)
	(segment
		(start 78.867 -402.9075)
		(end 77.851 -402.9075)
		(width 0.111252)
		(layer "F.Cu")
		(net "SW_HDD6_N")
	)
	(segment
		(start 79.4385 -405.0665)
		(end 79.4385 -404.114)
		(width 0.111252)
		(layer "F.Cu")
		(net "SW_HDD6_N")
	)
	(segment
		(start 79.4385 -403.479)
		(end 78.867 -402.9075)
		(width 0.111252)
		(layer "F.Cu")
		(net "SW_HDD6_N")
	)
	(via
		(at 77.216 -405.638)
		(size 0.7112)
		(drill 0.3556)
		(layers "F.Cu" "B.Cu")
		(net "SW_HDD6_N")
	)
	(segment
		(start 83.82 -501.2055)
		(end 84.2645 -500.761)
		(width 0.111252)
		(layer "F.Cu")
		(net "SW_HDD5_N")
	)
	(segment
		(start 77.645514 -501.9548)
		(end 77.959204 -501.9548)
		(width 0.111252)
		(layer "F.Cu")
		(net "SW_HDD5_N")
	)
	(segment
		(start 79.609696 -501.351804)
		(end 79.629 -501.3325)
		(width 0.111252)
		(layer "F.Cu")
		(net "SW_HDD5_N")
	)
	(segment
		(start 79.8195 -501.523)
		(end 83.5025 -501.523)
		(width 0.111252)
		(layer "F.Cu")
		(net "SW_HDD5_N")
	)
	(segment
		(start 83.5025 -501.523)
		(end 83.82 -501.2055)
		(width 0.111252)
		(layer "F.Cu")
		(net "SW_HDD5_N")
	)
	(segment
		(start 76.143358 -501.952514)
		(end 77.643228 -501.952514)
		(width 0.111252)
		(layer "F.Cu")
		(net "SW_HDD5_N")
	)
	(segment
		(start 77.643228 -501.952514)
		(end 77.645514 -501.9548)
		(width 0.111252)
		(layer "F.Cu")
		(net "SW_HDD5_N")
	)
	(segment
		(start 78.5622 -501.351804)
		(end 79.609696 -501.351804)
		(width 0.111252)
		(layer "F.Cu")
		(net "SW_HDD5_N")
	)
	(segment
		(start 79.629 -501.3325)
		(end 79.8195 -501.523)
		(width 0.111252)
		(layer "F.Cu")
		(net "SW_HDD5_N")
	)
	(segment
		(start 84.2645 -500.761)
		(end 85.344 -500.761)
		(width 0.111252)
		(layer "F.Cu")
		(net "SW_HDD5_N")
	)
	(segment
		(start 77.959204 -501.9548)
		(end 78.5622 -501.351804)
		(width 0.111252)
		(layer "F.Cu")
		(net "SW_HDD5_N")
	)
	(via
		(at 77.645514 -501.9548)
		(size 0.7112)
		(drill 0.3556)
		(layers "F.Cu" "B.Cu")
		(net "SW_HDD5_N")
	)
	(segment
		(start 16.890746 -260.3627)
		(end 16.890746 -259.367274)
		(width 0.111252)
		(layer "F.Cu")
		(net "FLT_NET_HDD12")
	)
	(segment
		(start 16.890746 -259.367274)
		(end 16.769842 -259.24637)
		(width 0.111252)
		(layer "F.Cu")
		(net "FLT_NET_HDD12")
	)
	(segment
		(start 15.541244 -260.7437)
		(end 16.636746 -260.7437)
		(width 0.111252)
		(layer "F.Cu")
		(net "FLT_NET_HDD12")
	)
	(segment
		(start 16.636746 -260.7437)
		(end 16.890746 -260.4897)
		(width 0.111252)
		(layer "F.Cu")
		(net "FLT_NET_HDD12")
	)
	(segment
		(start 15.160244 -260.3627)
		(end 15.541244 -260.7437)
		(width 0.111252)
		(layer "F.Cu")
		(net "FLT_NET_HDD12")
	)
	(segment
		(start 16.890746 -260.4897)
		(end 16.890746 -260.3627)
		(width 0.111252)
		(layer "F.Cu")
		(net "FLT_NET_HDD12")
	)
	(via
		(at 17.830546 -260.3627)
		(size 0.7112)
		(drill 0.3556)
		(layers "F.Cu" "B.Cu")
		(net "FLT_NET_HDD12")
	)
	(via
		(at 16.890746 -260.3627)
		(size 0.5588)
		(drill 0.3048)
		(layers "F.Cu" "B.Cu")
		(net "FLT_NET_HDD12")
	)
	(segment
		(start 16.890746 -260.3627)
		(end 17.830546 -260.3627)
		(width 0.111252)
		(layer "B.Cu")
		(net "FLT_NET_HDD12")
	)
	(segment
		(start 193.2305 -91.7575)
		(end 193.548 -92.075)
		(width 0.111252)
		(layer "F.Cu")
		(net "SW_HDD4_N")
	)
	(segment
		(start 194.056 -89.4715)
		(end 193.2305 -90.297)
		(width 0.111252)
		(layer "F.Cu")
		(net "SW_HDD4_N")
	)
	(segment
		(start 193.2305 -90.297)
		(end 193.2305 -91.7575)
		(width 0.111252)
		(layer "F.Cu")
		(net "SW_HDD4_N")
	)
	(segment
		(start 196.742304 -86.848696)
		(end 195.326 -88.265)
		(width 0.111252)
		(layer "F.Cu")
		(net "SW_HDD4_N")
	)
	(segment
		(start 195.326 -88.265)
		(end 195.326 -89.4715)
		(width 0.111252)
		(layer "F.Cu")
		(net "SW_HDD4_N")
	)
	(segment
		(start 194.31 -89.4715)
		(end 194.056 -89.4715)
		(width 0.111252)
		(layer "F.Cu")
		(net "SW_HDD4_N")
	)
	(segment
		(start 197.606412 -86.848696)
		(end 196.742304 -86.848696)
		(width 0.111252)
		(layer "F.Cu")
		(net "SW_HDD4_N")
	)
	(segment
		(start 195.326 -89.4715)
		(end 194.31 -89.4715)
		(width 0.111252)
		(layer "F.Cu")
		(net "SW_HDD4_N")
	)
	(via
		(at 195.326 -88.265)
		(size 0.7112)
		(drill 0.3556)
		(layers "F.Cu" "B.Cu")
		(net "SW_HDD4_N")
	)
	(segment
		(start 193.4845 -191.77)
		(end 193.4845 -191.1985)
		(width 0.111252)
		(layer "F.Cu")
		(net "SW_HDD3_N")
	)
	(segment
		(start 197.993 -186.944)
		(end 197.280784 -187.656216)
		(width 0.111252)
		(layer "F.Cu")
		(net "SW_HDD3_N")
	)
	(segment
		(start 194.31 -193.421)
		(end 193.4845 -192.5955)
		(width 0.111252)
		(layer "F.Cu")
		(net "SW_HDD3_N")
	)
	(segment
		(start 197.280784 -187.656216)
		(end 197.280784 -188.565028)
		(width 0.111252)
		(layer "F.Cu")
		(net "SW_HDD3_N")
	)
	(segment
		(start 193.8655 -190.8175)
		(end 194.564 -190.8175)
		(width 0.111252)
		(layer "F.Cu")
		(net "SW_HDD3_N")
	)
	(segment
		(start 195.58 -190.8175)
		(end 195.58 -189.484)
		(width 0.111252)
		(layer "F.Cu")
		(net "SW_HDD3_N")
	)
	(segment
		(start 193.4845 -192.5955)
		(end 193.4845 -191.77)
		(width 0.111252)
		(layer "F.Cu")
		(net "SW_HDD3_N")
	)
	(segment
		(start 196.498972 -188.565028)
		(end 197.280784 -188.565028)
		(width 0.111252)
		(layer "F.Cu")
		(net "SW_HDD3_N")
	)
	(segment
		(start 195.58 -189.484)
		(end 196.498972 -188.565028)
		(width 0.111252)
		(layer "F.Cu")
		(net "SW_HDD3_N")
	)
	(segment
		(start 194.564 -190.8175)
		(end 195.58 -190.8175)
		(width 0.111252)
		(layer "F.Cu")
		(net "SW_HDD3_N")
	)
	(segment
		(start 193.4845 -191.1985)
		(end 193.8655 -190.8175)
		(width 0.111252)
		(layer "F.Cu")
		(net "SW_HDD3_N")
	)
	(via
		(at 197.993 -186.944)
		(size 0.7112)
		(drill 0.3556)
		(layers "F.Cu" "B.Cu")
		(net "SW_HDD3_N")
	)
	(segment
		(start 24.498046 -395.605)
		(end 23.5585 -395.605)
		(width 0.111252)
		(layer "F.Cu")
		(net "I2C_B_SDA")
	)
	(segment
		(start 201.567288 -457.551536)
		(end 202.145646 -458.129894)
		(width 0.111252)
		(layer "F.Cu")
		(net "I2C_B_SDA")
	)
	(segment
		(start 26.784046 -245.8339)
		(end 26.060146 -245.11)
		(width 0.111252)
		(layer "F.Cu")
		(net "I2C_B_SDA")
	)
	(segment
		(start 180.65623 -463.524854)
		(end 180.809392 -463.678016)
		(width 0.111252)
		(layer "F.Cu")
		(net "I2C_B_SDA")
	)
	(segment
		(start 26.060146 -245.11)
		(end 25.146 -245.11)
		(width 0.111252)
		(layer "F.Cu")
		(net "I2C_B_SDA")
	)
	(segment
		(start 39.128446 -137.1727)
		(end 38.480746 -136.525)
		(width 0.111252)
		(layer "F.Cu")
		(net "I2C_B_SDA")
	)
	(segment
		(start 211.835746 -53.508148)
		(end 212.470746 -54.143148)
		(width 0.111252)
		(layer "F.Cu")
		(net "I2C_B_SDA")
	)
	(segment
		(start 211.728304 -54.719728)
		(end 211.878418 -54.719728)
		(width 0.111252)
		(layer "F.Cu")
		(net "I2C_B_SDA")
	)
	(segment
		(start 24.637746 -395.7447)
		(end 24.498046 -395.605)
		(width 0.111252)
		(layer "F.Cu")
		(net "I2C_B_SDA")
	)
	(segment
		(start 29.5148 -390.880092)
		(end 24.650192 -395.7447)
		(width 0.111252)
		(layer "F.Cu")
		(net "I2C_B_SDA")
	)
	(segment
		(start 24.650192 -395.7447)
		(end 24.637746 -395.7447)
		(width 0.111252)
		(layer "F.Cu")
		(net "I2C_B_SDA")
	)
	(segment
		(start 38.480746 -136.525)
		(end 37.846 -136.525)
		(width 0.111252)
		(layer "F.Cu")
		(net "I2C_B_SDA")
	)
	(segment
		(start 10.8966 -153.6319)
		(end 10.8966 -153.644346)
		(width 0.111252)
		(layer "F.Cu")
		(net "I2C_B_SDA")
	)
	(segment
		(start 200.481946 -457.361036)
		(end 200.672446 -457.551536)
		(width 0.111252)
		(layer "F.Cu")
		(net "I2C_B_SDA")
	)
	(segment
		(start 29.5148 -384.593846)
		(end 29.5148 -390.880092)
		(width 0.111252)
		(layer "F.Cu")
		(net "I2C_B_SDA")
	)
	(segment
		(start 211.878418 -54.719728)
		(end 212.454998 -54.143148)
		(width 0.111252)
		(layer "F.Cu")
		(net "I2C_B_SDA")
	)
	(segment
		(start 202.145646 -458.129894)
		(end 202.145646 -458.597)
		(width 0.111252)
		(layer "F.Cu")
		(net "I2C_B_SDA")
	)
	(segment
		(start 29.654246 -384.4544)
		(end 29.5148 -384.593846)
		(width 0.111252)
		(layer "F.Cu")
		(net "I2C_B_SDA")
	)
	(segment
		(start 211.835746 -52.9082)
		(end 211.835746 -53.508148)
		(width 0.111252)
		(layer "F.Cu")
		(net "I2C_B_SDA")
	)
	(segment
		(start 177.300128 -463.524854)
		(end 180.65623 -463.524854)
		(width 0.111252)
		(layer "F.Cu")
		(net "I2C_B_SDA")
	)
	(segment
		(start 200.672446 -457.551536)
		(end 201.567288 -457.551536)
		(width 0.111252)
		(layer "F.Cu")
		(net "I2C_B_SDA")
	)
	(segment
		(start 10.8966 -153.644346)
		(end 11.608054 -154.3558)
		(width 0.111252)
		(layer "F.Cu")
		(net "I2C_B_SDA")
	)
	(segment
		(start 206.692246 -463.6897)
		(end 204.810868 -463.6897)
		(width 0.111252)
		(layer "F.Cu")
		(net "I2C_B_SDA")
	)
	(segment
		(start 204.810868 -463.6897)
		(end 204.089 -462.967832)
		(width 0.111252)
		(layer "F.Cu")
		(net "I2C_B_SDA")
	)
	(segment
		(start 177.113946 -463.711036)
		(end 177.300128 -463.524854)
		(width 0.111252)
		(layer "F.Cu")
		(net "I2C_B_SDA")
	)
	(segment
		(start 212.454998 -54.143148)
		(end 212.470746 -54.143148)
		(width 0.111252)
		(layer "F.Cu")
		(net "I2C_B_SDA")
	)
	(via
		(at 25.146 -245.11)
		(size 0.5588)
		(drill 0.3048)
		(layers "F.Cu" "B.Cu")
		(net "I2C_B_SDA")
	)
	(via
		(at 26.924 -137.9728)
		(size 0.5588)
		(drill 0.3048)
		(layers "F.Cu" "B.Cu")
		(net "I2C_B_SDA")
	)
	(via
		(at 24.637746 -395.7447)
		(size 0.5588)
		(drill 0.3048)
		(layers "F.Cu" "B.Cu")
		(net "I2C_B_SDA")
	)
	(via
		(at 212.470746 -54.143148)
		(size 0.7112)
		(drill 0.3556)
		(layers "F.Cu" "B.Cu")
		(net "I2C_B_SDA")
	)
	(via
		(at 180.809392 -463.678016)
		(size 0.5588)
		(drill 0.3048)
		(layers "F.Cu" "B.Cu")
		(net "I2C_B_SDA")
	)
	(via
		(at 211.728304 -54.719728)
		(size 0.5588)
		(drill 0.3048)
		(layers "F.Cu" "B.Cu")
		(net "I2C_B_SDA")
	)
	(via
		(at 11.608054 -154.3558)
		(size 0.5588)
		(drill 0.3048)
		(layers "F.Cu" "B.Cu")
		(net "I2C_B_SDA")
	)
	(via
		(at 40.6908 -406.019)
		(size 0.5588)
		(drill 0.3048)
		(layers "F.Cu" "B.Cu")
		(net "I2C_B_SDA")
	)
	(via
		(at 204.089 -462.967832)
		(size 0.5588)
		(drill 0.3048)
		(layers "F.Cu" "B.Cu")
		(net "I2C_B_SDA")
	)
	(via
		(at 37.846 -136.525)
		(size 0.5588)
		(drill 0.3048)
		(layers "F.Cu" "B.Cu")
		(net "I2C_B_SDA")
	)
	(via
		(at 26.6954 -152.4)
		(size 0.5588)
		(drill 0.3048)
		(layers "F.Cu" "B.Cu")
		(net "I2C_B_SDA")
	)
	(via
		(at 202.145646 -458.597)
		(size 0.5588)
		(drill 0.3048)
		(layers "F.Cu" "B.Cu")
		(net "I2C_B_SDA")
	)
	(segment
		(start 202.145646 -458.597)
		(end 203.326746 -459.7781)
		(width 0.111252)
		(layer "B.Cu")
		(net "I2C_B_SDA")
	)
	(segment
		(start 37.846 -136.525)
		(end 28.3718 -136.525)
		(width 0.111252)
		(layer "B.Cu")
		(net "I2C_B_SDA")
	)
	(segment
		(start 203.326746 -462.205578)
		(end 204.089 -462.967832)
		(width 0.111252)
		(layer "B.Cu")
		(net "I2C_B_SDA")
	)
	(segment
		(start 180.809392 -463.678016)
		(end 188.184536 -463.678016)
		(width 0.111252)
		(layer "B.Cu")
		(net "I2C_B_SDA")
	)
	(segment
		(start 203.326746 -459.7781)
		(end 203.326746 -462.205578)
		(width 0.111252)
		(layer "B.Cu")
		(net "I2C_B_SDA")
	)
	(segment
		(start 188.184536 -463.678016)
		(end 193.265552 -458.597)
		(width 0.111252)
		(layer "B.Cu")
		(net "I2C_B_SDA")
	)
	(segment
		(start 28.3718 -136.525)
		(end 26.924 -137.9728)
		(width 0.111252)
		(layer "B.Cu")
		(net "I2C_B_SDA")
	)
	(segment
		(start 193.265552 -458.597)
		(end 202.145646 -458.597)
		(width 0.111252)
		(layer "B.Cu")
		(net "I2C_B_SDA")
	)
	(segment
		(start 28.3718 -249.164602)
		(end 28.3718 -267.1318)
		(width 0.14605)
		(layer "In2.Cu")
		(net "I2C_B_SDA")
	)
	(segment
		(start 38.5826 -137.760964)
		(end 38.085268 -137.760964)
		(width 0.14605)
		(layer "In2.Cu")
		(net "I2C_B_SDA")
	)
	(segment
		(start 211.728304 -54.719728)
		(end 210.935316 -55.512716)
		(width 0.14605)
		(layer "In2.Cu")
		(net "I2C_B_SDA")
	)
	(segment
		(start 210.935316 -55.512716)
		(end 38.5826 -137.760964)
		(width 0.14605)
		(layer "In2.Cu")
		(net "I2C_B_SDA")
	)
	(segment
		(start 26.9494 -356.361746)
		(end 21.951696 -361.35945)
		(width 0.14605)
		(layer "In2.Cu")
		(net "I2C_B_SDA")
	)
	(segment
		(start 24.892 -340.0044)
		(end 24.892 -346.123768)
		(width 0.14605)
		(layer "In2.Cu")
		(net "I2C_B_SDA")
	)
	(segment
		(start 24.892 -346.123768)
		(end 26.9494 -348.181168)
		(width 0.14605)
		(layer "In2.Cu")
		(net "I2C_B_SDA")
	)
	(segment
		(start 25.146 -245.11)
		(end 25.3746 -245.3386)
		(width 0.14605)
		(layer "In2.Cu")
		(net "I2C_B_SDA")
	)
	(segment
		(start 40.6908 -406.019)
		(end 180.809392 -463.678016)
		(width 0.14605)
		(layer "In2.Cu")
		(net "I2C_B_SDA")
	)
	(segment
		(start 36.576 -272.923)
		(end 36.576 -281.453336)
		(width 0.14605)
		(layer "In2.Cu")
		(net "I2C_B_SDA")
	)
	(segment
		(start 36.576 -281.453336)
		(end 24.1935 -293.835836)
		(width 0.14605)
		(layer "In2.Cu")
		(net "I2C_B_SDA")
	)
	(segment
		(start 26.9494 -348.181168)
		(end 26.9494 -356.361746)
		(width 0.14605)
		(layer "In2.Cu")
		(net "I2C_B_SDA")
	)
	(segment
		(start 21.951696 -361.35945)
		(end 21.951696 -393.05865)
		(width 0.14605)
		(layer "In2.Cu")
		(net "I2C_B_SDA")
	)
	(segment
		(start 35.814 -272.161)
		(end 36.576 -272.923)
		(width 0.14605)
		(layer "In2.Cu")
		(net "I2C_B_SDA")
	)
	(segment
		(start 25.3746 -246.167402)
		(end 28.3718 -249.164602)
		(width 0.14605)
		(layer "In2.Cu")
		(net "I2C_B_SDA")
	)
	(segment
		(start 24.1935 -293.835836)
		(end 24.1935 -339.3059)
		(width 0.14605)
		(layer "In2.Cu")
		(net "I2C_B_SDA")
	)
	(segment
		(start 21.951696 -393.05865)
		(end 24.637746 -395.7447)
		(width 0.14605)
		(layer "In2.Cu")
		(net "I2C_B_SDA")
	)
	(segment
		(start 37.7952 -136.5758)
		(end 37.846 -136.525)
		(width 0.14605)
		(layer "In2.Cu")
		(net "I2C_B_SDA")
	)
	(segment
		(start 23.622 -233.68)
		(end 23.622 -243.586)
		(width 0.14605)
		(layer "In2.Cu")
		(net "I2C_B_SDA")
	)
	(segment
		(start 37.7952 -137.470896)
		(end 37.7952 -136.5758)
		(width 0.14605)
		(layer "In2.Cu")
		(net "I2C_B_SDA")
	)
	(segment
		(start 24.1935 -339.3059)
		(end 24.892 -340.0044)
		(width 0.14605)
		(layer "In2.Cu")
		(net "I2C_B_SDA")
	)
	(segment
		(start 31.877 -272.161)
		(end 35.814 -272.161)
		(width 0.14605)
		(layer "In2.Cu")
		(net "I2C_B_SDA")
	)
	(segment
		(start 26.6954 -152.4)
		(end 26.340308 -152.755092)
		(width 0.14605)
		(layer "In2.Cu")
		(net "I2C_B_SDA")
	)
	(segment
		(start 23.622 -243.586)
		(end 25.146 -245.11)
		(width 0.14605)
		(layer "In2.Cu")
		(net "I2C_B_SDA")
	)
	(segment
		(start 30.988 -269.748)
		(end 30.988 -271.272)
		(width 0.14605)
		(layer "In2.Cu")
		(net "I2C_B_SDA")
	)
	(segment
		(start 25.3746 -245.3386)
		(end 25.3746 -246.167402)
		(width 0.14605)
		(layer "In2.Cu")
		(net "I2C_B_SDA")
	)
	(segment
		(start 28.3718 -267.1318)
		(end 30.988 -269.748)
		(width 0.14605)
		(layer "In2.Cu")
		(net "I2C_B_SDA")
	)
	(segment
		(start 26.340308 -152.755092)
		(end 26.340308 -230.961692)
		(width 0.14605)
		(layer "In2.Cu")
		(net "I2C_B_SDA")
	)
	(segment
		(start 26.340308 -230.961692)
		(end 23.622 -233.68)
		(width 0.14605)
		(layer "In2.Cu")
		(net "I2C_B_SDA")
	)
	(segment
		(start 30.988 -271.272)
		(end 31.877 -272.161)
		(width 0.14605)
		(layer "In2.Cu")
		(net "I2C_B_SDA")
	)
	(segment
		(start 38.085268 -137.760964)
		(end 37.7952 -137.470896)
		(width 0.14605)
		(layer "In2.Cu")
		(net "I2C_B_SDA")
	)
	(segment
		(start 26.642822 -152.347422)
		(end 26.6954 -152.4)
		(width 0.14605)
		(layer "In5.Cu")
		(net "I2C_B_SDA")
	)
	(segment
		(start 24.637746 -395.7447)
		(end 39.624 -406.019)
		(width 0.14605)
		(layer "In5.Cu")
		(net "I2C_B_SDA")
	)
	(segment
		(start 26.47315 -138.42365)
		(end 26.924 -137.9728)
		(width 0.14605)
		(layer "In5.Cu")
		(net "I2C_B_SDA")
	)
	(segment
		(start 26.6954 -152.2984)
		(end 26.47315 -152.07615)
		(width 0.14605)
		(layer "In5.Cu")
		(net "I2C_B_SDA")
	)
	(segment
		(start 11.608054 -154.3558)
		(end 17.917668 -154.3558)
		(width 0.14605)
		(layer "In5.Cu")
		(net "I2C_B_SDA")
	)
	(segment
		(start 26.47315 -152.07615)
		(end 26.47315 -138.42365)
		(width 0.14605)
		(layer "In5.Cu")
		(net "I2C_B_SDA")
	)
	(segment
		(start 39.624 -406.019)
		(end 40.6908 -406.019)
		(width 0.14605)
		(layer "In5.Cu")
		(net "I2C_B_SDA")
	)
	(segment
		(start 19.926046 -152.347422)
		(end 26.642822 -152.347422)
		(width 0.14605)
		(layer "In5.Cu")
		(net "I2C_B_SDA")
	)
	(segment
		(start 17.917668 -154.3558)
		(end 19.926046 -152.347422)
		(width 0.14605)
		(layer "In5.Cu")
		(net "I2C_B_SDA")
	)
	(segment
		(start 26.6954 -152.4)
		(end 26.6954 -152.2984)
		(width 0.14605)
		(layer "In5.Cu")
		(net "I2C_B_SDA")
	)
	(segment
		(start 194.818 -293.4335)
		(end 195.0085 -293.4335)
		(width 0.111252)
		(layer "F.Cu")
		(net "SW_HDD2_N")
	)
	(segment
		(start 197.315582 -290.548568)
		(end 196.750432 -290.548568)
		(width 0.111252)
		(layer "F.Cu")
		(net "SW_HDD2_N")
	)
	(segment
		(start 195.58 -292.862)
		(end 195.58 -292.354)
		(width 0.111252)
		(layer "F.Cu")
		(net "SW_HDD2_N")
	)
	(segment
		(start 195.58 -291.719)
		(end 195.58 -292.354)
		(width 0.111252)
		(layer "F.Cu")
		(net "SW_HDD2_N")
	)
	(segment
		(start 192.7225 -295.0591)
		(end 192.7225 -294.259)
		(width 0.111252)
		(layer "F.Cu")
		(net "SW_HDD2_N")
	)
	(segment
		(start 193.5226 -295.8592)
		(end 192.7225 -295.0591)
		(width 0.111252)
		(layer "F.Cu")
		(net "SW_HDD2_N")
	)
	(segment
		(start 192.7225 -294.259)
		(end 193.548 -293.4335)
		(width 0.111252)
		(layer "F.Cu")
		(net "SW_HDD2_N")
	)
	(segment
		(start 195.0085 -293.4335)
		(end 195.58 -292.862)
		(width 0.111252)
		(layer "F.Cu")
		(net "SW_HDD2_N")
	)
	(segment
		(start 193.548 -293.4335)
		(end 193.802 -293.4335)
		(width 0.111252)
		(layer "F.Cu")
		(net "SW_HDD2_N")
	)
	(segment
		(start 193.802 -293.4335)
		(end 194.818 -293.4335)
		(width 0.111252)
		(layer "F.Cu")
		(net "SW_HDD2_N")
	)
	(segment
		(start 196.750432 -290.548568)
		(end 195.58 -291.719)
		(width 0.111252)
		(layer "F.Cu")
		(net "SW_HDD2_N")
	)
	(via
		(at 195.58 -292.354)
		(size 0.7112)
		(drill 0.3556)
		(layers "F.Cu" "B.Cu")
		(net "SW_HDD2_N")
	)
	(segment
		(start 38.2905 -137.401554)
		(end 38.2905 -137.265664)
		(width 0.111252)
		(layer "F.Cu")
		(net "I2C_B_SCL")
	)
	(segment
		(start 210.692746 -52.9082)
		(end 210.692746 -53.710332)
		(width 0.111252)
		(layer "F.Cu")
		(net "I2C_B_SCL")
	)
	(segment
		(start 205.1685 -462.6737)
		(end 204.978 -462.8642)
		(width 0.111252)
		(layer "F.Cu")
		(net "I2C_B_SCL")
	)
	(segment
		(start 12.097004 -152.876504)
		(end 12.097004 -155.2702)
		(width 0.111252)
		(layer "F.Cu")
		(net "I2C_B_SCL")
	)
	(segment
		(start 39.128446 -138.2395)
		(end 38.2905 -137.401554)
		(width 0.111252)
		(layer "F.Cu")
		(net "I2C_B_SCL")
	)
	(segment
		(start 177.113946 -462.695036)
		(end 177.46091 -463.042)
		(width 0.111252)
		(layer "F.Cu")
		(net "I2C_B_SCL")
	)
	(segment
		(start 177.46091 -463.042)
		(end 180.533294 -463.042)
		(width 0.111252)
		(layer "F.Cu")
		(net "I2C_B_SCL")
	)
	(segment
		(start 200.824846 -458.034136)
		(end 201.367136 -458.034136)
		(width 0.111252)
		(layer "F.Cu")
		(net "I2C_B_SCL")
	)
	(segment
		(start 28.600146 -384.4544)
		(end 28.600146 -391.111994)
		(width 0.111252)
		(layer "F.Cu")
		(net "I2C_B_SCL")
	)
	(segment
		(start 206.692246 -462.6737)
		(end 205.1685 -462.6737)
		(width 0.111252)
		(layer "F.Cu")
		(net "I2C_B_SCL")
	)
	(segment
		(start 201.367136 -458.034136)
		(end 201.422 -458.089)
		(width 0.111252)
		(layer "F.Cu")
		(net "I2C_B_SCL")
	)
	(segment
		(start 210.798918 -54.9148)
		(end 210.254596 -54.370478)
		(width 0.111252)
		(layer "F.Cu")
		(net "I2C_B_SCL")
	)
	(segment
		(start 24.498046 -394.589)
		(end 23.5585 -394.589)
		(width 0.111252)
		(layer "F.Cu")
		(net "I2C_B_SCL")
	)
	(segment
		(start 28.600146 -391.111994)
		(end 24.85644 -394.8557)
		(width 0.111252)
		(layer "F.Cu")
		(net "I2C_B_SCL")
	)
	(segment
		(start 24.85644 -394.8557)
		(end 24.764746 -394.8557)
		(width 0.111252)
		(layer "F.Cu")
		(net "I2C_B_SCL")
	)
	(segment
		(start 25.9334 -246.634)
		(end 25.9334 -245.999)
		(width 0.111252)
		(layer "F.Cu")
		(net "I2C_B_SCL")
	)
	(segment
		(start 200.481946 -458.377036)
		(end 200.824846 -458.034136)
		(width 0.111252)
		(layer "F.Cu")
		(net "I2C_B_SCL")
	)
	(segment
		(start 180.533294 -463.042)
		(end 180.759608 -462.815686)
		(width 0.111252)
		(layer "F.Cu")
		(net "I2C_B_SCL")
	)
	(segment
		(start 210.254596 -54.370478)
		(end 210.254596 -54.148482)
		(width 0.111252)
		(layer "F.Cu")
		(net "I2C_B_SCL")
	)
	(segment
		(start 210.692746 -53.710332)
		(end 210.254596 -54.148482)
		(width 0.111252)
		(layer "F.Cu")
		(net "I2C_B_SCL")
	)
	(segment
		(start 10.9601 -151.7396)
		(end 12.097004 -152.876504)
		(width 0.111252)
		(layer "F.Cu")
		(net "I2C_B_SCL")
	)
	(segment
		(start 24.764746 -394.8557)
		(end 24.498046 -394.589)
		(width 0.111252)
		(layer "F.Cu")
		(net "I2C_B_SCL")
	)
	(segment
		(start 26.1874 -246.888)
		(end 25.9334 -246.634)
		(width 0.111252)
		(layer "F.Cu")
		(net "I2C_B_SCL")
	)
	(segment
		(start 26.797 -246.888)
		(end 26.1874 -246.888)
		(width 0.111252)
		(layer "F.Cu")
		(net "I2C_B_SCL")
	)
	(via
		(at 27.178 -153.6192)
		(size 0.5588)
		(drill 0.3048)
		(layers "F.Cu" "B.Cu")
		(net "I2C_B_SCL")
	)
	(via
		(at 210.254596 -54.148482)
		(size 0.7112)
		(drill 0.3556)
		(layers "F.Cu" "B.Cu")
		(net "I2C_B_SCL")
	)
	(via
		(at 39.9796 -405.5237)
		(size 0.5588)
		(drill 0.3048)
		(layers "F.Cu" "B.Cu")
		(net "I2C_B_SCL")
	)
	(via
		(at 12.097004 -155.2702)
		(size 0.5588)
		(drill 0.3048)
		(layers "F.Cu" "B.Cu")
		(net "I2C_B_SCL")
	)
	(via
		(at 201.422 -458.089)
		(size 0.5588)
		(drill 0.3048)
		(layers "F.Cu" "B.Cu")
		(net "I2C_B_SCL")
	)
	(via
		(at 25.9334 -245.999)
		(size 0.5588)
		(drill 0.3048)
		(layers "F.Cu" "B.Cu")
		(net "I2C_B_SCL")
	)
	(via
		(at 24.764746 -394.8557)
		(size 0.5588)
		(drill 0.3048)
		(layers "F.Cu" "B.Cu")
		(net "I2C_B_SCL")
	)
	(via
		(at 180.759608 -462.815686)
		(size 0.5588)
		(drill 0.3048)
		(layers "F.Cu" "B.Cu")
		(net "I2C_B_SCL")
	)
	(via
		(at 38.2905 -137.265664)
		(size 0.5588)
		(drill 0.3048)
		(layers "F.Cu" "B.Cu")
		(net "I2C_B_SCL")
	)
	(via
		(at 210.798918 -54.9148)
		(size 0.5588)
		(drill 0.3048)
		(layers "F.Cu" "B.Cu")
		(net "I2C_B_SCL")
	)
	(via
		(at 27.7876 -137.9728)
		(size 0.5588)
		(drill 0.3048)
		(layers "F.Cu" "B.Cu")
		(net "I2C_B_SCL")
	)
	(via
		(at 204.978 -462.8642)
		(size 0.5588)
		(drill 0.3048)
		(layers "F.Cu" "B.Cu")
		(net "I2C_B_SCL")
	)
	(segment
		(start 201.422 -458.089)
		(end 193.0908 -458.089)
		(width 0.111252)
		(layer "B.Cu")
		(net "I2C_B_SCL")
	)
	(segment
		(start 188.364114 -462.815686)
		(end 180.759608 -462.815686)
		(width 0.111252)
		(layer "B.Cu")
		(net "I2C_B_SCL")
	)
	(segment
		(start 38.2905 -137.265664)
		(end 28.494736 -137.265664)
		(width 0.111252)
		(layer "B.Cu")
		(net "I2C_B_SCL")
	)
	(segment
		(start 203.809346 -461.695546)
		(end 203.809346 -459.577948)
		(width 0.111252)
		(layer "B.Cu")
		(net "I2C_B_SCL")
	)
	(segment
		(start 204.978 -462.8642)
		(end 203.809346 -461.695546)
		(width 0.111252)
		(layer "B.Cu")
		(net "I2C_B_SCL")
	)
	(segment
		(start 28.494736 -137.265664)
		(end 27.7876 -137.9728)
		(width 0.111252)
		(layer "B.Cu")
		(net "I2C_B_SCL")
	)
	(segment
		(start 193.0908 -458.089)
		(end 188.364114 -462.815686)
		(width 0.111252)
		(layer "B.Cu")
		(net "I2C_B_SCL")
	)
	(segment
		(start 203.809346 -459.577948)
		(end 202.320398 -458.089)
		(width 0.111252)
		(layer "B.Cu")
		(net "I2C_B_SCL")
	)
	(segment
		(start 202.320398 -458.089)
		(end 201.422 -458.089)
		(width 0.111252)
		(layer "B.Cu")
		(net "I2C_B_SCL")
	)
	(segment
		(start 24.257 -234.188)
		(end 24.257 -243.332)
		(width 0.14605)
		(layer "In2.Cu")
		(net "I2C_B_SCL")
	)
	(segment
		(start 29.7942 -346.4052)
		(end 29.3116 -346.8878)
		(width 0.14605)
		(layer "In2.Cu")
		(net "I2C_B_SCL")
	)
	(segment
		(start 25.9334 -246.02567)
		(end 28.8671 -248.95937)
		(width 0.14605)
		(layer "In2.Cu")
		(net "I2C_B_SCL")
	)
	(segment
		(start 26.924 -231.521)
		(end 24.257 -234.188)
		(width 0.14605)
		(layer "In2.Cu")
		(net "I2C_B_SCL")
	)
	(segment
		(start 37.071554 -272.402554)
		(end 37.071554 -281.658568)
		(width 0.14605)
		(layer "In2.Cu")
		(net "I2C_B_SCL")
	)
	(segment
		(start 25.908 -245.9736)
		(end 25.9334 -245.999)
		(width 0.14605)
		(layer "In2.Cu")
		(net "I2C_B_SCL")
	)
	(segment
		(start 32.385 -271.526)
		(end 36.195 -271.526)
		(width 0.14605)
		(layer "In2.Cu")
		(net "I2C_B_SCL")
	)
	(segment
		(start 29.0068 -339.725)
		(end 29.7942 -340.5124)
		(width 0.14605)
		(layer "In2.Cu")
		(net "I2C_B_SCL")
	)
	(segment
		(start 27.178 -153.7716)
		(end 26.924 -154.0256)
		(width 0.14605)
		(layer "In2.Cu")
		(net "I2C_B_SCL")
	)
	(segment
		(start 26.924 -154.0256)
		(end 26.924 -231.521)
		(width 0.14605)
		(layer "In2.Cu")
		(net "I2C_B_SCL")
	)
	(segment
		(start 31.75 -269.748)
		(end 31.75 -270.891)
		(width 0.14605)
		(layer "In2.Cu")
		(net "I2C_B_SCL")
	)
	(segment
		(start 29.0068 -336.931)
		(end 29.0068 -339.725)
		(width 0.14605)
		(layer "In2.Cu")
		(net "I2C_B_SCL")
	)
	(segment
		(start 24.257 -243.332)
		(end 25.908 -244.983)
		(width 0.14605)
		(layer "In2.Cu")
		(net "I2C_B_SCL")
	)
	(segment
		(start 23.5458 -393.636754)
		(end 24.764746 -394.8557)
		(width 0.14605)
		(layer "In2.Cu")
		(net "I2C_B_SCL")
	)
	(segment
		(start 25.9334 -245.999)
		(end 25.9334 -246.02567)
		(width 0.14605)
		(layer "In2.Cu")
		(net "I2C_B_SCL")
	)
	(segment
		(start 28.8671 -266.8651)
		(end 31.75 -269.748)
		(width 0.14605)
		(layer "In2.Cu")
		(net "I2C_B_SCL")
	)
	(segment
		(start 41.148 -405.5237)
		(end 180.759608 -462.815686)
		(width 0.14605)
		(layer "In2.Cu")
		(net "I2C_B_SCL")
	)
	(segment
		(start 29.3116 -355.4984)
		(end 23.5458 -361.2642)
		(width 0.14605)
		(layer "In2.Cu")
		(net "I2C_B_SCL")
	)
	(segment
		(start 29.7942 -340.5124)
		(end 29.7942 -346.4052)
		(width 0.14605)
		(layer "In2.Cu")
		(net "I2C_B_SCL")
	)
	(segment
		(start 25.908 -244.983)
		(end 25.908 -245.9736)
		(width 0.14605)
		(layer "In2.Cu")
		(net "I2C_B_SCL")
	)
	(segment
		(start 27.178 -153.6192)
		(end 27.178 -153.7716)
		(width 0.14605)
		(layer "In2.Cu")
		(net "I2C_B_SCL")
	)
	(segment
		(start 38.2905 -137.265664)
		(end 210.798918 -54.9148)
		(width 0.14605)
		(layer "In2.Cu")
		(net "I2C_B_SCL")
	)
	(segment
		(start 23.5458 -361.2642)
		(end 23.5458 -393.636754)
		(width 0.14605)
		(layer "In2.Cu")
		(net "I2C_B_SCL")
	)
	(segment
		(start 39.9796 -405.5237)
		(end 41.148 -405.5237)
		(width 0.14605)
		(layer "In2.Cu")
		(net "I2C_B_SCL")
	)
	(segment
		(start 29.3116 -346.8878)
		(end 29.3116 -355.4984)
		(width 0.14605)
		(layer "In2.Cu")
		(net "I2C_B_SCL")
	)
	(segment
		(start 24.6888 -332.613)
		(end 29.0068 -336.931)
		(width 0.14605)
		(layer "In2.Cu")
		(net "I2C_B_SCL")
	)
	(segment
		(start 36.195 -271.526)
		(end 37.071554 -272.402554)
		(width 0.14605)
		(layer "In2.Cu")
		(net "I2C_B_SCL")
	)
	(segment
		(start 28.8671 -248.95937)
		(end 28.8671 -266.8651)
		(width 0.14605)
		(layer "In2.Cu")
		(net "I2C_B_SCL")
	)
	(segment
		(start 31.75 -270.891)
		(end 32.385 -271.526)
		(width 0.14605)
		(layer "In2.Cu")
		(net "I2C_B_SCL")
	)
	(segment
		(start 37.071554 -281.658568)
		(end 24.6888 -294.041322)
		(width 0.14605)
		(layer "In2.Cu")
		(net "I2C_B_SCL")
	)
	(segment
		(start 24.6888 -294.041322)
		(end 24.6888 -332.613)
		(width 0.14605)
		(layer "In2.Cu")
		(net "I2C_B_SCL")
	)
	(segment
		(start 26.924 -138.8364)
		(end 27.7876 -137.9728)
		(width 0.14605)
		(layer "In5.Cu")
		(net "I2C_B_SCL")
	)
	(segment
		(start 27.2542 -151.7904)
		(end 26.924 -151.4602)
		(width 0.14605)
		(layer "In5.Cu")
		(net "I2C_B_SCL")
	)
	(segment
		(start 27.178 -153.6192)
		(end 26.543 -152.9842)
		(width 0.14605)
		(layer "In5.Cu")
		(net "I2C_B_SCL")
	)
	(segment
		(start 12.452604 -154.9146)
		(end 12.097004 -155.2702)
		(width 0.14605)
		(layer "In5.Cu")
		(net "I2C_B_SCL")
	)
	(segment
		(start 27.2542 -153.543)
		(end 27.2542 -151.7904)
		(width 0.14605)
		(layer "In5.Cu")
		(net "I2C_B_SCL")
	)
	(segment
		(start 27.178 -153.6192)
		(end 27.2542 -153.543)
		(width 0.14605)
		(layer "In5.Cu")
		(net "I2C_B_SCL")
	)
	(segment
		(start 39.9796 -405.5237)
		(end 24.764746 -394.8557)
		(width 0.14605)
		(layer "In5.Cu")
		(net "I2C_B_SCL")
	)
	(segment
		(start 26.543 -152.9842)
		(end 19.9898 -152.9842)
		(width 0.14605)
		(layer "In5.Cu")
		(net "I2C_B_SCL")
	)
	(segment
		(start 19.9898 -152.9842)
		(end 18.0594 -154.9146)
		(width 0.14605)
		(layer "In5.Cu")
		(net "I2C_B_SCL")
	)
	(segment
		(start 26.924 -151.4602)
		(end 26.924 -138.8364)
		(width 0.14605)
		(layer "In5.Cu")
		(net "I2C_B_SCL")
	)
	(segment
		(start 18.0594 -154.9146)
		(end 12.452604 -154.9146)
		(width 0.14605)
		(layer "In5.Cu")
		(net "I2C_B_SCL")
	)
	(segment
		(start 28.0797 -351.991676)
		(end 19.3167 -360.754676)
		(width 0.111252)
		(layer "F.Cu")
		(net "FLT_NET_HDD11")
	)
	(segment
		(start 16.980662 -362.243116)
		(end 16.773144 -362.243116)
		(width 0.111252)
		(layer "F.Cu")
		(net "FLT_NET_HDD11")
	)
	(segment
		(start 30.734 -346.456)
		(end 30.734 -346.899738)
		(width 0.111252)
		(layer "F.Cu")
		(net "FLT_NET_HDD11")
	)
	(segment
		(start 16.773144 -362.243116)
		(end 16.769842 -362.246418)
		(width 0.111252)
		(layer "F.Cu")
		(net "FLT_NET_HDD11")
	)
	(segment
		(start 30.352746 -339.8647)
		(end 29.590746 -339.1027)
		(width 0.111252)
		(layer "F.Cu")
		(net "FLT_NET_HDD11")
	)
	(segment
		(start 28.0797 -349.554038)
		(end 28.0797 -351.991676)
		(width 0.111252)
		(layer "F.Cu")
		(net "FLT_NET_HDD11")
	)
	(segment
		(start 19.3167 -360.754676)
		(end 17.888966 -360.754676)
		(width 0.111252)
		(layer "F.Cu")
		(net "FLT_NET_HDD11")
	)
	(segment
		(start 17.888966 -360.754676)
		(end 17.5006 -361.143042)
		(width 0.111252)
		(layer "F.Cu")
		(net "FLT_NET_HDD11")
	)
	(segment
		(start 17.5006 -361.143042)
		(end 17.5006 -361.723178)
		(width 0.111252)
		(layer "F.Cu")
		(net "FLT_NET_HDD11")
	)
	(segment
		(start 30.543246 -341.1347)
		(end 30.352746 -340.9442)
		(width 0.111252)
		(layer "F.Cu")
		(net "FLT_NET_HDD11")
	)
	(segment
		(start 30.734 -346.899738)
		(end 28.0797 -349.554038)
		(width 0.111252)
		(layer "F.Cu")
		(net "FLT_NET_HDD11")
	)
	(segment
		(start 30.352746 -340.1187)
		(end 30.352746 -339.8647)
		(width 0.111252)
		(layer "F.Cu")
		(net "FLT_NET_HDD11")
	)
	(segment
		(start 17.5006 -361.723178)
		(end 16.980662 -362.243116)
		(width 0.111252)
		(layer "F.Cu")
		(net "FLT_NET_HDD11")
	)
	(segment
		(start 30.352746 -340.9442)
		(end 30.352746 -340.1187)
		(width 0.111252)
		(layer "F.Cu")
		(net "FLT_NET_HDD11")
	)
	(via
		(at 30.352746 -340.1187)
		(size 0.5588)
		(drill 0.3048)
		(layers "F.Cu" "B.Cu")
		(net "FLT_NET_HDD11")
	)
	(via
		(at 30.734 -346.456)
		(size 0.5588)
		(drill 0.3048)
		(layers "F.Cu" "B.Cu")
		(net "FLT_NET_HDD11")
	)
	(via
		(at 29.590746 -339.1027)
		(size 0.7112)
		(drill 0.3556)
		(layers "F.Cu" "B.Cu")
		(net "FLT_NET_HDD11")
	)
	(segment
		(start 30.609032 -346.456)
		(end 30.734 -346.456)
		(width 0.14605)
		(layer "In2.Cu")
		(net "FLT_NET_HDD11")
	)
	(segment
		(start 30.352746 -346.199714)
		(end 30.609032 -346.456)
		(width 0.14605)
		(layer "In2.Cu")
		(net "FLT_NET_HDD11")
	)
	(segment
		(start 30.352746 -340.1187)
		(end 30.352746 -346.199714)
		(width 0.14605)
		(layer "In2.Cu")
		(net "FLT_NET_HDD11")
	)
	(segment
		(start 197.028816 -393.394184)
		(end 195.707 -394.716)
		(width 0.111252)
		(layer "F.Cu")
		(net "SW_HDD1_N")
	)
	(segment
		(start 193.6115 -396.4305)
		(end 193.6115 -396.494)
		(width 0.111252)
		(layer "F.Cu")
		(net "SW_HDD1_N")
	)
	(segment
		(start 193.6115 -396.494)
		(end 193.6115 -397.7005)
		(width 0.111252)
		(layer "F.Cu")
		(net "SW_HDD1_N")
	)
	(segment
		(start 197.949058 -393.394184)
		(end 197.028816 -393.394184)
		(width 0.111252)
		(layer "F.Cu")
		(net "SW_HDD1_N")
	)
	(segment
		(start 194.691 -395.7955)
		(end 194.2465 -395.7955)
		(width 0.111252)
		(layer "F.Cu")
		(net "SW_HDD1_N")
	)
	(segment
		(start 193.6115 -397.7005)
		(end 194.183 -398.272)
		(width 0.111252)
		(layer "F.Cu")
		(net "SW_HDD1_N")
	)
	(segment
		(start 194.2465 -395.7955)
		(end 193.6115 -396.4305)
		(width 0.111252)
		(layer "F.Cu")
		(net "SW_HDD1_N")
	)
	(segment
		(start 195.707 -394.716)
		(end 195.707 -395.7955)
		(width 0.111252)
		(layer "F.Cu")
		(net "SW_HDD1_N")
	)
	(segment
		(start 195.707 -395.7955)
		(end 194.691 -395.7955)
		(width 0.111252)
		(layer "F.Cu")
		(net "SW_HDD1_N")
	)
	(via
		(at 195.707 -394.716)
		(size 0.7112)
		(drill 0.3556)
		(layers "F.Cu" "B.Cu")
		(net "SW_HDD1_N")
	)
	(segment
		(start 194.31 -498.0305)
		(end 193.2305 -499.11)
		(width 0.111252)
		(layer "F.Cu")
		(net "SW_HDD0_N")
	)
	(segment
		(start 195.453 -497.078)
		(end 195.453 -497.9035)
		(width 0.111252)
		(layer "F.Cu")
		(net "SW_HDD0_N")
	)
	(segment
		(start 196.033898 -496.497102)
		(end 195.58 -496.951)
		(width 0.111252)
		(layer "F.Cu")
		(net "SW_HDD0_N")
	)
	(segment
		(start 195.453 -497.9035)
		(end 195.326 -498.0305)
		(width 0.111252)
		(layer "F.Cu")
		(net "SW_HDD0_N")
	)
	(segment
		(start 193.2305 -499.11)
		(end 193.2305 -499.8085)
		(width 0.111252)
		(layer "F.Cu")
		(net "SW_HDD0_N")
	)
	(segment
		(start 195.58 -496.951)
		(end 195.453 -497.078)
		(width 0.111252)
		(layer "F.Cu")
		(net "SW_HDD0_N")
	)
	(segment
		(start 197.310756 -496.497102)
		(end 196.033898 -496.497102)
		(width 0.111252)
		(layer "F.Cu")
		(net "SW_HDD0_N")
	)
	(segment
		(start 195.326 -498.0305)
		(end 194.31 -498.0305)
		(width 0.111252)
		(layer "F.Cu")
		(net "SW_HDD0_N")
	)
	(segment
		(start 193.2305 -499.8085)
		(end 194.31 -500.888)
		(width 0.111252)
		(layer "F.Cu")
		(net "SW_HDD0_N")
	)
	(via
		(at 195.58 -496.951)
		(size 0.7112)
		(drill 0.3556)
		(layers "F.Cu" "B.Cu")
		(net "SW_HDD0_N")
	)
	(segment
		(start 230.711756 -453.545702)
		(end 230.711756 -452.529702)
		(width 0.111252)
		(layer "F.Cu")
		(net "DRIVE_ACT_0")
	)
	(segment
		(start 232.168446 -452.374)
		(end 232.409746 -452.6153)
		(width 0.111252)
		(layer "F.Cu")
		(net "DRIVE_ACT_0")
	)
	(segment
		(start 230.711756 -452.529702)
		(end 232.012744 -452.529702)
		(width 0.111252)
		(layer "F.Cu")
		(net "DRIVE_ACT_0")
	)
	(segment
		(start 232.409746 -452.6153)
		(end 232.409746 -455.041)
		(width 0.111252)
		(layer "F.Cu")
		(net "DRIVE_ACT_0")
	)
	(segment
		(start 232.012744 -452.529702)
		(end 232.168446 -452.374)
		(width 0.111252)
		(layer "F.Cu")
		(net "DRIVE_ACT_0")
	)
	(via
		(at 232.409746 -455.041)
		(size 0.7112)
		(drill 0.3556)
		(layers "F.Cu" "B.Cu")
		(net "DRIVE_ACT_0")
	)
	(segment
		(start 100.126546 -11.4427)
		(end 100.126546 -10.56894)
		(width 0.111252)
		(layer "F.Cu")
		(net "SW_HDD14_P")
	)
	(segment
		(start 93.091 -21.9075)
		(end 93.0148 -21.9837)
		(width 0.111252)
		(layer "F.Cu")
		(net "SW_HDD14_P")
	)
	(segment
		(start 98.932746 -6.6167)
		(end 99.186746 -6.8707)
		(width 0.111252)
		(layer "F.Cu")
		(net "SW_HDD14_P")
	)
	(segment
		(start 99.328986 -10.56894)
		(end 100.126546 -10.56894)
		(width 0.111252)
		(layer "F.Cu")
		(net "SW_HDD14_P")
	)
	(segment
		(start 94.4118 -21.717)
		(end 94.2213 -21.9075)
		(width 0.111252)
		(layer "F.Cu")
		(net "SW_HDD14_P")
	)
	(segment
		(start 94.2213 -21.9075)
		(end 93.091 -21.9075)
		(width 0.111252)
		(layer "F.Cu")
		(net "SW_HDD14_P")
	)
	(segment
		(start 98.234246 -6.6167)
		(end 98.932746 -6.6167)
		(width 0.111252)
		(layer "F.Cu")
		(net "SW_HDD14_P")
	)
	(segment
		(start 99.186746 -6.8707)
		(end 99.186746 -10.4267)
		(width 0.111252)
		(layer "F.Cu")
		(net "SW_HDD14_P")
	)
	(segment
		(start 99.186746 -10.4267)
		(end 99.328986 -10.56894)
		(width 0.111252)
		(layer "F.Cu")
		(net "SW_HDD14_P")
	)
	(segment
		(start 93.0148 -21.9837)
		(end 91.693746 -21.9837)
		(width 0.111252)
		(layer "F.Cu")
		(net "SW_HDD14_P")
	)
	(via
		(at 99.164394 -17.688052)
		(size 0.7112)
		(drill 0.3556)
		(layers "F.Cu" "B.Cu")
		(net "SW_HDD14_P")
	)
	(via
		(at 100.126546 -11.4427)
		(size 0.5588)
		(drill 0.3048)
		(layers "F.Cu" "B.Cu")
		(net "SW_HDD14_P")
	)
	(via
		(at 94.4118 -21.717)
		(size 0.5588)
		(drill 0.3048)
		(layers "F.Cu" "B.Cu")
		(net "SW_HDD14_P")
	)
	(segment
		(start 95.135446 -21.717)
		(end 99.164394 -17.688052)
		(width 0.111252)
		(layer "B.Cu")
		(net "SW_HDD14_P")
	)
	(segment
		(start 100.126546 -16.7259)
		(end 99.164394 -17.688052)
		(width 0.111252)
		(layer "B.Cu")
		(net "SW_HDD14_P")
	)
	(segment
		(start 94.4118 -21.717)
		(end 95.135446 -21.717)
		(width 0.111252)
		(layer "B.Cu")
		(net "SW_HDD14_P")
	)
	(segment
		(start 100.126546 -11.4427)
		(end 100.126546 -16.7259)
		(width 0.111252)
		(layer "B.Cu")
		(net "SW_HDD14_P")
	)
	(segment
		(start 16.045688 -463.94624)
		(end 15.358364 -464.633564)
		(width 0.111252)
		(layer "F.Cu")
		(net "FLT_NET_HDD10")
	)
	(segment
		(start 15.358364 -464.633564)
		(end 15.358364 -465.82965)
		(width 0.111252)
		(layer "F.Cu")
		(net "FLT_NET_HDD10")
	)
	(segment
		(start 17.409668 -464.948778)
		(end 17.409668 -464.053174)
		(width 0.111252)
		(layer "F.Cu")
		(net "FLT_NET_HDD10")
	)
	(segment
		(start 17.11198 -465.246466)
		(end 17.409668 -464.948778)
		(width 0.111252)
		(layer "F.Cu")
		(net "FLT_NET_HDD10")
	)
	(segment
		(start 19.621246 -469.484202)
		(end 19.621246 -469.6587)
		(width 0.111252)
		(layer "F.Cu")
		(net "FLT_NET_HDD10")
	)
	(segment
		(start 16.170148 -468.594948)
		(end 16.637 -469.0618)
		(width 0.111252)
		(layer "F.Cu")
		(net "FLT_NET_HDD10")
	)
	(segment
		(start 16.170148 -466.641434)
		(end 16.170148 -468.594948)
		(width 0.111252)
		(layer "F.Cu")
		(net "FLT_NET_HDD10")
	)
	(segment
		(start 17.409668 -464.053174)
		(end 17.302734 -463.94624)
		(width 0.111252)
		(layer "F.Cu")
		(net "FLT_NET_HDD10")
	)
	(segment
		(start 20.319746 -469.6587)
		(end 20.700746 -469.2777)
		(width 0.111252)
		(layer "F.Cu")
		(net "FLT_NET_HDD10")
	)
	(segment
		(start 16.637 -469.0618)
		(end 19.198844 -469.0618)
		(width 0.111252)
		(layer "F.Cu")
		(net "FLT_NET_HDD10")
	)
	(segment
		(start 17.302734 -463.94624)
		(end 16.045688 -463.94624)
		(width 0.111252)
		(layer "F.Cu")
		(net "FLT_NET_HDD10")
	)
	(segment
		(start 16.769842 -465.246466)
		(end 17.11198 -465.246466)
		(width 0.111252)
		(layer "F.Cu")
		(net "FLT_NET_HDD10")
	)
	(segment
		(start 15.358364 -465.82965)
		(end 16.170148 -466.641434)
		(width 0.111252)
		(layer "F.Cu")
		(net "FLT_NET_HDD10")
	)
	(segment
		(start 19.198844 -469.0618)
		(end 19.621246 -469.484202)
		(width 0.111252)
		(layer "F.Cu")
		(net "FLT_NET_HDD10")
	)
	(segment
		(start 19.621246 -469.6587)
		(end 20.319746 -469.6587)
		(width 0.111252)
		(layer "F.Cu")
		(net "FLT_NET_HDD10")
	)
	(via
		(at 20.700746 -469.2777)
		(size 0.7112)
		(drill 0.3556)
		(layers "F.Cu" "B.Cu")
		(net "FLT_NET_HDD10")
	)
	(segment
		(start 41.401746 -112.741202)
		(end 40.995346 -112.334802)
		(width 0.111252)
		(layer "F.Cu")
		(net "SW_HDD13_P")
	)
	(segment
		(start 53.9115 -130.3655)
		(end 54.7116 -131.1656)
		(width 0.111252)
		(layer "F.Cu")
		(net "SW_HDD13_P")
	)
	(segment
		(start 40.5384 -113.385346)
		(end 40.766746 -113.157)
		(width 0.111252)
		(layer "F.Cu")
		(net "SW_HDD13_P")
	)
	(segment
		(start 55.88 -131.1656)
		(end 54.7116 -131.1656)
		(width 0.111252)
		(layer "F.Cu")
		(net "SW_HDD13_P")
	)
	(segment
		(start 53.628798 -130.584702)
		(end 53.848 -130.3655)
		(width 0.111252)
		(layer "F.Cu")
		(net "SW_HDD13_P")
	)
	(segment
		(start 40.766746 -113.157)
		(end 40.779446 -113.157)
		(width 0.111252)
		(layer "F.Cu")
		(net "SW_HDD13_P")
	)
	(segment
		(start 53.848 -130.3655)
		(end 53.9115 -130.3655)
		(width 0.111252)
		(layer "F.Cu")
		(net "SW_HDD13_P")
	)
	(segment
		(start 40.995346 -112.334802)
		(end 40.995346 -110.440724)
		(width 0.111252)
		(layer "F.Cu")
		(net "SW_HDD13_P")
	)
	(segment
		(start 40.550084 -109.995462)
		(end 40.207946 -109.995462)
		(width 0.111252)
		(layer "F.Cu")
		(net "SW_HDD13_P")
	)
	(segment
		(start 52.450746 -130.584702)
		(end 53.628798 -130.584702)
		(width 0.111252)
		(layer "F.Cu")
		(net "SW_HDD13_P")
	)
	(segment
		(start 40.779446 -113.157)
		(end 41.195244 -112.741202)
		(width 0.111252)
		(layer "F.Cu")
		(net "SW_HDD13_P")
	)
	(segment
		(start 40.995346 -110.440724)
		(end 40.550084 -109.995462)
		(width 0.111252)
		(layer "F.Cu")
		(net "SW_HDD13_P")
	)
	(segment
		(start 41.195244 -112.741202)
		(end 41.401746 -112.741202)
		(width 0.111252)
		(layer "F.Cu")
		(net "SW_HDD13_P")
	)
	(via
		(at 40.5384 -113.385346)
		(size 0.5588)
		(drill 0.3048)
		(layers "F.Cu" "B.Cu")
		(net "SW_HDD13_P")
	)
	(via
		(at 55.88 -131.1656)
		(size 0.5588)
		(drill 0.3048)
		(layers "F.Cu" "B.Cu")
		(net "SW_HDD13_P")
	)
	(via
		(at 54.7116 -131.1656)
		(size 0.7112)
		(drill 0.3556)
		(layers "F.Cu" "B.Cu")
		(net "SW_HDD13_P")
	)
	(segment
		(start 54.101746 -126.948692)
		(end 54.101746 -130.209544)
		(width 0.14605)
		(layer "In5.Cu")
		(net "SW_HDD13_P")
	)
	(segment
		(start 54.101746 -130.209544)
		(end 55.057802 -131.1656)
		(width 0.14605)
		(layer "In5.Cu")
		(net "SW_HDD13_P")
	)
	(segment
		(start 55.057802 -131.1656)
		(end 55.88 -131.1656)
		(width 0.14605)
		(layer "In5.Cu")
		(net "SW_HDD13_P")
	)
	(segment
		(start 40.5384 -113.385346)
		(end 54.101746 -126.948692)
		(width 0.14605)
		(layer "In5.Cu")
		(net "SW_HDD13_P")
	)
	(segment
		(start 20.243546 -167.2209)
		(end 20.769834 -166.694612)
		(width 0.09525)
		(layer "F.Cu")
		(net "SAS2X28_B_HDD6_TX_-")
	)
	(segment
		(start 20.769834 -146.852894)
		(end 19.489166 -145.572226)
		(width 0.09525)
		(layer "F.Cu")
		(net "SAS2X28_B_HDD6_TX_-")
	)
	(segment
		(start 4.69265 -145.500344)
		(end 4.691126 -145.49882)
		(width 0.09525)
		(layer "F.Cu")
		(net "SAS2X28_B_HDD6_TX_-")
	)
	(segment
		(start 4.691126 -145.49882)
		(end 3.192526 -145.49882)
		(width 0.09525)
		(layer "F.Cu")
		(net "SAS2X28_B_HDD6_TX_-")
	)
	(segment
		(start 38.888924 -370.5479)
		(end 37.001704 -370.5479)
		(width 0.09525)
		(layer "F.Cu")
		(net "SAS2X28_B_HDD6_TX_-")
	)
	(segment
		(start 39.148766 -370.69268)
		(end 39.085266 -370.62918)
		(width 0.09525)
		(layer "F.Cu")
		(net "SAS2X28_B_HDD6_TX_-")
	)
	(segment
		(start 21.5138 -164.898578)
		(end 21.5138 -148.648928)
		(width 0.09525)
		(layer "F.Cu")
		(net "SAS2X28_B_HDD6_TX_-")
	)
	(segment
		(start 40.39997 -370.789962)
		(end 39.37889 -370.789962)
		(width 0.09525)
		(layer "F.Cu")
		(net "SAS2X28_B_HDD6_TX_-")
	)
	(segment
		(start 39.37889 -370.789962)
		(end 39.375588 -370.78666)
		(width 0.09525)
		(layer "F.Cu")
		(net "SAS2X28_B_HDD6_TX_-")
	)
	(segment
		(start 18.495772 -145.160746)
		(end 5.512562 -145.160746)
		(width 0.09525)
		(layer "F.Cu")
		(net "SAS2X28_B_HDD6_TX_-")
	)
	(segment
		(start 19.986498 -167.644826)
		(end 19.988276 -167.638984)
		(width 0.09525)
		(layer "F.Cu")
		(net "SAS2X28_B_HDD6_TX_-")
	)
	(via
		(at 19.557746 -168.7957)
		(size 0.5588)
		(drill 0.3048)
		(layers "F.Cu" "B.Cu")
		(net "SAS2X28_B_HDD6_TX_-")
	)
	(via
		(at 36.2966 -370.84)
		(size 0.5588)
		(drill 0.3048)
		(layers "F.Cu" "B.Cu")
		(net "SAS2X28_B_HDD6_TX_-")
	)
	(arc
		(start 19.859752 -168.319196)
		(mid 19.905835 -168.159948)
		(end 19.931126 -167.996108)
		(width 0.09525)
		(layer "F.Cu")
		(net "SAS2X28_B_HDD6_TX_-")
	)
	(arc
		(start 20.769834 -166.694612)
		(mid 21.320432 -165.870585)
		(end 21.5138 -164.898578)
		(width 0.09525)
		(layer "F.Cu")
		(net "SAS2X28_B_HDD6_TX_-")
	)
	(arc
		(start 19.931126 -167.996108)
		(mid 19.945068 -167.8183)
		(end 19.986498 -167.644826)
		(width 0.09525)
		(layer "F.Cu")
		(net "SAS2X28_B_HDD6_TX_-")
	)
	(arc
		(start 39.375588 -370.78666)
		(mid 39.252822 -370.76224)
		(end 39.148766 -370.69268)
		(width 0.09525)
		(layer "F.Cu")
		(net "SAS2X28_B_HDD6_TX_-")
	)
	(arc
		(start 5.512562 -145.160746)
		(mid 5.350916 -145.192899)
		(end 5.213858 -145.284444)
		(width 0.09525)
		(layer "F.Cu")
		(net "SAS2X28_B_HDD6_TX_-")
	)
	(arc
		(start 19.489166 -145.572226)
		(mid 19.033393 -145.267688)
		(end 18.495772 -145.160746)
		(width 0.09525)
		(layer "F.Cu")
		(net "SAS2X28_B_HDD6_TX_-")
	)
	(arc
		(start 37.001704 -370.5479)
		(mid 36.620091 -370.623808)
		(end 36.2966 -370.84)
		(width 0.09525)
		(layer "F.Cu")
		(net "SAS2X28_B_HDD6_TX_-")
	)
	(arc
		(start 19.557746 -168.7957)
		(mid 19.735046 -168.574118)
		(end 19.859752 -168.319196)
		(width 0.09525)
		(layer "F.Cu")
		(net "SAS2X28_B_HDD6_TX_-")
	)
	(arc
		(start 39.04234 -370.594128)
		(mid 38.96904 -370.559701)
		(end 38.888924 -370.5479)
		(width 0.09525)
		(layer "F.Cu")
		(net "SAS2X28_B_HDD6_TX_-")
	)
	(arc
		(start 39.085266 -370.62918)
		(mid 39.06468 -370.61058)
		(end 39.04234 -370.594128)
		(width 0.09525)
		(layer "F.Cu")
		(net "SAS2X28_B_HDD6_TX_-")
	)
	(arc
		(start 20.004786 -167.59174)
		(mid 20.104304 -167.393533)
		(end 20.243546 -167.2209)
		(width 0.09525)
		(layer "F.Cu")
		(net "SAS2X28_B_HDD6_TX_-")
	)
	(arc
		(start 21.5138 -148.648928)
		(mid 21.320454 -147.676912)
		(end 20.769834 -146.852894)
		(width 0.09525)
		(layer "F.Cu")
		(net "SAS2X28_B_HDD6_TX_-")
	)
	(arc
		(start 5.213858 -145.284444)
		(mid 4.974726 -145.444227)
		(end 4.69265 -145.500344)
		(width 0.09525)
		(layer "F.Cu")
		(net "SAS2X28_B_HDD6_TX_-")
	)
	(arc
		(start 19.988276 -167.638984)
		(mid 19.996246 -167.615262)
		(end 20.004786 -167.59174)
		(width 0.09525)
		(layer "F.Cu")
		(net "SAS2X28_B_HDD6_TX_-")
	)
	(segment
		(start 19.908266 -170.16222)
		(end 19.913346 -170.1673)
		(width 0.09525)
		(layer "B.Cu")
		(net "SAS2X28_B_HDD6_TX_-")
	)
	(segment
		(start 19.677634 -169.08526)
		(end 19.677634 -169.634154)
		(width 0.09525)
		(layer "B.Cu")
		(net "SAS2X28_B_HDD6_TX_-")
	)
	(segment
		(start 21.31441 -171.2087)
		(end 22.975824 -171.2087)
		(width 0.09525)
		(layer "B.Cu")
		(net "SAS2X28_B_HDD6_TX_-")
	)
	(segment
		(start 37.985954 -195.325492)
		(end 48.158654 -205.498192)
		(width 0.09525)
		(layer "B.Cu")
		(net "SAS2X28_B_HDD6_TX_-")
	)
	(segment
		(start 37.477954 -185.98134)
		(end 37.477954 -194.09918)
		(width 0.09525)
		(layer "B.Cu")
		(net "SAS2X28_B_HDD6_TX_-")
	)
	(segment
		(start 48.252888 -299.37075)
		(end 43.058842 -304.564796)
		(width 0.09525)
		(layer "B.Cu")
		(net "SAS2X28_B_HDD6_TX_-")
	)
	(segment
		(start 34.5821 -368.655346)
		(end 34.581846 -368.6556)
		(width 0.09525)
		(layer "B.Cu")
		(net "SAS2X28_B_HDD6_TX_-")
	)
	(segment
		(start 42.243248 -350.434656)
		(end 35.169602 -357.508302)
		(width 0.09525)
		(layer "B.Cu")
		(net "SAS2X28_B_HDD6_TX_-")
	)
	(segment
		(start 48.539146 -206.416148)
		(end 48.539146 -298.67987)
		(width 0.09525)
		(layer "B.Cu")
		(net "SAS2X28_B_HDD6_TX_-")
	)
	(segment
		(start 37.985954 -195.325238)
		(end 37.985954 -195.325492)
		(width 0.09525)
		(layer "B.Cu")
		(net "SAS2X28_B_HDD6_TX_-")
	)
	(segment
		(start 34.581846 -358.9274)
		(end 34.581846 -367.4618)
		(width 0.09525)
		(layer "B.Cu")
		(net "SAS2X28_B_HDD6_TX_-")
	)
	(segment
		(start 32.996632 -181.311804)
		(end 33.198816 -181.513988)
		(width 0.09525)
		(layer "B.Cu")
		(net "SAS2X28_B_HDD6_TX_-")
	)
	(segment
		(start 33.69183 -181.678326)
		(end 37.112448 -185.098944)
		(width 0.09525)
		(layer "B.Cu")
		(net "SAS2X28_B_HDD6_TX_-")
	)
	(segment
		(start 34.85642 -370.03228)
		(end 35.008566 -370.184426)
		(width 0.09525)
		(layer "B.Cu")
		(net "SAS2X28_B_HDD6_TX_-")
	)
	(segment
		(start 34.5821 -367.462054)
		(end 34.5821 -368.655346)
		(width 0.09525)
		(layer "B.Cu")
		(net "SAS2X28_B_HDD6_TX_-")
	)
	(segment
		(start 48.158654 -205.498192)
		(end 48.158654 -205.498446)
		(width 0.09525)
		(layer "B.Cu")
		(net "SAS2X28_B_HDD6_TX_-")
	)
	(segment
		(start 19.913346 -170.1673)
		(end 20.700492 -170.9547)
		(width 0.09525)
		(layer "B.Cu")
		(net "SAS2X28_B_HDD6_TX_-")
	)
	(segment
		(start 34.581846 -368.6556)
		(end 34.581846 -369.36934)
		(width 0.09525)
		(layer "B.Cu")
		(net "SAS2X28_B_HDD6_TX_-")
	)
	(segment
		(start 23.396448 -171.382944)
		(end 32.832294 -180.81879)
		(width 0.09525)
		(layer "B.Cu")
		(net "SAS2X28_B_HDD6_TX_-")
	)
	(segment
		(start 42.544746 -305.806094)
		(end 42.544746 -349.706692)
		(width 0.09525)
		(layer "B.Cu")
		(net "SAS2X28_B_HDD6_TX_-")
	)
	(segment
		(start 35.70224 -370.4717)
		(end 35.9283 -370.4717)
		(width 0.09525)
		(layer "B.Cu")
		(net "SAS2X28_B_HDD6_TX_-")
	)
	(segment
		(start 34.581846 -367.4618)
		(end 34.5821 -367.462054)
		(width 0.09525)
		(layer "B.Cu")
		(net "SAS2X28_B_HDD6_TX_-")
	)
	(arc
		(start 37.112448 -185.098944)
		(mid 37.382958 -185.503791)
		(end 37.477954 -185.98134)
		(width 0.09525)
		(layer "B.Cu")
		(net "SAS2X28_B_HDD6_TX_-")
	)
	(arc
		(start 48.539146 -298.67987)
		(mid 48.464736 -299.053776)
		(end 48.252888 -299.37075)
		(width 0.09525)
		(layer "B.Cu")
		(net "SAS2X28_B_HDD6_TX_-")
	)
	(arc
		(start 33.198816 -181.513988)
		(mid 33.312041 -181.584947)
		(end 33.445196 -181.59603)
		(width 0.09525)
		(layer "B.Cu")
		(net "SAS2X28_B_HDD6_TX_-")
	)
	(arc
		(start 32.832294 -180.81879)
		(mid 32.903391 -180.932109)
		(end 32.91459 -181.065424)
		(width 0.09525)
		(layer "B.Cu")
		(net "SAS2X28_B_HDD6_TX_-")
	)
	(arc
		(start 19.557746 -168.7957)
		(mid 19.646514 -168.928551)
		(end 19.677634 -169.08526)
		(width 0.09525)
		(layer "B.Cu")
		(net "SAS2X28_B_HDD6_TX_-")
	)
	(arc
		(start 35.008566 -370.184426)
		(mid 35.326827 -370.397051)
		(end 35.70224 -370.4717)
		(width 0.09525)
		(layer "B.Cu")
		(net "SAS2X28_B_HDD6_TX_-")
	)
	(arc
		(start 19.677634 -169.634154)
		(mid 19.743116 -169.919946)
		(end 19.908266 -170.16222)
		(width 0.09525)
		(layer "B.Cu")
		(net "SAS2X28_B_HDD6_TX_-")
	)
	(arc
		(start 37.477954 -194.09918)
		(mid 37.610034 -194.762722)
		(end 37.985954 -195.325238)
		(width 0.09525)
		(layer "B.Cu")
		(net "SAS2X28_B_HDD6_TX_-")
	)
	(arc
		(start 35.169602 -357.508302)
		(mid 34.734588 -358.15939)
		(end 34.581846 -358.9274)
		(width 0.09525)
		(layer "B.Cu")
		(net "SAS2X28_B_HDD6_TX_-")
	)
	(arc
		(start 34.581846 -369.36934)
		(mid 34.653225 -369.728097)
		(end 34.85642 -370.03228)
		(width 0.09525)
		(layer "B.Cu")
		(net "SAS2X28_B_HDD6_TX_-")
	)
	(arc
		(start 42.544746 -349.706692)
		(mid 42.466383 -350.10065)
		(end 42.243248 -350.434656)
		(width 0.09525)
		(layer "B.Cu")
		(net "SAS2X28_B_HDD6_TX_-")
	)
	(arc
		(start 20.700492 -170.9547)
		(mid 20.982189 -171.142768)
		(end 21.31441 -171.2087)
		(width 0.09525)
		(layer "B.Cu")
		(net "SAS2X28_B_HDD6_TX_-")
	)
	(arc
		(start 22.975824 -171.2087)
		(mid 23.20347 -171.253982)
		(end 23.396448 -171.382944)
		(width 0.09525)
		(layer "B.Cu")
		(net "SAS2X28_B_HDD6_TX_-")
	)
	(arc
		(start 32.91459 -181.065424)
		(mid 32.925699 -181.198579)
		(end 32.996632 -181.311804)
		(width 0.09525)
		(layer "B.Cu")
		(net "SAS2X28_B_HDD6_TX_-")
	)
	(arc
		(start 35.9283 -370.4717)
		(mid 36.188727 -370.579573)
		(end 36.2966 -370.84)
		(width 0.09525)
		(layer "B.Cu")
		(net "SAS2X28_B_HDD6_TX_-")
	)
	(arc
		(start 33.445196 -181.59603)
		(mid 33.578522 -181.607196)
		(end 33.69183 -181.678326)
		(width 0.09525)
		(layer "B.Cu")
		(net "SAS2X28_B_HDD6_TX_-")
	)
	(arc
		(start 43.058842 -304.564796)
		(mid 42.678335 -305.134309)
		(end 42.544746 -305.806094)
		(width 0.09525)
		(layer "B.Cu")
		(net "SAS2X28_B_HDD6_TX_-")
	)
	(arc
		(start 48.158654 -205.498446)
		(mid 48.440153 -205.919461)
		(end 48.539146 -206.416148)
		(width 0.09525)
		(layer "B.Cu")
		(net "SAS2X28_B_HDD6_TX_-")
	)
	(segment
		(start 59.944 -230.6955)
		(end 58.835798 -231.803702)
		(width 0.111252)
		(layer "F.Cu")
		(net "SW_HDD12_P")
	)
	(segment
		(start 47.2694 -212.697314)
		(end 47.370746 -212.79866)
		(width 0.111252)
		(layer "F.Cu")
		(net "SW_HDD12_P")
	)
	(segment
		(start 47.370746 -213.833202)
		(end 47.243746 -213.960202)
		(width 0.111252)
		(layer "F.Cu")
		(net "SW_HDD12_P")
	)
	(segment
		(start 47.2694 -210.972146)
		(end 47.2694 -212.697314)
		(width 0.111252)
		(layer "F.Cu")
		(net "SW_HDD12_P")
	)
	(segment
		(start 60.324746 -230.314754)
		(end 59.944 -230.6955)
		(width 0.111252)
		(layer "F.Cu")
		(net "SW_HDD12_P")
	)
	(segment
		(start 46.867572 -211.58581)
		(end 46.867572 -212.793834)
		(width 0.111252)
		(layer "F.Cu")
		(net "SW_HDD12_P")
	)
	(segment
		(start 46.867572 -212.793834)
		(end 46.863508 -212.797898)
		(width 0.111252)
		(layer "F.Cu")
		(net "SW_HDD12_P")
	)
	(segment
		(start 47.370746 -210.8708)
		(end 47.2694 -210.972146)
		(width 0.111252)
		(layer "F.Cu")
		(net "SW_HDD12_P")
	)
	(segment
		(start 46.496224 -211.214462)
		(end 46.867572 -211.58581)
		(width 0.111252)
		(layer "F.Cu")
		(net "SW_HDD12_P")
	)
	(segment
		(start 47.370746 -206.756254)
		(end 47.370746 -210.8708)
		(width 0.111252)
		(layer "F.Cu")
		(net "SW_HDD12_P")
	)
	(segment
		(start 60.324746 -210.184746)
		(end 55.499 -205.359)
		(width 0.111252)
		(layer "F.Cu")
		(net "SW_HDD12_P")
	)
	(segment
		(start 60.324746 -228.6127)
		(end 60.324746 -230.314754)
		(width 0.111252)
		(layer "F.Cu")
		(net "SW_HDD12_P")
	)
	(segment
		(start 46.176946 -211.214462)
		(end 46.496224 -211.214462)
		(width 0.111252)
		(layer "F.Cu")
		(net "SW_HDD12_P")
	)
	(segment
		(start 55.499 -205.359)
		(end 48.768 -205.359)
		(width 0.111252)
		(layer "F.Cu")
		(net "SW_HDD12_P")
	)
	(segment
		(start 58.835798 -231.803702)
		(end 58.419746 -231.803702)
		(width 0.111252)
		(layer "F.Cu")
		(net "SW_HDD12_P")
	)
	(segment
		(start 46.863508 -213.579964)
		(end 47.243746 -213.960202)
		(width 0.111252)
		(layer "F.Cu")
		(net "SW_HDD12_P")
	)
	(segment
		(start 60.324746 -228.6127)
		(end 60.324746 -210.184746)
		(width 0.111252)
		(layer "F.Cu")
		(net "SW_HDD12_P")
	)
	(segment
		(start 48.768 -205.359)
		(end 47.370746 -206.756254)
		(width 0.111252)
		(layer "F.Cu")
		(net "SW_HDD12_P")
	)
	(segment
		(start 46.863508 -212.797898)
		(end 46.863508 -213.579964)
		(width 0.111252)
		(layer "F.Cu")
		(net "SW_HDD12_P")
	)
	(segment
		(start 47.370746 -212.79866)
		(end 47.370746 -213.833202)
		(width 0.111252)
		(layer "F.Cu")
		(net "SW_HDD12_P")
	)
	(via
		(at 60.324746 -228.6127)
		(size 0.7112)
		(drill 0.3556)
		(layers "F.Cu" "B.Cu")
		(net "SW_HDD12_P")
	)
	(segment
		(start 202.120246 -288.8107)
		(end 201.866246 -289.0647)
		(width 0.111252)
		(layer "F.Cu")
		(net "SAS2X28_A_HDD2_FLT")
	)
	(segment
		(start 6.445504 -389.500364)
		(end 3.19405 -389.500364)
		(width 0.111252)
		(layer "F.Cu")
		(net "SAS2X28_A_HDD2_FLT")
	)
	(segment
		(start 3.19405 -389.500364)
		(end 3.192526 -389.49884)
		(width 0.111252)
		(layer "F.Cu")
		(net "SAS2X28_A_HDD2_FLT")
	)
	(segment
		(start 199.897746 -288.4297)
		(end 199.897746 -287.4772)
		(width 0.111252)
		(layer "F.Cu")
		(net "SAS2X28_A_HDD2_FLT")
	)
	(segment
		(start 201.866246 -289.0647)
		(end 200.532746 -289.0647)
		(width 0.111252)
		(layer "F.Cu")
		(net "SAS2X28_A_HDD2_FLT")
	)
	(segment
		(start 6.78307 -389.83793)
		(end 6.445504 -389.500364)
		(width 0.111252)
		(layer "F.Cu")
		(net "SAS2X28_A_HDD2_FLT")
	)
	(segment
		(start 200.532746 -289.0647)
		(end 199.897746 -288.4297)
		(width 0.111252)
		(layer "F.Cu")
		(net "SAS2X28_A_HDD2_FLT")
	)
	(via
		(at 200.532746 -289.0647)
		(size 0.5588)
		(drill 0.3048)
		(layers "F.Cu" "B.Cu")
		(net "SAS2X28_A_HDD2_FLT")
	)
	(via
		(at 6.78307 -389.83793)
		(size 0.5588)
		(drill 0.3048)
		(layers "F.Cu" "B.Cu")
		(net "SAS2X28_A_HDD2_FLT")
	)
	(via
		(at 200.368916 -290.227004)
		(size 0.7112)
		(drill 0.3556)
		(layers "F.Cu" "B.Cu")
		(net "SAS2X28_A_HDD2_FLT")
	)
	(segment
		(start 200.532746 -289.0647)
		(end 200.368916 -289.287204)
		(width 0.111252)
		(layer "B.Cu")
		(net "SAS2X28_A_HDD2_FLT")
	)
	(segment
		(start 200.368916 -289.287204)
		(end 200.368916 -290.227004)
		(width 0.111252)
		(layer "B.Cu")
		(net "SAS2X28_A_HDD2_FLT")
	)
	(segment
		(start 7.88035 -445.120268)
		(end 7.88035 -442.989208)
		(width 0.14605)
		(layer "In5.Cu")
		(net "SAS2X28_A_HDD2_FLT")
	)
	(segment
		(start 18.560288 -464.787234)
		(end 14.490446 -460.717392)
		(width 0.14605)
		(layer "In5.Cu")
		(net "SAS2X28_A_HDD2_FLT")
	)
	(segment
		(start 14.490446 -460.717392)
		(end 14.490446 -450.146166)
		(width 0.14605)
		(layer "In5.Cu")
		(net "SAS2X28_A_HDD2_FLT")
	)
	(segment
		(start 7.88035 -442.989208)
		(end 7.032498 -442.141356)
		(width 0.14605)
		(layer "In5.Cu")
		(net "SAS2X28_A_HDD2_FLT")
	)
	(segment
		(start 195.36283 -340.665816)
		(end 218.62161 -363.924596)
		(width 0.14605)
		(layer "In5.Cu")
		(net "SAS2X28_A_HDD2_FLT")
	)
	(segment
		(start 14.490446 -450.146166)
		(end 12.22248 -447.8782)
		(width 0.14605)
		(layer "In5.Cu")
		(net "SAS2X28_A_HDD2_FLT")
	)
	(segment
		(start 12.38504 -401.05711)
		(end 12.639802 -400.802348)
		(width 0.14605)
		(layer "In5.Cu")
		(net "SAS2X28_A_HDD2_FLT")
	)
	(segment
		(start 195.36283 -287.206436)
		(end 195.36283 -340.665816)
		(width 0.14605)
		(layer "In5.Cu")
		(net "SAS2X28_A_HDD2_FLT")
	)
	(segment
		(start 199.048878 -289.163252)
		(end 196.438774 -286.553148)
		(width 0.14605)
		(layer "In5.Cu")
		(net "SAS2X28_A_HDD2_FLT")
	)
	(segment
		(start 7.032498 -442.141356)
		(end 7.032498 -435.908958)
		(width 0.14605)
		(layer "In5.Cu")
		(net "SAS2X28_A_HDD2_FLT")
	)
	(segment
		(start 218.62161 -363.924596)
		(end 218.62161 -380.759462)
		(width 0.14605)
		(layer "In5.Cu")
		(net "SAS2X28_A_HDD2_FLT")
	)
	(segment
		(start 10.564876 -396.005812)
		(end 9.023096 -394.464032)
		(width 0.14605)
		(layer "In5.Cu")
		(net "SAS2X28_A_HDD2_FLT")
	)
	(segment
		(start 12.38504 -430.556416)
		(end 12.38504 -401.05711)
		(width 0.14605)
		(layer "In5.Cu")
		(net "SAS2X28_A_HDD2_FLT")
	)
	(segment
		(start 7.032498 -435.908958)
		(end 12.38504 -430.556416)
		(width 0.14605)
		(layer "In5.Cu")
		(net "SAS2X28_A_HDD2_FLT")
	)
	(segment
		(start 217.449654 -385.129786)
		(end 137.79246 -464.787234)
		(width 0.14605)
		(layer "In5.Cu")
		(net "SAS2X28_A_HDD2_FLT")
	)
	(segment
		(start 196.438774 -286.553148)
		(end 196.016118 -286.553148)
		(width 0.14605)
		(layer "In5.Cu")
		(net "SAS2X28_A_HDD2_FLT")
	)
	(segment
		(start 10.638282 -447.8782)
		(end 7.88035 -445.120268)
		(width 0.14605)
		(layer "In5.Cu")
		(net "SAS2X28_A_HDD2_FLT")
	)
	(segment
		(start 200.434194 -289.163252)
		(end 199.048878 -289.163252)
		(width 0.14605)
		(layer "In5.Cu")
		(net "SAS2X28_A_HDD2_FLT")
	)
	(segment
		(start 9.023096 -392.077956)
		(end 6.78307 -389.83793)
		(width 0.14605)
		(layer "In5.Cu")
		(net "SAS2X28_A_HDD2_FLT")
	)
	(segment
		(start 12.639802 -397.807434)
		(end 10.83818 -396.005812)
		(width 0.14605)
		(layer "In5.Cu")
		(net "SAS2X28_A_HDD2_FLT")
	)
	(segment
		(start 218.62161 -380.759462)
		(end 218.449144 -380.931928)
		(width 0.14605)
		(layer "In5.Cu")
		(net "SAS2X28_A_HDD2_FLT")
	)
	(segment
		(start 196.016118 -286.553148)
		(end 195.36283 -287.206436)
		(width 0.14605)
		(layer "In5.Cu")
		(net "SAS2X28_A_HDD2_FLT")
	)
	(segment
		(start 12.22248 -447.8782)
		(end 10.638282 -447.8782)
		(width 0.14605)
		(layer "In5.Cu")
		(net "SAS2X28_A_HDD2_FLT")
	)
	(segment
		(start 10.83818 -396.005812)
		(end 10.564876 -396.005812)
		(width 0.14605)
		(layer "In5.Cu")
		(net "SAS2X28_A_HDD2_FLT")
	)
	(segment
		(start 218.449144 -380.931928)
		(end 218.449144 -384.130296)
		(width 0.14605)
		(layer "In5.Cu")
		(net "SAS2X28_A_HDD2_FLT")
	)
	(segment
		(start 9.023096 -394.464032)
		(end 9.023096 -392.077956)
		(width 0.14605)
		(layer "In5.Cu")
		(net "SAS2X28_A_HDD2_FLT")
	)
	(segment
		(start 12.639802 -400.802348)
		(end 12.639802 -397.807434)
		(width 0.14605)
		(layer "In5.Cu")
		(net "SAS2X28_A_HDD2_FLT")
	)
	(segment
		(start 137.79246 -464.787234)
		(end 18.560288 -464.787234)
		(width 0.14605)
		(layer "In5.Cu")
		(net "SAS2X28_A_HDD2_FLT")
	)
	(segment
		(start 200.532746 -289.0647)
		(end 200.434194 -289.163252)
		(width 0.14605)
		(layer "In5.Cu")
		(net "SAS2X28_A_HDD2_FLT")
	)
	(segment
		(start 218.449144 -384.130296)
		(end 217.449654 -385.129786)
		(width 0.14605)
		(layer "In5.Cu")
		(net "SAS2X28_A_HDD2_FLT")
	)
	(segment
		(start 32.008572 -308.72049)
		(end 32.008572 -308.61381)
		(width 0.111252)
		(layer "F.Cu")
		(net "SW_HDD11_P")
	)
	(segment
		(start 32.19704 -310.988202)
		(end 32.384746 -310.988202)
		(width 0.111252)
		(layer "F.Cu")
		(net "SW_HDD11_P")
	)
	(segment
		(start 31.48838 -310.279542)
		(end 32.19704 -310.988202)
		(width 0.111252)
		(layer "F.Cu")
		(net "SW_HDD11_P")
	)
	(segment
		(start 32.384746 -309.096664)
		(end 32.008572 -308.72049)
		(width 0.111252)
		(layer "F.Cu")
		(net "SW_HDD11_P")
	)
	(segment
		(start 32.008572 -308.61381)
		(end 31.637224 -308.242462)
		(width 0.111252)
		(layer "F.Cu")
		(net "SW_HDD11_P")
	)
	(segment
		(start 46.0375 -324.2945)
		(end 45.085 -324.2945)
		(width 0.111252)
		(layer "F.Cu")
		(net "SW_HDD11_P")
	)
	(segment
		(start 31.637224 -308.242462)
		(end 31.317946 -308.242462)
		(width 0.111252)
		(layer "F.Cu")
		(net "SW_HDD11_P")
	)
	(segment
		(start 30.734 -306.578)
		(end 31.317946 -307.161946)
		(width 0.111252)
		(layer "F.Cu")
		(net "SW_HDD11_P")
	)
	(segment
		(start 44.992798 -324.386702)
		(end 43.560746 -324.386702)
		(width 0.111252)
		(layer "F.Cu")
		(net "SW_HDD11_P")
	)
	(segment
		(start 45.085 -324.2945)
		(end 44.992798 -324.386702)
		(width 0.111252)
		(layer "F.Cu")
		(net "SW_HDD11_P")
	)
	(segment
		(start 46.355 -323.977)
		(end 46.0375 -324.2945)
		(width 0.111252)
		(layer "F.Cu")
		(net "SW_HDD11_P")
	)
	(segment
		(start 32.384746 -310.988202)
		(end 32.384746 -309.096664)
		(width 0.111252)
		(layer "F.Cu")
		(net "SW_HDD11_P")
	)
	(segment
		(start 31.317946 -307.161946)
		(end 31.317946 -308.242462)
		(width 0.111252)
		(layer "F.Cu")
		(net "SW_HDD11_P")
	)
	(via
		(at 30.734 -306.578)
		(size 0.7112)
		(drill 0.3556)
		(layers "F.Cu" "B.Cu")
		(net "SW_HDD11_P")
	)
	(via
		(at 31.48838 -310.279542)
		(size 0.5588)
		(drill 0.3048)
		(layers "F.Cu" "B.Cu")
		(net "SW_HDD11_P")
	)
	(via
		(at 46.355 -323.977)
		(size 0.5588)
		(drill 0.3048)
		(layers "F.Cu" "B.Cu")
		(net "SW_HDD11_P")
	)
	(segment
		(start 45.580046 -323.977)
		(end 46.355 -323.977)
		(width 0.14605)
		(layer "In5.Cu")
		(net "SW_HDD11_P")
	)
	(segment
		(start 31.882588 -310.279542)
		(end 45.580046 -323.977)
		(width 0.14605)
		(layer "In5.Cu")
		(net "SW_HDD11_P")
	)
	(segment
		(start 31.48838 -310.279542)
		(end 31.882588 -310.279542)
		(width 0.14605)
		(layer "In5.Cu")
		(net "SW_HDD11_P")
	)
	(via
		(at 78.4606 -10.414)
		(size 0.7112)
		(drill 0.4064)
		(layers "F.Cu" "B.Cu")
		(net "P12V_HDD14")
	)
	(via
		(at 78.4352 -11.7856)
		(size 0.7112)
		(drill 0.4064)
		(layers "F.Cu" "B.Cu")
		(net "P12V_HDD14")
	)
	(via
		(at 77.4192 -7.4168)
		(size 0.7112)
		(drill 0.3556)
		(layers "F.Cu" "B.Cu")
		(net "P12V_HDD14")
	)
	(via
		(at 23.622 -11.4046)
		(size 0.7112)
		(drill 0.4064)
		(layers "F.Cu" "B.Cu")
		(net "P12V_HDD14")
	)
	(via
		(at 24.6126 -10.2616)
		(size 0.7112)
		(drill 0.4064)
		(layers "F.Cu" "B.Cu")
		(net "P12V_HDD14")
	)
	(via
		(at 74.7014 -7.112)
		(size 0.7112)
		(drill 0.4064)
		(layers "F.Cu" "B.Cu")
		(net "P12V_HDD14")
	)
	(via
		(at 77.343 -11.303)
		(size 0.7112)
		(drill 0.4064)
		(layers "F.Cu" "B.Cu")
		(net "P12V_HDD14")
	)
	(via
		(at 22.352 -9.2456)
		(size 0.7112)
		(drill 0.4064)
		(layers "F.Cu" "B.Cu")
		(net "P12V_HDD14")
	)
	(via
		(at 77.4954 -10.0838)
		(size 0.7112)
		(drill 0.4064)
		(layers "F.Cu" "B.Cu")
		(net "P12V_HDD14")
	)
	(via
		(at 88.221312 -8.005826)
		(size 0.7112)
		(drill 0.3556)
		(layers "F.Cu" "B.Cu")
		(net "P12V_HDD14")
	)
	(via
		(at 87.248746 -8.0391)
		(size 0.5588)
		(drill 0.3048)
		(layers "F.Cu" "B.Cu")
		(net "P12V_HDD14")
	)
	(via
		(at 76.3778 -10.0076)
		(size 0.7112)
		(drill 0.4064)
		(layers "F.Cu" "B.Cu")
		(net "P12V_HDD14")
	)
	(via
		(at 24.8412 -9.144)
		(size 0.7112)
		(drill 0.4064)
		(layers "F.Cu" "B.Cu")
		(net "P12V_HDD14")
	)
	(via
		(at 23.5966 -10.0838)
		(size 0.7112)
		(drill 0.4064)
		(layers "F.Cu" "B.Cu")
		(net "P12V_HDD14")
	)
	(segment
		(start 87.28202 -8.005826)
		(end 88.221312 -8.005826)
		(width 0.508)
		(layer "B.Cu")
		(net "P12V_HDD14")
	)
	(segment
		(start 87.248746 -8.0391)
		(end 87.28202 -8.005826)
		(width 0.508)
		(layer "B.Cu")
		(net "P12V_HDD14")
	)
	(segment
		(start 43.230038 -40.753284)
		(end 43.230038 -39.332408)
		(width 0.111252)
		(layer "F.Cu")
		(net "FLT_NET_HDD9")
	)
	(segment
		(start 44.005246 -38.8747)
		(end 43.687746 -38.8747)
		(width 0.111252)
		(layer "F.Cu")
		(net "FLT_NET_HDD9")
	)
	(segment
		(start 43.687746 -38.8747)
		(end 43.560746 -39.0017)
		(width 0.111252)
		(layer "F.Cu")
		(net "FLT_NET_HDD9")
	)
	(segment
		(start 44.894246 -39.7637)
		(end 44.005246 -38.8747)
		(width 0.111252)
		(layer "F.Cu")
		(net "FLT_NET_HDD9")
	)
	(segment
		(start 43.230038 -39.332408)
		(end 43.560746 -39.0017)
		(width 0.111252)
		(layer "F.Cu")
		(net "FLT_NET_HDD9")
	)
	(segment
		(start 43.230292 -40.753538)
		(end 43.230038 -40.753284)
		(width 0.111252)
		(layer "F.Cu")
		(net "FLT_NET_HDD9")
	)
	(via
		(at 43.560746 -39.0017)
		(size 0.7112)
		(drill 0.3556)
		(layers "F.Cu" "B.Cu")
		(net "FLT_NET_HDD9")
	)
	(segment
		(start 29.590746 -335.626202)
		(end 29.841698 -335.37525)
		(width 0.111252)
		(layer "F.Cu")
		(net "SAS2X28_A_HDD11_FLT")
	)
	(segment
		(start 29.841698 -335.37525)
		(end 29.841698 -333.9846)
		(width 0.111252)
		(layer "F.Cu")
		(net "SAS2X28_A_HDD11_FLT")
	)
	(segment
		(start 29.841698 -333.9846)
		(end 29.844746 -333.981552)
		(width 0.111252)
		(layer "F.Cu")
		(net "SAS2X28_A_HDD11_FLT")
	)
	(segment
		(start 29.844746 -333.981552)
		(end 29.844746 -333.1972)
		(width 0.111252)
		(layer "F.Cu")
		(net "SAS2X28_A_HDD11_FLT")
	)
	(segment
		(start 26.0858 -335.626202)
		(end 29.590746 -335.626202)
		(width 0.111252)
		(layer "F.Cu")
		(net "SAS2X28_A_HDD11_FLT")
	)
	(via
		(at 17.805146 -391.2997)
		(size 0.7112)
		(drill 0.3556)
		(layers "F.Cu" "B.Cu")
		(net "SAS2X28_A_HDD11_FLT")
	)
	(via
		(at 26.0858 -335.626202)
		(size 0.5588)
		(drill 0.3048)
		(layers "F.Cu" "B.Cu")
		(net "SAS2X28_A_HDD11_FLT")
	)
	(via
		(at 22.942296 -390.8552)
		(size 0.5588)
		(drill 0.3048)
		(layers "F.Cu" "B.Cu")
		(net "SAS2X28_A_HDD11_FLT")
	)
	(segment
		(start 20.0914 -390.8552)
		(end 19.6469 -391.2997)
		(width 0.111252)
		(layer "B.Cu")
		(net "SAS2X28_A_HDD11_FLT")
	)
	(segment
		(start 15.857982 -391.2997)
		(end 15.610078 -391.051796)
		(width 0.111252)
		(layer "B.Cu")
		(net "SAS2X28_A_HDD11_FLT")
	)
	(segment
		(start 4.798822 -388.500366)
		(end 2.81305 -388.500366)
		(width 0.111252)
		(layer "B.Cu")
		(net "SAS2X28_A_HDD11_FLT")
	)
	(segment
		(start 17.805146 -391.2997)
		(end 15.857982 -391.2997)
		(width 0.111252)
		(layer "B.Cu")
		(net "SAS2X28_A_HDD11_FLT")
	)
	(segment
		(start 22.942296 -390.8552)
		(end 20.0914 -390.8552)
		(width 0.111252)
		(layer "B.Cu")
		(net "SAS2X28_A_HDD11_FLT")
	)
	(segment
		(start 6.321044 -390.022588)
		(end 4.798822 -388.500366)
		(width 0.111252)
		(layer "B.Cu")
		(net "SAS2X28_A_HDD11_FLT")
	)
	(segment
		(start 2.81305 -388.500366)
		(end 2.811526 -388.498842)
		(width 0.111252)
		(layer "B.Cu")
		(net "SAS2X28_A_HDD11_FLT")
	)
	(segment
		(start 6.591554 -390.299956)
		(end 6.321044 -390.029446)
		(width 0.111252)
		(layer "B.Cu")
		(net "SAS2X28_A_HDD11_FLT")
	)
	(segment
		(start 6.598412 -390.299956)
		(end 6.591554 -390.299956)
		(width 0.111252)
		(layer "B.Cu")
		(net "SAS2X28_A_HDD11_FLT")
	)
	(segment
		(start 8.709914 -390.797796)
		(end 7.096252 -390.797796)
		(width 0.111252)
		(layer "B.Cu")
		(net "SAS2X28_A_HDD11_FLT")
	)
	(segment
		(start 19.6469 -391.2997)
		(end 17.805146 -391.2997)
		(width 0.111252)
		(layer "B.Cu")
		(net "SAS2X28_A_HDD11_FLT")
	)
	(segment
		(start 15.610078 -391.051796)
		(end 8.963914 -391.051796)
		(width 0.111252)
		(layer "B.Cu")
		(net "SAS2X28_A_HDD11_FLT")
	)
	(segment
		(start 8.963914 -391.051796)
		(end 8.709914 -390.797796)
		(width 0.111252)
		(layer "B.Cu")
		(net "SAS2X28_A_HDD11_FLT")
	)
	(segment
		(start 6.321044 -390.029446)
		(end 6.321044 -390.022588)
		(width 0.111252)
		(layer "B.Cu")
		(net "SAS2X28_A_HDD11_FLT")
	)
	(segment
		(start 7.096252 -390.797796)
		(end 6.598412 -390.299956)
		(width 0.111252)
		(layer "B.Cu")
		(net "SAS2X28_A_HDD11_FLT")
	)
	(segment
		(start 22.942296 -390.8552)
		(end 22.942296 -361.080304)
		(width 0.14605)
		(layer "In2.Cu")
		(net "SAS2X28_A_HDD11_FLT")
	)
	(segment
		(start 27.432 -356.5906)
		(end 27.432 -347.599)
		(width 0.14605)
		(layer "In2.Cu")
		(net "SAS2X28_A_HDD11_FLT")
	)
	(segment
		(start 26.6954 -346.8624)
		(end 26.6954 -336.235802)
		(width 0.14605)
		(layer "In2.Cu")
		(net "SAS2X28_A_HDD11_FLT")
	)
	(segment
		(start 27.432 -347.599)
		(end 26.6954 -346.8624)
		(width 0.14605)
		(layer "In2.Cu")
		(net "SAS2X28_A_HDD11_FLT")
	)
	(segment
		(start 22.942296 -361.080304)
		(end 27.432 -356.5906)
		(width 0.14605)
		(layer "In2.Cu")
		(net "SAS2X28_A_HDD11_FLT")
	)
	(segment
		(start 26.6954 -336.235802)
		(end 26.0858 -335.626202)
		(width 0.14605)
		(layer "In2.Cu")
		(net "SAS2X28_A_HDD11_FLT")
	)
	(segment
		(start 44.294298 -431.828702)
		(end 44.8945 -431.2285)
		(width 0.111252)
		(layer "F.Cu")
		(net "SW_HDD10_P")
	)
	(segment
		(start 46.0375 -431.2285)
		(end 46.736 -430.53)
		(width 0.111252)
		(layer "F.Cu")
		(net "SW_HDD10_P")
	)
	(segment
		(start 45.719746 -418.558218)
		(end 45.719746 -417.703)
		(width 0.111252)
		(layer "F.Cu")
		(net "SW_HDD10_P")
	)
	(segment
		(start 45.339 -431.2285)
		(end 46.0375 -431.2285)
		(width 0.111252)
		(layer "F.Cu")
		(net "SW_HDD10_P")
	)
	(segment
		(start 53.876702 -414.175702)
		(end 50.494946 -414.175702)
		(width 0.111252)
		(layer "F.Cu")
		(net "SW_HDD10_P")
	)
	(segment
		(start 43.814746 -431.828702)
		(end 44.294298 -431.828702)
		(width 0.111252)
		(layer "F.Cu")
		(net "SW_HDD10_P")
	)
	(segment
		(start 50.494946 -413.436054)
		(end 50.673 -413.258)
		(width 0.111252)
		(layer "F.Cu")
		(net "SW_HDD10_P")
	)
	(segment
		(start 55.0164 -422.2496)
		(end 55.0164 -415.3154)
		(width 0.111252)
		(layer "F.Cu")
		(net "SW_HDD10_P")
	)
	(segment
		(start 46.736 -430.53)
		(end 55.0164 -422.2496)
		(width 0.111252)
		(layer "F.Cu")
		(net "SW_HDD10_P")
	)
	(segment
		(start 50.494946 -414.175702)
		(end 50.494946 -413.436054)
		(width 0.111252)
		(layer "F.Cu")
		(net "SW_HDD10_P")
	)
	(segment
		(start 44.8945 -431.2285)
		(end 45.339 -431.2285)
		(width 0.111252)
		(layer "F.Cu")
		(net "SW_HDD10_P")
	)
	(segment
		(start 55.0164 -415.3154)
		(end 53.876702 -414.175702)
		(width 0.111252)
		(layer "F.Cu")
		(net "SW_HDD10_P")
	)
	(via
		(at 46.736 -430.53)
		(size 0.7112)
		(drill 0.3556)
		(layers "F.Cu" "B.Cu")
		(net "SW_HDD10_P")
	)
	(via
		(at 45.719746 -417.703)
		(size 0.5588)
		(drill 0.3048)
		(layers "F.Cu" "B.Cu")
		(net "SW_HDD10_P")
	)
	(via
		(at 50.673 -413.258)
		(size 0.5588)
		(drill 0.3048)
		(layers "F.Cu" "B.Cu")
		(net "SW_HDD10_P")
	)
	(segment
		(start 50.673 -413.258)
		(end 50.164746 -413.258)
		(width 0.111252)
		(layer "B.Cu")
		(net "SW_HDD10_P")
	)
	(segment
		(start 50.164746 -413.258)
		(end 45.719746 -417.703)
		(width 0.111252)
		(layer "B.Cu")
		(net "SW_HDD10_P")
	)
	(segment
		(start 76.517246 -87.8967)
		(end 76.939902 -88.319356)
		(width 0.111252)
		(layer "F.Cu")
		(net "SW_HDD9_P")
	)
	(segment
		(start 64.483234 -74.01814)
		(end 64.515492 -74.050398)
		(width 0.111252)
		(layer "F.Cu")
		(net "SW_HDD9_P")
	)
	(segment
		(start 64.515492 -74.050398)
		(end 64.515492 -74.958956)
		(width 0.111252)
		(layer "F.Cu")
		(net "SW_HDD9_P")
	)
	(segment
		(start 81.548986 -90.16746)
		(end 81.548986 -89.4969)
		(width 0.111252)
		(layer "F.Cu")
		(net "SW_HDD9_P")
	)
	(segment
		(start 78.587092 -90.220546)
		(end 78.803246 -90.4367)
		(width 0.111252)
		(layer "F.Cu")
		(net "SW_HDD9_P")
	)
	(segment
		(start 77.723746 -88.319356)
		(end 78.587092 -89.182702)
		(width 0.111252)
		(layer "F.Cu")
		(net "SW_HDD9_P")
	)
	(segment
		(start 81.279746 -90.4367)
		(end 81.548986 -90.16746)
		(width 0.111252)
		(layer "F.Cu")
		(net "SW_HDD9_P")
	)
	(segment
		(start 78.587092 -89.182702)
		(end 78.587092 -90.220546)
		(width 0.111252)
		(layer "F.Cu")
		(net "SW_HDD9_P")
	)
	(segment
		(start 76.939902 -88.319356)
		(end 77.723746 -88.319356)
		(width 0.111252)
		(layer "F.Cu")
		(net "SW_HDD9_P")
	)
	(segment
		(start 78.803246 -90.4367)
		(end 81.279746 -90.4367)
		(width 0.111252)
		(layer "F.Cu")
		(net "SW_HDD9_P")
	)
	(segment
		(start 82.5754 -89.4969)
		(end 81.548986 -89.4969)
		(width 0.111252)
		(layer "F.Cu")
		(net "SW_HDD9_P")
	)
	(segment
		(start 83.185 -90.1065)
		(end 82.5754 -89.4969)
		(width 0.111252)
		(layer "F.Cu")
		(net "SW_HDD9_P")
	)
	(via
		(at 71.20763 -83.539584)
		(size 0.7112)
		(drill 0.3556)
		(layers "F.Cu" "B.Cu")
		(net "SW_HDD9_P")
	)
	(via
		(at 76.517246 -87.8967)
		(size 0.5588)
		(drill 0.3048)
		(layers "F.Cu" "B.Cu")
		(net "SW_HDD9_P")
	)
	(via
		(at 64.483234 -74.01814)
		(size 0.5588)
		(drill 0.3048)
		(layers "F.Cu" "B.Cu")
		(net "SW_HDD9_P")
	)
	(segment
		(start 75.564746 -87.8967)
		(end 71.20763 -83.539584)
		(width 0.111252)
		(layer "B.Cu")
		(net "SW_HDD9_P")
	)
	(segment
		(start 76.517246 -87.8967)
		(end 75.564746 -87.8967)
		(width 0.111252)
		(layer "B.Cu")
		(net "SW_HDD9_P")
	)
	(segment
		(start 64.483234 -76.815188)
		(end 71.20763 -83.539584)
		(width 0.111252)
		(layer "B.Cu")
		(net "SW_HDD9_P")
	)
	(segment
		(start 64.483234 -74.01814)
		(end 64.483234 -76.815188)
		(width 0.111252)
		(layer "B.Cu")
		(net "SW_HDD9_P")
	)
	(segment
		(start 64.642746 -178.1937)
		(end 64.642746 -177.2158)
		(width 0.111252)
		(layer "F.Cu")
		(net "SW_HDD8_P")
	)
	(segment
		(start 78.994 -192.5447)
		(end 77.851 -191.4017)
		(width 0.111252)
		(layer "F.Cu")
		(net "SW_HDD8_P")
	)
	(segment
		(start 81.802986 -193.54546)
		(end 81.660746 -193.6877)
		(width 0.111252)
		(layer "F.Cu")
		(net "SW_HDD8_P")
	)
	(segment
		(start 78.994 -193.624454)
		(end 78.994 -192.5955)
		(width 0.111252)
		(layer "F.Cu")
		(net "SW_HDD8_P")
	)
	(segment
		(start 79.057246 -193.6877)
		(end 78.994 -193.624454)
		(width 0.111252)
		(layer "F.Cu")
		(net "SW_HDD8_P")
	)
	(segment
		(start 81.802986 -192.8749)
		(end 81.802986 -193.54546)
		(width 0.111252)
		(layer "F.Cu")
		(net "SW_HDD8_P")
	)
	(segment
		(start 81.660746 -193.6877)
		(end 79.057246 -193.6877)
		(width 0.111252)
		(layer "F.Cu")
		(net "SW_HDD8_P")
	)
	(segment
		(start 78.994 -192.5955)
		(end 78.994 -192.5447)
		(width 0.111252)
		(layer "F.Cu")
		(net "SW_HDD8_P")
	)
	(via
		(at 64.642746 -177.2158)
		(size 0.5588)
		(drill 0.3048)
		(layers "F.Cu" "B.Cu")
		(net "SW_HDD8_P")
	)
	(via
		(at 77.851 -191.4017)
		(size 0.5588)
		(drill 0.3048)
		(layers "F.Cu" "B.Cu")
		(net "SW_HDD8_P")
	)
	(via
		(at 72.330056 -187.53201)
		(size 0.7112)
		(drill 0.3556)
		(layers "F.Cu" "B.Cu")
		(net "SW_HDD8_P")
	)
	(segment
		(start 77.851 -191.4017)
		(end 75.691746 -191.4017)
		(width 0.111252)
		(layer "B.Cu")
		(net "SW_HDD8_P")
	)
	(segment
		(start 72.330056 -188.04001)
		(end 72.330056 -187.53201)
		(width 0.111252)
		(layer "B.Cu")
		(net "SW_HDD8_P")
	)
	(segment
		(start 75.691746 -191.4017)
		(end 72.330056 -188.04001)
		(width 0.111252)
		(layer "B.Cu")
		(net "SW_HDD8_P")
	)
	(segment
		(start 64.642746 -177.2158)
		(end 64.642746 -179.8447)
		(width 0.111252)
		(layer "B.Cu")
		(net "SW_HDD8_P")
	)
	(segment
		(start 64.642746 -179.8447)
		(end 72.330056 -187.53201)
		(width 0.111252)
		(layer "B.Cu")
		(net "SW_HDD8_P")
	)
	(segment
		(start 43.738546 -141.505432)
		(end 44.196 -141.962886)
		(width 0.111252)
		(layer "F.Cu")
		(net "FLT_NET_HDD8")
	)
	(segment
		(start 44.196 -142.570454)
		(end 44.894246 -143.2687)
		(width 0.111252)
		(layer "F.Cu")
		(net "FLT_NET_HDD8")
	)
	(segment
		(start 44.894246 -143.2687)
		(end 44.412662 -143.750284)
		(width 0.111252)
		(layer "F.Cu")
		(net "FLT_NET_HDD8")
	)
	(segment
		(start 43.233594 -143.750284)
		(end 43.230292 -143.753586)
		(width 0.111252)
		(layer "F.Cu")
		(net "FLT_NET_HDD8")
	)
	(segment
		(start 44.196 -141.962886)
		(end 44.196 -142.570454)
		(width 0.111252)
		(layer "F.Cu")
		(net "FLT_NET_HDD8")
	)
	(segment
		(start 44.412662 -143.750284)
		(end 43.233594 -143.750284)
		(width 0.111252)
		(layer "F.Cu")
		(net "FLT_NET_HDD8")
	)
	(via
		(at 43.738546 -141.505432)
		(size 0.7112)
		(drill 0.3556)
		(layers "F.Cu" "B.Cu")
		(net "FLT_NET_HDD8")
	)
	(segment
		(start 35.2044 -285.6484)
		(end 35.0901 -285.7627)
		(width 0.111252)
		(layer "F.Cu")
		(net "SW_HDD7_P")
	)
	(segment
		(start 30.2895 -282.829)
		(end 30.2895 -283.418534)
		(width 0.111252)
		(layer "F.Cu")
		(net "SW_HDD7_P")
	)
	(segment
		(start 30.79623 -283.925264)
		(end 30.79623 -284.671262)
		(width 0.111252)
		(layer "F.Cu")
		(net "SW_HDD7_P")
	)
	(segment
		(start 29.84754 -282.38704)
		(end 30.2895 -282.829)
		(width 0.111252)
		(layer "F.Cu")
		(net "SW_HDD7_P")
	)
	(segment
		(start 30.987746 -284.85973)
		(end 30.799278 -284.671262)
		(width 0.111252)
		(layer "F.Cu")
		(net "SW_HDD7_P")
	)
	(segment
		(start 30.987746 -285.6992)
		(end 30.987746 -284.85973)
		(width 0.111252)
		(layer "F.Cu")
		(net "SW_HDD7_P")
	)
	(segment
		(start 35.0901 -285.7627)
		(end 31.051246 -285.7627)
		(width 0.111252)
		(layer "F.Cu")
		(net "SW_HDD7_P")
	)
	(segment
		(start 30.799278 -284.671262)
		(end 30.79623 -284.671262)
		(width 0.111252)
		(layer "F.Cu")
		(net "SW_HDD7_P")
	)
	(segment
		(start 28.828746 -282.38704)
		(end 29.84754 -282.38704)
		(width 0.111252)
		(layer "F.Cu")
		(net "SW_HDD7_P")
	)
	(segment
		(start 63.8683 -288.7091)
		(end 62.813946 -288.7091)
		(width 0.111252)
		(layer "F.Cu")
		(net "SW_HDD7_P")
	)
	(segment
		(start 30.2895 -283.418534)
		(end 30.79623 -283.925264)
		(width 0.111252)
		(layer "F.Cu")
		(net "SW_HDD7_P")
	)
	(segment
		(start 31.051246 -285.7627)
		(end 30.987746 -285.6992)
		(width 0.111252)
		(layer "F.Cu")
		(net "SW_HDD7_P")
	)
	(segment
		(start 63.881 -288.7218)
		(end 63.8683 -288.7091)
		(width 0.111252)
		(layer "F.Cu")
		(net "SW_HDD7_P")
	)
	(via
		(at 63.881 -288.7218)
		(size 0.5588)
		(drill 0.3048)
		(layers "F.Cu" "B.Cu")
		(net "SW_HDD7_P")
	)
	(via
		(at 30.79623 -284.671262)
		(size 0.7112)
		(drill 0.3556)
		(layers "F.Cu" "B.Cu")
		(net "SW_HDD7_P")
	)
	(via
		(at 35.2044 -285.6484)
		(size 0.5588)
		(drill 0.3048)
		(layers "F.Cu" "B.Cu")
		(net "SW_HDD7_P")
	)
	(segment
		(start 38.2778 -288.7218)
		(end 35.2044 -285.6484)
		(width 0.14605)
		(layer "In2.Cu")
		(net "SW_HDD7_P")
	)
	(segment
		(start 63.881 -288.7218)
		(end 38.2778 -288.7218)
		(width 0.14605)
		(layer "In2.Cu")
		(net "SW_HDD7_P")
	)
	(segment
		(start 24.520144 -362.226098)
		(end 24.37384 -362.372656)
		(width 0.09525)
		(layer "F.Cu")
		(net "SAS2X28_A_HDD3_RX_+")
	)
	(segment
		(start 9.778746 -383.102104)
		(end 9.176512 -383.102104)
		(width 0.09525)
		(layer "F.Cu")
		(net "SAS2X28_A_HDD3_RX_+")
	)
	(segment
		(start 8.545576 -383.36347)
		(end 8.399272 -383.509774)
		(width 0.09525)
		(layer "F.Cu")
		(net "SAS2X28_A_HDD3_RX_+")
	)
	(segment
		(start 8.302244 -383.743708)
		(end 8.302244 -383.85115)
		(width 0.09525)
		(layer "F.Cu")
		(net "SAS2X28_A_HDD3_RX_+")
	)
	(segment
		(start 10.867898 -382.609344)
		(end 10.796778 -382.680718)
		(width 0.09525)
		(layer "F.Cu")
		(net "SAS2X28_A_HDD3_RX_+")
	)
	(segment
		(start 23.47595 -370.001292)
		(end 10.867898 -382.609344)
		(width 0.09525)
		(layer "F.Cu")
		(net "SAS2X28_A_HDD3_RX_+")
	)
	(segment
		(start 23.964646 -363.3597)
		(end 23.964646 -368.820954)
		(width 0.09525)
		(layer "F.Cu")
		(net "SAS2X28_A_HDD3_RX_+")
	)
	(segment
		(start 24.37384 -362.372656)
		(end 24.37384 -362.37291)
		(width 0.09525)
		(layer "F.Cu")
		(net "SAS2X28_A_HDD3_RX_+")
	)
	(segment
		(start 216.661746 -160.726628)
		(end 196.14261 -160.726628)
		(width 0.09525)
		(layer "F.Cu")
		(net "SAS2X28_A_HDD3_RX_+")
	)
	(segment
		(start 105.582212 -271.12849)
		(end 63.96609 -322.780152)
		(width 0.09525)
		(layer "F.Cu")
		(net "SAS2X28_A_HDD3_RX_+")
	)
	(segment
		(start 63.96609 -322.780152)
		(end 24.520144 -362.226098)
		(width 0.09525)
		(layer "F.Cu")
		(net "SAS2X28_A_HDD3_RX_+")
	)
	(segment
		(start 193.729102 -161.726372)
		(end 105.582212 -271.12849)
		(width 0.09525)
		(layer "F.Cu")
		(net "SAS2X28_A_HDD3_RX_+")
	)
	(via
		(at 8.512048 -384.060954)
		(size 0.5588)
		(drill 0.3048)
		(layers "F.Cu" "B.Cu")
		(net "SAS2X28_A_HDD3_RX_+")
	)
	(arc
		(start 217.410284 -161.006028)
		(mid 217.061233 -160.798771)
		(end 216.661746 -160.726628)
		(width 0.09525)
		(layer "F.Cu")
		(net "SAS2X28_A_HDD3_RX_+")
	)
	(arc
		(start 8.302244 -383.85115)
		(mid 8.363694 -383.999504)
		(end 8.512048 -384.060954)
		(width 0.09525)
		(layer "F.Cu")
		(net "SAS2X28_A_HDD3_RX_+")
	)
	(arc
		(start 9.176512 -383.102104)
		(mid 8.835043 -383.170026)
		(end 8.545576 -383.36347)
		(width 0.09525)
		(layer "F.Cu")
		(net "SAS2X28_A_HDD3_RX_+")
	)
	(arc
		(start 24.173942 -362.625132)
		(mid 24.018113 -362.977828)
		(end 23.964646 -363.3597)
		(width 0.09525)
		(layer "F.Cu")
		(net "SAS2X28_A_HDD3_RX_+")
	)
	(arc
		(start 8.399272 -383.509774)
		(mid 8.327449 -383.617075)
		(end 8.302244 -383.743708)
		(width 0.09525)
		(layer "F.Cu")
		(net "SAS2X28_A_HDD3_RX_+")
	)
	(arc
		(start 23.964646 -368.820954)
		(mid 23.837643 -369.459708)
		(end 23.47595 -370.001292)
		(width 0.09525)
		(layer "F.Cu")
		(net "SAS2X28_A_HDD3_RX_+")
	)
	(arc
		(start 10.796778 -382.680718)
		(mid 10.329685 -382.992697)
		(end 9.778746 -383.102104)
		(width 0.09525)
		(layer "F.Cu")
		(net "SAS2X28_A_HDD3_RX_+")
	)
	(arc
		(start 196.14261 -160.726628)
		(mid 194.836415 -160.986446)
		(end 193.729102 -161.726372)
		(width 0.09525)
		(layer "F.Cu")
		(net "SAS2X28_A_HDD3_RX_+")
	)
	(arc
		(start 24.37384 -362.37291)
		(mid 24.26659 -362.493235)
		(end 24.173942 -362.625132)
		(width 0.09525)
		(layer "F.Cu")
		(net "SAS2X28_A_HDD3_RX_+")
	)
	(segment
		(start 5.849874 -379.7935)
		(end 5.833618 -379.7935)
		(width 0.09525)
		(layer "B.Cu")
		(net "SAS2X28_A_HDD3_RX_+")
	)
	(segment
		(start 5.820664 -379.7935)
		(end 5.715254 -379.7935)
		(width 0.09525)
		(layer "B.Cu")
		(net "SAS2X28_A_HDD3_RX_+")
	)
	(segment
		(start 7.832852 -381.386842)
		(end 6.514592 -380.068582)
		(width 0.09525)
		(layer "B.Cu")
		(net "SAS2X28_A_HDD3_RX_+")
	)
	(segment
		(start 5.024882 -379.500384)
		(end 2.81305 -379.500384)
		(width 0.09525)
		(layer "B.Cu")
		(net "SAS2X28_A_HDD3_RX_+")
	)
	(segment
		(start 2.81305 -379.500384)
		(end 2.811526 -379.49886)
		(width 0.09525)
		(layer "B.Cu")
		(net "SAS2X28_A_HDD3_RX_+")
	)
	(segment
		(start 5.346446 -379.640592)
		(end 5.334 -379.6284)
		(width 0.09525)
		(layer "B.Cu")
		(net "SAS2X28_A_HDD3_RX_+")
	)
	(segment
		(start 8.203946 -383.317242)
		(end 8.203946 -382.2827)
		(width 0.09525)
		(layer "B.Cu")
		(net "SAS2X28_A_HDD3_RX_+")
	)
	(arc
		(start 5.715254 -379.7935)
		(mid 5.51563 -379.753757)
		(end 5.346446 -379.640592)
		(width 0.09525)
		(layer "B.Cu")
		(net "SAS2X28_A_HDD3_RX_+")
	)
	(arc
		(start 6.514592 -380.068582)
		(mid 6.209602 -379.864887)
		(end 5.849874 -379.7935)
		(width 0.09525)
		(layer "B.Cu")
		(net "SAS2X28_A_HDD3_RX_+")
	)
	(arc
		(start 8.512048 -384.060954)
		(mid 8.284053 -383.719736)
		(end 8.203946 -383.317242)
		(width 0.09525)
		(layer "B.Cu")
		(net "SAS2X28_A_HDD3_RX_+")
	)
	(arc
		(start 5.334 -379.6284)
		(mid 5.192175 -379.533636)
		(end 5.024882 -379.500384)
		(width 0.09525)
		(layer "B.Cu")
		(net "SAS2X28_A_HDD3_RX_+")
	)
	(arc
		(start 8.203946 -382.2827)
		(mid 8.107505 -381.797858)
		(end 7.832852 -381.386842)
		(width 0.09525)
		(layer "B.Cu")
		(net "SAS2X28_A_HDD3_RX_+")
	)
	(arc
		(start 5.833618 -379.7935)
		(mid 5.827141 -379.793479)
		(end 5.820664 -379.7935)
		(width 0.09525)
		(layer "B.Cu")
		(net "SAS2X28_A_HDD3_RX_+")
	)
	(segment
		(start 78.915006 -399.66646)
		(end 78.803246 -399.5547)
		(width 0.111252)
		(layer "F.Cu")
		(net "SW_HDD6_P")
	)
	(segment
		(start 81.548986 -398.7419)
		(end 81.548986 -399.56486)
		(width 0.111252)
		(layer "F.Cu")
		(net "SW_HDD6_P")
	)
	(segment
		(start 78.803246 -399.5547)
		(end 78.803246 -398.7292)
		(width 0.111252)
		(layer "F.Cu")
		(net "SW_HDD6_P")
	)
	(segment
		(start 81.447386 -399.66646)
		(end 78.915006 -399.66646)
		(width 0.111252)
		(layer "F.Cu")
		(net "SW_HDD6_P")
	)
	(segment
		(start 66.547746 -385.0767)
		(end 65.785746 -384.3147)
		(width 0.111252)
		(layer "F.Cu")
		(net "SW_HDD6_P")
	)
	(segment
		(start 83.058 -398.9705)
		(end 82.8294 -398.7419)
		(width 0.111252)
		(layer "F.Cu")
		(net "SW_HDD6_P")
	)
	(segment
		(start 81.548986 -399.56486)
		(end 81.447386 -399.66646)
		(width 0.111252)
		(layer "F.Cu")
		(net "SW_HDD6_P")
	)
	(segment
		(start 65.785746 -384.3147)
		(end 64.261746 -384.3147)
		(width 0.111252)
		(layer "F.Cu")
		(net "SW_HDD6_P")
	)
	(segment
		(start 82.8294 -398.7419)
		(end 81.548986 -398.7419)
		(width 0.111252)
		(layer "F.Cu")
		(net "SW_HDD6_P")
	)
	(via
		(at 73.764394 -392.801348)
		(size 0.7112)
		(drill 0.3556)
		(layers "F.Cu" "B.Cu")
		(net "SW_HDD6_P")
	)
	(via
		(at 66.547746 -385.0767)
		(size 0.5588)
		(drill 0.3048)
		(layers "F.Cu" "B.Cu")
		(net "SW_HDD6_P")
	)
	(via
		(at 78.803246 -398.7292)
		(size 0.5588)
		(drill 0.3048)
		(layers "F.Cu" "B.Cu")
		(net "SW_HDD6_P")
	)
	(segment
		(start 73.764394 -388.819898)
		(end 69.805296 -384.8608)
		(width 0.111252)
		(layer "B.Cu")
		(net "SW_HDD6_P")
	)
	(segment
		(start 78.866746 -398.6657)
		(end 78.866746 -397.9037)
		(width 0.111252)
		(layer "B.Cu")
		(net "SW_HDD6_P")
	)
	(segment
		(start 78.866746 -397.9037)
		(end 73.764394 -392.801348)
		(width 0.111252)
		(layer "B.Cu")
		(net "SW_HDD6_P")
	)
	(segment
		(start 78.803246 -398.7292)
		(end 78.866746 -398.6657)
		(width 0.111252)
		(layer "B.Cu")
		(net "SW_HDD6_P")
	)
	(segment
		(start 66.763646 -384.8608)
		(end 66.547746 -385.0767)
		(width 0.111252)
		(layer "B.Cu")
		(net "SW_HDD6_P")
	)
	(segment
		(start 73.764394 -392.801348)
		(end 73.764394 -388.819898)
		(width 0.111252)
		(layer "B.Cu")
		(net "SW_HDD6_P")
	)
	(segment
		(start 69.805296 -384.8608)
		(end 66.763646 -384.8608)
		(width 0.111252)
		(layer "B.Cu")
		(net "SW_HDD6_P")
	)
	(via
		(at 19.9898 -18.8468)
		(size 0.5588)
		(drill 0.3048)
		(layers "F.Cu" "B.Cu")
		(net "P5V_HDD14")
	)
	(via
		(at 79.374746 -18.4277)
		(size 0.7112)
		(drill 0.3556)
		(layers "F.Cu" "B.Cu")
		(net "P5V_HDD14")
	)
	(via
		(at 19.049746 -18.8087)
		(size 0.5588)
		(drill 0.3048)
		(layers "F.Cu" "B.Cu")
		(net "P5V_HDD14")
	)
	(via
		(at 77.215746 -18.8087)
		(size 0.7112)
		(drill 0.4064)
		(layers "F.Cu" "B.Cu")
		(net "P5V_HDD14")
	)
	(via
		(at 19.049746 -17.9197)
		(size 0.5588)
		(drill 0.3048)
		(layers "F.Cu" "B.Cu")
		(net "P5V_HDD14")
	)
	(via
		(at 83.439 -18.161)
		(size 0.7112)
		(drill 0.3556)
		(layers "F.Cu" "B.Cu")
		(net "P5V_HDD14")
	)
	(via
		(at 78.358746 -18.4277)
		(size 0.7112)
		(drill 0.4064)
		(layers "F.Cu" "B.Cu")
		(net "P5V_HDD14")
	)
	(via
		(at 19.9898 -17.9578)
		(size 0.5588)
		(drill 0.3048)
		(layers "F.Cu" "B.Cu")
		(net "P5V_HDD14")
	)
	(via
		(at 78.231746 -19.9517)
		(size 0.7112)
		(drill 0.4064)
		(layers "F.Cu" "B.Cu")
		(net "P5V_HDD14")
	)
	(via
		(at 73.913746 -17.1577)
		(size 0.7112)
		(drill 0.4064)
		(layers "F.Cu" "B.Cu")
		(net "P5V_HDD14")
	)
	(segment
		(start 78.358746 -18.4277)
		(end 79.374746 -18.4277)
		(width 0.508)
		(layer "B.Cu")
		(net "P5V_HDD14")
	)
	(segment
		(start 24.286464 -361.992672)
		(end 24.14016 -362.13923)
		(width 0.09525)
		(layer "F.Cu")
		(net "SAS2X28_A_HDD3_RX_-")
	)
	(segment
		(start 8.311896 -383.12979)
		(end 8.165846 -383.276094)
		(width 0.09525)
		(layer "F.Cu")
		(net "SAS2X28_A_HDD3_RX_-")
	)
	(segment
		(start 23.634446 -363.3597)
		(end 23.634446 -368.8207)
		(width 0.09525)
		(layer "F.Cu")
		(net "SAS2X28_A_HDD3_RX_-")
	)
	(segment
		(start 216.661746 -160.396428)
		(end 196.142356 -160.396428)
		(width 0.09525)
		(layer "F.Cu")
		(net "SAS2X28_A_HDD3_RX_-")
	)
	(segment
		(start 63.721996 -322.556632)
		(end 63.719964 -322.559172)
		(width 0.09525)
		(layer "F.Cu")
		(net "SAS2X28_A_HDD3_RX_-")
	)
	(segment
		(start 23.24227 -369.767612)
		(end 10.633964 -382.375918)
		(width 0.09525)
		(layer "F.Cu")
		(net "SAS2X28_A_HDD3_RX_-")
	)
	(segment
		(start 105.325164 -270.921226)
		(end 63.723266 -322.555108)
		(width 0.09525)
		(layer "F.Cu")
		(net "SAS2X28_A_HDD3_RX_-")
	)
	(segment
		(start 9.778746 -382.771904)
		(end 9.176258 -382.771904)
		(width 0.09525)
		(layer "F.Cu")
		(net "SAS2X28_A_HDD3_RX_-")
	)
	(segment
		(start 193.482722 -161.505646)
		(end 105.325164 -270.921226)
		(width 0.09525)
		(layer "F.Cu")
		(net "SAS2X28_A_HDD3_RX_-")
	)
	(segment
		(start 63.719964 -322.559172)
		(end 24.286464 -361.992672)
		(width 0.09525)
		(layer "F.Cu")
		(net "SAS2X28_A_HDD3_RX_-")
	)
	(segment
		(start 10.633964 -382.375918)
		(end 10.562844 -382.447292)
		(width 0.09525)
		(layer "F.Cu")
		(net "SAS2X28_A_HDD3_RX_-")
	)
	(segment
		(start 7.693152 -384.0226)
		(end 7.64921 -384.0226)
		(width 0.09525)
		(layer "F.Cu")
		(net "SAS2X28_A_HDD3_RX_-")
	)
	(via
		(at 7.64921 -384.0226)
		(size 0.5588)
		(drill 0.3048)
		(layers "F.Cu" "B.Cu")
		(net "SAS2X28_A_HDD3_RX_-")
	)
	(arc
		(start 63.723266 -322.555108)
		(mid 63.722636 -322.555874)
		(end 63.721996 -322.556632)
		(width 0.09525)
		(layer "F.Cu")
		(net "SAS2X28_A_HDD3_RX_-")
	)
	(arc
		(start 23.893018 -362.451142)
		(mid 23.700357 -362.887387)
		(end 23.634446 -363.3597)
		(width 0.09525)
		(layer "F.Cu")
		(net "SAS2X28_A_HDD3_RX_-")
	)
	(arc
		(start 7.972044 -383.743708)
		(mid 7.890358 -383.940914)
		(end 7.693152 -384.0226)
		(width 0.09525)
		(layer "F.Cu")
		(net "SAS2X28_A_HDD3_RX_-")
	)
	(arc
		(start 9.176258 -382.771904)
		(mid 8.70851 -382.864927)
		(end 8.311896 -383.12979)
		(width 0.09525)
		(layer "F.Cu")
		(net "SAS2X28_A_HDD3_RX_-")
	)
	(arc
		(start 217.410284 -160.117028)
		(mid 217.061233 -160.324285)
		(end 216.661746 -160.396428)
		(width 0.09525)
		(layer "F.Cu")
		(net "SAS2X28_A_HDD3_RX_-")
	)
	(arc
		(start 24.14016 -362.13923)
		(mid 24.007568 -362.288038)
		(end 23.893018 -362.451142)
		(width 0.09525)
		(layer "F.Cu")
		(net "SAS2X28_A_HDD3_RX_-")
	)
	(arc
		(start 196.142356 -160.396428)
		(mid 194.70156 -160.684911)
		(end 193.482722 -161.505646)
		(width 0.09525)
		(layer "F.Cu")
		(net "SAS2X28_A_HDD3_RX_-")
	)
	(arc
		(start 10.562844 -382.447292)
		(mid 10.203082 -382.687584)
		(end 9.778746 -382.771904)
		(width 0.09525)
		(layer "F.Cu")
		(net "SAS2X28_A_HDD3_RX_-")
	)
	(arc
		(start 8.165846 -383.276094)
		(mid 8.022439 -383.490623)
		(end 7.972044 -383.743708)
		(width 0.09525)
		(layer "F.Cu")
		(net "SAS2X28_A_HDD3_RX_-")
	)
	(arc
		(start 23.634446 -368.8207)
		(mid 23.532529 -369.333161)
		(end 23.24227 -369.767612)
		(width 0.09525)
		(layer "F.Cu")
		(net "SAS2X28_A_HDD3_RX_-")
	)
	(segment
		(start 7.873746 -383.480564)
		(end 7.873746 -382.2827)
		(width 0.09525)
		(layer "B.Cu")
		(net "SAS2X28_A_HDD3_RX_-")
	)
	(segment
		(start 4.924298 -380.500382)
		(end 4.922774 -380.498858)
		(width 0.09525)
		(layer "B.Cu")
		(net "SAS2X28_A_HDD3_RX_-")
	)
	(segment
		(start 5.849874 -380.1237)
		(end 5.833618 -380.1237)
		(width 0.09525)
		(layer "B.Cu")
		(net "SAS2X28_A_HDD3_RX_-")
	)
	(segment
		(start 4.922774 -380.498858)
		(end 2.811526 -380.498858)
		(width 0.09525)
		(layer "B.Cu")
		(net "SAS2X28_A_HDD3_RX_-")
	)
	(segment
		(start 7.59968 -381.62103)
		(end 6.280912 -380.302262)
		(width 0.09525)
		(layer "B.Cu")
		(net "SAS2X28_A_HDD3_RX_-")
	)
	(arc
		(start 6.280912 -380.302262)
		(mid 6.08315 -380.170122)
		(end 5.849874 -380.1237)
		(width 0.09525)
		(layer "B.Cu")
		(net "SAS2X28_A_HDD3_RX_-")
	)
	(arc
		(start 5.40258 -380.302262)
		(mid 5.183142 -380.448886)
		(end 4.924298 -380.500382)
		(width 0.09525)
		(layer "B.Cu")
		(net "SAS2X28_A_HDD3_RX_-")
	)
	(arc
		(start 5.833618 -380.1237)
		(mid 5.600334 -380.170103)
		(end 5.40258 -380.302262)
		(width 0.09525)
		(layer "B.Cu")
		(net "SAS2X28_A_HDD3_RX_-")
	)
	(arc
		(start 7.873746 -382.2827)
		(mid 7.802517 -381.924609)
		(end 7.59968 -381.62103)
		(width 0.09525)
		(layer "B.Cu")
		(net "SAS2X28_A_HDD3_RX_-")
	)
	(arc
		(start 7.64921 -384.0226)
		(mid 7.815378 -383.773912)
		(end 7.873746 -383.480564)
		(width 0.09525)
		(layer "B.Cu")
		(net "SAS2X28_A_HDD3_RX_-")
	)
	(segment
		(start 80.130396 -498.343174)
		(end 82.095086 -498.343174)
		(width 0.111252)
		(layer "F.Cu")
		(net "SW_HDD5_P")
	)
	(segment
		(start 82.095086 -498.343174)
		(end 82.3468 -498.09146)
		(width 0.111252)
		(layer "F.Cu")
		(net "SW_HDD5_P")
	)
	(segment
		(start 79.635858 -498.396514)
		(end 79.635858 -497.859812)
		(width 0.111252)
		(layer "F.Cu")
		(net "SW_HDD5_P")
	)
	(segment
		(start 65.353946 -485.4575)
		(end 65.404746 -485.4067)
		(width 0.111252)
		(layer "F.Cu")
		(net "SW_HDD5_P")
	)
	(segment
		(start 65.404746 -486.529126)
		(end 64.967358 -486.966514)
		(width 0.111252)
		(layer "F.Cu")
		(net "SW_HDD5_P")
	)
	(segment
		(start 83.039712 -497.604288)
		(end 82.3468 -497.604288)
		(width 0.111252)
		(layer "F.Cu")
		(net "SW_HDD5_P")
	)
	(segment
		(start 79.635858 -497.859812)
		(end 78.866746 -497.0907)
		(width 0.111252)
		(layer "F.Cu")
		(net "SW_HDD5_P")
	)
	(segment
		(start 82.3468 -498.09146)
		(end 82.3468 -497.604288)
		(width 0.111252)
		(layer "F.Cu")
		(net "SW_HDD5_P")
	)
	(segment
		(start 83.693 -496.951)
		(end 83.039712 -497.604288)
		(width 0.111252)
		(layer "F.Cu")
		(net "SW_HDD5_P")
	)
	(segment
		(start 64.389 -485.4575)
		(end 65.353946 -485.4575)
		(width 0.111252)
		(layer "F.Cu")
		(net "SW_HDD5_P")
	)
	(segment
		(start 79.635858 -498.396514)
		(end 80.077056 -498.396514)
		(width 0.111252)
		(layer "F.Cu")
		(net "SW_HDD5_P")
	)
	(segment
		(start 65.404746 -485.4067)
		(end 65.404746 -486.529126)
		(width 0.111252)
		(layer "F.Cu")
		(net "SW_HDD5_P")
	)
	(segment
		(start 80.077056 -498.396514)
		(end 80.130396 -498.343174)
		(width 0.111252)
		(layer "F.Cu")
		(net "SW_HDD5_P")
	)
	(via
		(at 78.866746 -497.0907)
		(size 0.5588)
		(drill 0.3048)
		(layers "F.Cu" "B.Cu")
		(net "SW_HDD5_P")
	)
	(via
		(at 83.693 -496.951)
		(size 0.7112)
		(drill 0.3556)
		(layers "F.Cu" "B.Cu")
		(net "SW_HDD5_P")
	)
	(via
		(at 65.404746 -485.4067)
		(size 0.5588)
		(drill 0.3048)
		(layers "F.Cu" "B.Cu")
		(net "SW_HDD5_P")
	)
	(segment
		(start 65.404746 -485.4067)
		(end 65.404746 -491.083346)
		(width 0.14605)
		(layer "In5.Cu")
		(net "SW_HDD5_P")
	)
	(segment
		(start 65.404746 -491.083346)
		(end 71.7931 -497.4717)
		(width 0.14605)
		(layer "In5.Cu")
		(net "SW_HDD5_P")
	)
	(segment
		(start 78.485746 -497.4717)
		(end 78.866746 -497.0907)
		(width 0.14605)
		(layer "In5.Cu")
		(net "SW_HDD5_P")
	)
	(segment
		(start 71.7931 -497.4717)
		(end 78.485746 -497.4717)
		(width 0.14605)
		(layer "In5.Cu")
		(net "SW_HDD5_P")
	)
	(segment
		(start 43.230292 -246.753634)
		(end 43.230038 -246.75338)
		(width 0.111252)
		(layer "F.Cu")
		(net "FLT_NET_HDD7")
	)
	(segment
		(start 44.386246 -245.2497)
		(end 43.687746 -245.2497)
		(width 0.111252)
		(layer "F.Cu")
		(net "FLT_NET_HDD7")
	)
	(segment
		(start 44.894246 -245.7577)
		(end 44.386246 -245.2497)
		(width 0.111252)
		(layer "F.Cu")
		(net "FLT_NET_HDD7")
	)
	(segment
		(start 43.230038 -246.75338)
		(end 43.230038 -245.453408)
		(width 0.111252)
		(layer "F.Cu")
		(net "FLT_NET_HDD7")
	)
	(segment
		(start 43.687746 -245.2497)
		(end 43.560746 -245.1227)
		(width 0.111252)
		(layer "F.Cu")
		(net "FLT_NET_HDD7")
	)
	(segment
		(start 43.230038 -245.453408)
		(end 43.560746 -245.1227)
		(width 0.111252)
		(layer "F.Cu")
		(net "FLT_NET_HDD7")
	)
	(via
		(at 43.560746 -245.1227)
		(size 0.7112)
		(drill 0.3556)
		(layers "F.Cu" "B.Cu")
		(net "FLT_NET_HDD7")
	)
	(segment
		(start 192.5955 -88.4555)
		(end 190.373 -88.4555)
		(width 0.111252)
		(layer "F.Cu")
		(net "SW_HDD4_P")
	)
	(segment
		(start 188.6458 -86.7283)
		(end 190.373 -88.4555)
		(width 0.111252)
		(layer "F.Cu")
		(net "SW_HDD4_P")
	)
	(segment
		(start 207.2132 -72.5297)
		(end 207.391 -72.7075)
		(width 0.111252)
		(layer "F.Cu")
		(net "SW_HDD4_P")
	)
	(segment
		(start 192.729612 -85.563456)
		(end 193.386456 -85.563456)
		(width 0.111252)
		(layer "F.Cu")
		(net "SW_HDD4_P")
	)
	(segment
		(start 193.762376 -74.625962)
		(end 193.755518 -74.625962)
		(width 0.111252)
		(layer "F.Cu")
		(net "SW_HDD4_P")
	)
	(segment
		(start 193.548 -87.503)
		(end 192.5955 -88.4555)
		(width 0.111252)
		(layer "F.Cu")
		(net "SW_HDD4_P")
	)
	(segment
		(start 195.858638 -72.5297)
		(end 193.762376 -74.625962)
		(width 0.111252)
		(layer "F.Cu")
		(net "SW_HDD4_P")
	)
	(segment
		(start 193.755518 -74.625962)
		(end 193.485008 -74.896472)
		(width 0.111252)
		(layer "F.Cu")
		(net "SW_HDD4_P")
	)
	(segment
		(start 207.940148 -78.097634)
		(end 209.009742 -78.097634)
		(width 0.111252)
		(layer "F.Cu")
		(net "SW_HDD4_P")
	)
	(segment
		(start 193.485008 -74.903584)
		(end 191.97955 -76.409042)
		(width 0.111252)
		(layer "F.Cu")
		(net "SW_HDD4_P")
	)
	(segment
		(start 193.548 -85.725)
		(end 193.548 -87.503)
		(width 0.111252)
		(layer "F.Cu")
		(net "SW_HDD4_P")
	)
	(segment
		(start 188.6458 -82.2706)
		(end 188.6458 -86.7283)
		(width 0.111252)
		(layer "F.Cu")
		(net "SW_HDD4_P")
	)
	(segment
		(start 193.485008 -74.896472)
		(end 193.485008 -74.903584)
		(width 0.111252)
		(layer "F.Cu")
		(net "SW_HDD4_P")
	)
	(segment
		(start 193.386456 -85.563456)
		(end 193.548 -85.725)
		(width 0.111252)
		(layer "F.Cu")
		(net "SW_HDD4_P")
	)
	(segment
		(start 199.643746 -72.5297)
		(end 207.2132 -72.5297)
		(width 0.111252)
		(layer "F.Cu")
		(net "SW_HDD4_P")
	)
	(segment
		(start 199.643746 -72.5297)
		(end 195.858638 -72.5297)
		(width 0.111252)
		(layer "F.Cu")
		(net "SW_HDD4_P")
	)
	(segment
		(start 191.97955 -76.409042)
		(end 188.6458 -82.2706)
		(width 0.111252)
		(layer "F.Cu")
		(net "SW_HDD4_P")
	)
	(segment
		(start 207.391 -72.7075)
		(end 207.391 -77.548486)
		(width 0.111252)
		(layer "F.Cu")
		(net "SW_HDD4_P")
	)
	(segment
		(start 207.391 -77.548486)
		(end 207.940148 -78.097634)
		(width 0.111252)
		(layer "F.Cu")
		(net "SW_HDD4_P")
	)
	(via
		(at 199.643746 -72.5297)
		(size 0.7112)
		(drill 0.3556)
		(layers "F.Cu" "B.Cu")
		(net "SW_HDD4_P")
	)
	(segment
		(start 86.740746 -17.04594)
		(end 88.328246 -17.04594)
		(width 0.111252)
		(layer "F.Cu")
		(net "SAS2X28_B_HDD14_FLT")
	)
	(segment
		(start 86.725506 -17.0307)
		(end 86.740746 -17.04594)
		(width 0.111252)
		(layer "F.Cu")
		(net "SAS2X28_B_HDD14_FLT")
	)
	(segment
		(start 85.788246 -17.0307)
		(end 86.725506 -17.0307)
		(width 0.111252)
		(layer "F.Cu")
		(net "SAS2X28_B_HDD14_FLT")
	)
	(via
		(at 101.726746 -103.207566)
		(size 0.5588)
		(drill 0.3048)
		(layers "F.Cu" "B.Cu")
		(net "SAS2X28_B_HDD14_FLT")
	)
	(via
		(at 85.800946 -17.04594)
		(size 0.7112)
		(drill 0.3556)
		(layers "F.Cu" "B.Cu")
		(net "SAS2X28_B_HDD14_FLT")
	)
	(via
		(at 12.648946 -142.0241)
		(size 0.5588)
		(drill 0.3048)
		(layers "F.Cu" "B.Cu")
		(net "SAS2X28_B_HDD14_FLT")
	)
	(via
		(at 87.50808 -103.207566)
		(size 0.5588)
		(drill 0.3048)
		(layers "F.Cu" "B.Cu")
		(net "SAS2X28_B_HDD14_FLT")
	)
	(via
		(at 86.740746 -17.04594)
		(size 0.5588)
		(drill 0.3048)
		(layers "F.Cu" "B.Cu")
		(net "SAS2X28_B_HDD14_FLT")
	)
	(segment
		(start 86.740746 -17.04594)
		(end 85.800946 -17.04594)
		(width 0.111252)
		(layer "B.Cu")
		(net "SAS2X28_B_HDD14_FLT")
	)
	(segment
		(start 9.125204 -138.500358)
		(end 2.81305 -138.500358)
		(width 0.111252)
		(layer "B.Cu")
		(net "SAS2X28_B_HDD14_FLT")
	)
	(segment
		(start 12.648946 -142.0241)
		(end 9.125204 -138.500358)
		(width 0.111252)
		(layer "B.Cu")
		(net "SAS2X28_B_HDD14_FLT")
	)
	(segment
		(start 2.81305 -138.500358)
		(end 2.811526 -138.498834)
		(width 0.111252)
		(layer "B.Cu")
		(net "SAS2X28_B_HDD14_FLT")
	)
	(segment
		(start 87.50808 -103.207566)
		(end 101.726746 -103.207566)
		(width 0.14605)
		(layer "In2.Cu")
		(net "SAS2X28_B_HDD14_FLT")
	)
	(segment
		(start 14.741652 -134.579868)
		(end 13.392404 -135.929116)
		(width 0.14605)
		(layer "In5.Cu")
		(net "SAS2X28_B_HDD14_FLT")
	)
	(segment
		(start 86.740746 -17.04594)
		(end 86.512146 -17.27454)
		(width 0.14605)
		(layer "In5.Cu")
		(net "SAS2X28_B_HDD14_FLT")
	)
	(segment
		(start 14.741652 -128.475994)
		(end 14.741652 -134.579868)
		(width 0.14605)
		(layer "In5.Cu")
		(net "SAS2X28_B_HDD14_FLT")
	)
	(segment
		(start 17.403826 -111.81715)
		(end 14.303248 -114.917728)
		(width 0.14605)
		(layer "In5.Cu")
		(net "SAS2X28_B_HDD14_FLT")
	)
	(segment
		(start 101.472746 -49.7967)
		(end 101.472746 -102.953566)
		(width 0.14605)
		(layer "In5.Cu")
		(net "SAS2X28_B_HDD14_FLT")
	)
	(segment
		(start 29.609034 -103.207566)
		(end 20.99945 -111.81715)
		(width 0.14605)
		(layer "In5.Cu")
		(net "SAS2X28_B_HDD14_FLT")
	)
	(segment
		(start 86.512146 -34.8361)
		(end 101.472746 -49.7967)
		(width 0.14605)
		(layer "In5.Cu")
		(net "SAS2X28_B_HDD14_FLT")
	)
	(segment
		(start 86.512146 -17.27454)
		(end 86.512146 -34.8361)
		(width 0.14605)
		(layer "In5.Cu")
		(net "SAS2X28_B_HDD14_FLT")
	)
	(segment
		(start 14.303248 -114.917728)
		(end 14.303248 -128.03759)
		(width 0.14605)
		(layer "In5.Cu")
		(net "SAS2X28_B_HDD14_FLT")
	)
	(segment
		(start 13.392404 -141.280642)
		(end 12.648946 -142.0241)
		(width 0.14605)
		(layer "In5.Cu")
		(net "SAS2X28_B_HDD14_FLT")
	)
	(segment
		(start 87.50808 -103.207566)
		(end 29.609034 -103.207566)
		(width 0.14605)
		(layer "In5.Cu")
		(net "SAS2X28_B_HDD14_FLT")
	)
	(segment
		(start 14.303248 -128.03759)
		(end 14.741652 -128.475994)
		(width 0.14605)
		(layer "In5.Cu")
		(net "SAS2X28_B_HDD14_FLT")
	)
	(segment
		(start 20.99945 -111.81715)
		(end 17.403826 -111.81715)
		(width 0.14605)
		(layer "In5.Cu")
		(net "SAS2X28_B_HDD14_FLT")
	)
	(segment
		(start 101.472746 -102.953566)
		(end 101.726746 -103.207566)
		(width 0.14605)
		(layer "In5.Cu")
		(net "SAS2X28_B_HDD14_FLT")
	)
	(segment
		(start 13.392404 -135.929116)
		(end 13.392404 -141.280642)
		(width 0.14605)
		(layer "In5.Cu")
		(net "SAS2X28_B_HDD14_FLT")
	)
	(segment
		(start 212.812884 -263.591548)
		(end 66.157348 -323.085206)
		(width 0.09525)
		(layer "F.Cu")
		(net "SAS2X28_A_HDD2_RX_-")
	)
	(segment
		(start 10.802112 -392.057128)
		(end 7.687564 -395.171676)
		(width 0.09525)
		(layer "F.Cu")
		(net "SAS2X28_A_HDD2_RX_-")
	)
	(segment
		(start 11.764772 -386.453634)
		(end 11.764772 -389.9027)
		(width 0.09525)
		(layer "F.Cu")
		(net "SAS2X28_A_HDD2_RX_-")
	)
	(segment
		(start 11.764518 -386.45338)
		(end 11.764772 -386.453634)
		(width 0.09525)
		(layer "F.Cu")
		(net "SAS2X28_A_HDD2_RX_-")
	)
	(segment
		(start 25.102566 -371.571774)
		(end 12.297664 -384.376676)
		(width 0.09525)
		(layer "F.Cu")
		(net "SAS2X28_A_HDD2_RX_-")
	)
	(segment
		(start 213.960964 -263.395968)
		(end 213.960964 -263.396222)
		(width 0.09525)
		(layer "F.Cu")
		(net "SAS2X28_A_HDD2_RX_-")
	)
	(segment
		(start 25.514046 -364.344966)
		(end 25.514046 -370.57838)
		(width 0.09525)
		(layer "F.Cu")
		(net "SAS2X28_A_HDD2_RX_-")
	)
	(segment
		(start 212.813138 -263.591802)
		(end 212.812884 -263.591548)
		(width 0.09525)
		(layer "F.Cu")
		(net "SAS2X28_A_HDD2_RX_-")
	)
	(segment
		(start 65.306194 -323.632068)
		(end 27.330908 -361.607862)
		(width 0.09525)
		(layer "F.Cu")
		(net "SAS2X28_A_HDD2_RX_-")
	)
	(segment
		(start 216.153746 -263.395968)
		(end 213.960964 -263.395968)
		(width 0.09525)
		(layer "F.Cu")
		(net "SAS2X28_A_HDD2_RX_-")
	)
	(segment
		(start 11.764518 -385.663948)
		(end 11.764518 -386.45338)
		(width 0.09525)
		(layer "F.Cu")
		(net "SAS2X28_A_HDD2_RX_-")
	)
	(segment
		(start 10.808716 -392.05154)
		(end 10.802112 -392.057128)
		(width 0.09525)
		(layer "F.Cu")
		(net "SAS2X28_A_HDD2_RX_-")
	)
	(segment
		(start 7.124446 -396.5067)
		(end 7.124446 -398.6657)
		(width 0.09525)
		(layer "F.Cu")
		(net "SAS2X28_A_HDD2_RX_-")
	)
	(segment
		(start 27.330908 -361.607862)
		(end 26.165048 -362.773214)
		(width 0.09525)
		(layer "F.Cu")
		(net "SAS2X28_A_HDD2_RX_-")
	)
	(via
		(at 6.889242 -399.34007)
		(size 0.5588)
		(drill 0.3048)
		(layers "F.Cu" "B.Cu")
		(net "SAS2X28_A_HDD2_RX_-")
	)
	(arc
		(start 7.124446 -398.6657)
		(mid 7.063956 -399.022803)
		(end 6.889242 -399.34007)
		(width 0.09525)
		(layer "F.Cu")
		(net "SAS2X28_A_HDD2_RX_-")
	)
	(arc
		(start 216.377774 -263.386062)
		(mid 216.265868 -263.393466)
		(end 216.153746 -263.395968)
		(width 0.09525)
		(layer "F.Cu")
		(net "SAS2X28_A_HDD2_RX_-")
	)
	(arc
		(start 7.687564 -395.171676)
		(mid 7.27102 -395.782238)
		(end 7.124446 -396.5067)
		(width 0.09525)
		(layer "F.Cu")
		(net "SAS2X28_A_HDD2_RX_-")
	)
	(arc
		(start 66.157348 -323.085206)
		(mid 65.70632 -323.319021)
		(end 65.306194 -323.632068)
		(width 0.09525)
		(layer "F.Cu")
		(net "SAS2X28_A_HDD2_RX_-")
	)
	(arc
		(start 26.165048 -362.773214)
		(mid 25.683231 -363.494353)
		(end 25.514046 -364.344966)
		(width 0.09525)
		(layer "F.Cu")
		(net "SAS2X28_A_HDD2_RX_-")
	)
	(arc
		(start 25.514046 -370.57838)
		(mid 25.407106 -371.116002)
		(end 25.102566 -371.571774)
		(width 0.09525)
		(layer "F.Cu")
		(net "SAS2X28_A_HDD2_RX_-")
	)
	(arc
		(start 12.297664 -384.376676)
		(mid 11.903063 -384.967282)
		(end 11.764518 -385.663948)
		(width 0.09525)
		(layer "F.Cu")
		(net "SAS2X28_A_HDD2_RX_-")
	)
	(arc
		(start 11.764772 -389.9027)
		(mid 11.514967 -391.078656)
		(end 10.808716 -392.05154)
		(width 0.09525)
		(layer "F.Cu")
		(net "SAS2X28_A_HDD2_RX_-")
	)
	(arc
		(start 213.960964 -263.396222)
		(mid 213.3764 -263.431505)
		(end 212.813138 -263.591802)
		(width 0.09525)
		(layer "F.Cu")
		(net "SAS2X28_A_HDD2_RX_-")
	)
	(arc
		(start 217.318082 -263.116568)
		(mid 216.860889 -263.296538)
		(end 216.377774 -263.386062)
		(width 0.09525)
		(layer "F.Cu")
		(net "SAS2X28_A_HDD2_RX_-")
	)
	(segment
		(start 4.599686 -398.500346)
		(end 4.598162 -398.498822)
		(width 0.09525)
		(layer "B.Cu")
		(net "SAS2X28_A_HDD2_RX_-")
	)
	(segment
		(start 6.349746 -398.162272)
		(end 5.415788 -398.162272)
		(width 0.09525)
		(layer "B.Cu")
		(net "SAS2X28_A_HDD2_RX_-")
	)
	(segment
		(start 5.147564 -398.273524)
		(end 5.14731 -398.273524)
		(width 0.09525)
		(layer "B.Cu")
		(net "SAS2X28_A_HDD2_RX_-")
	)
	(segment
		(start 4.598162 -398.498822)
		(end 2.811526 -398.498822)
		(width 0.09525)
		(layer "B.Cu")
		(net "SAS2X28_A_HDD2_RX_-")
	)
	(arc
		(start 6.889242 -399.34007)
		(mid 7.087492 -399.062118)
		(end 7.115048 -398.721834)
		(width 0.09525)
		(layer "B.Cu")
		(net "SAS2X28_A_HDD2_RX_-")
	)
	(arc
		(start 7.115048 -398.721834)
		(mid 7.013097 -398.477925)
		(end 6.821424 -398.295876)
		(width 0.09525)
		(layer "B.Cu")
		(net "SAS2X28_A_HDD2_RX_-")
	)
	(arc
		(start 6.749542 -398.255998)
		(mid 6.555062 -398.186011)
		(end 6.349746 -398.162272)
		(width 0.09525)
		(layer "B.Cu")
		(net "SAS2X28_A_HDD2_RX_-")
	)
	(arc
		(start 5.415788 -398.162272)
		(mid 5.270623 -398.191241)
		(end 5.147564 -398.273524)
		(width 0.09525)
		(layer "B.Cu")
		(net "SAS2X28_A_HDD2_RX_-")
	)
	(arc
		(start 5.14731 -398.273524)
		(mid 4.896058 -398.441405)
		(end 4.599686 -398.500346)
		(width 0.09525)
		(layer "B.Cu")
		(net "SAS2X28_A_HDD2_RX_-")
	)
	(arc
		(start 6.821424 -398.295876)
		(mid 6.785939 -398.275114)
		(end 6.749542 -398.255998)
		(width 0.09525)
		(layer "B.Cu")
		(net "SAS2X28_A_HDD2_RX_-")
	)
	(segment
		(start 192.994788 -189.529212)
		(end 192.5955 -189.9285)
		(width 0.111252)
		(layer "F.Cu")
		(net "SW_HDD3_P")
	)
	(segment
		(start 192.5955 -189.9285)
		(end 190.627 -189.9285)
		(width 0.111252)
		(layer "F.Cu")
		(net "SW_HDD3_P")
	)
	(segment
		(start 205.5622 -175.2727)
		(end 205.74 -175.4505)
		(width 0.111252)
		(layer "F.Cu")
		(net "SW_HDD3_P")
	)
	(segment
		(start 192.994788 -187.381388)
		(end 192.994788 -189.529212)
		(width 0.111252)
		(layer "F.Cu")
		(net "SW_HDD3_P")
	)
	(segment
		(start 205.74 -175.4505)
		(end 205.74 -179.209954)
		(width 0.111252)
		(layer "F.Cu")
		(net "SW_HDD3_P")
	)
	(segment
		(start 192.893188 -187.279788)
		(end 192.994788 -187.381388)
		(width 0.111252)
		(layer "F.Cu")
		(net "SW_HDD3_P")
	)
	(segment
		(start 207.340708 -180.810662)
		(end 208.491074 -180.810662)
		(width 0.111252)
		(layer "F.Cu")
		(net "SW_HDD3_P")
	)
	(segment
		(start 188.468 -177.812446)
		(end 188.468 -188.722)
		(width 0.111252)
		(layer "F.Cu")
		(net "SW_HDD3_P")
	)
	(segment
		(start 205.74 -179.209954)
		(end 207.340708 -180.810662)
		(width 0.111252)
		(layer "F.Cu")
		(net "SW_HDD3_P")
	)
	(segment
		(start 189.6745 -189.9285)
		(end 190.627 -189.9285)
		(width 0.111252)
		(layer "F.Cu")
		(net "SW_HDD3_P")
	)
	(segment
		(start 197.357746 -175.2727)
		(end 205.5622 -175.2727)
		(width 0.111252)
		(layer "F.Cu")
		(net "SW_HDD3_P")
	)
	(segment
		(start 188.468 -188.722)
		(end 189.6745 -189.9285)
		(width 0.111252)
		(layer "F.Cu")
		(net "SW_HDD3_P")
	)
	(segment
		(start 197.357746 -175.2727)
		(end 191.007746 -175.2727)
		(width 0.111252)
		(layer "F.Cu")
		(net "SW_HDD3_P")
	)
	(segment
		(start 192.276984 -187.279788)
		(end 192.893188 -187.279788)
		(width 0.111252)
		(layer "F.Cu")
		(net "SW_HDD3_P")
	)
	(segment
		(start 191.007746 -175.2727)
		(end 188.468 -177.812446)
		(width 0.111252)
		(layer "F.Cu")
		(net "SW_HDD3_P")
	)
	(via
		(at 197.357746 -175.2727)
		(size 0.7112)
		(drill 0.3556)
		(layers "F.Cu" "B.Cu")
		(net "SW_HDD3_P")
	)
	(segment
		(start 12.687046 -52.8066)
		(end 12.775946 -52.7177)
		(width 0.111252)
		(layer "F.Cu")
		(net "DRIVE_ACT_14")
	)
	(segment
		(start 14.160246 -51.7017)
		(end 14.160246 -51.2572)
		(width 0.111252)
		(layer "F.Cu")
		(net "DRIVE_ACT_14")
	)
	(segment
		(start 14.160246 -51.2572)
		(end 13.334746 -50.4317)
		(width 0.111252)
		(layer "F.Cu")
		(net "DRIVE_ACT_14")
	)
	(segment
		(start 12.775946 -52.7177)
		(end 14.160246 -52.7177)
		(width 0.111252)
		(layer "F.Cu")
		(net "DRIVE_ACT_14")
	)
	(segment
		(start 14.160246 -52.7177)
		(end 14.160246 -51.7017)
		(width 0.111252)
		(layer "F.Cu")
		(net "DRIVE_ACT_14")
	)
	(via
		(at 13.334746 -50.4317)
		(size 0.7112)
		(drill 0.3556)
		(layers "F.Cu" "B.Cu")
		(net "DRIVE_ACT_14")
	)
	(segment
		(start 192.912746 -291.922454)
		(end 192.912746 -291.522658)
		(width 0.111252)
		(layer "F.Cu")
		(net "SW_HDD2_P")
	)
	(segment
		(start 193.298826 -275.6027)
		(end 198.627746 -275.6027)
		(width 0.111252)
		(layer "F.Cu")
		(net "SW_HDD2_P")
	)
	(segment
		(start 192.912746 -291.522658)
		(end 192.917572 -291.517832)
		(width 0.111252)
		(layer "F.Cu")
		(net "SW_HDD2_P")
	)
	(segment
		(start 207.264 -277.9395)
		(end 204.9272 -275.6027)
		(width 0.111252)
		(layer "F.Cu")
		(net "SW_HDD2_P")
	)
	(segment
		(start 188.7474 -280.154126)
		(end 193.298826 -275.6027)
		(width 0.111252)
		(layer "F.Cu")
		(net "SW_HDD2_P")
	)
	(segment
		(start 188.7474 -291.4269)
		(end 188.7474 -280.154126)
		(width 0.111252)
		(layer "F.Cu")
		(net "SW_HDD2_P")
	)
	(segment
		(start 189.865 -292.5445)
		(end 192.2907 -292.5445)
		(width 0.111252)
		(layer "F.Cu")
		(net "SW_HDD2_P")
	)
	(segment
		(start 207.289146 -277.964646)
		(end 207.264 -277.9395)
		(width 0.111252)
		(layer "F.Cu")
		(net "SW_HDD2_P")
	)
	(segment
		(start 192.917572 -290.309808)
		(end 192.912746 -290.304982)
		(width 0.111252)
		(layer "F.Cu")
		(net "SW_HDD2_P")
	)
	(segment
		(start 192.912746 -290.304982)
		(end 192.912746 -290.067746)
		(width 0.111252)
		(layer "F.Cu")
		(net "SW_HDD2_P")
	)
	(segment
		(start 208.493614 -283.518864)
		(end 207.94599 -283.518864)
		(width 0.111252)
		(layer "F.Cu")
		(net "SW_HDD2_P")
	)
	(segment
		(start 204.9272 -275.6027)
		(end 198.627746 -275.6027)
		(width 0.111252)
		(layer "F.Cu")
		(net "SW_HDD2_P")
	)
	(segment
		(start 192.78346 -289.93846)
		(end 192.226946 -289.93846)
		(width 0.111252)
		(layer "F.Cu")
		(net "SW_HDD2_P")
	)
	(segment
		(start 207.94599 -283.518864)
		(end 207.289146 -282.86202)
		(width 0.111252)
		(layer "F.Cu")
		(net "SW_HDD2_P")
	)
	(segment
		(start 207.289146 -282.86202)
		(end 207.289146 -277.964646)
		(width 0.111252)
		(layer "F.Cu")
		(net "SW_HDD2_P")
	)
	(segment
		(start 192.912746 -290.067746)
		(end 192.78346 -289.93846)
		(width 0.111252)
		(layer "F.Cu")
		(net "SW_HDD2_P")
	)
	(segment
		(start 189.865 -292.5445)
		(end 188.7474 -291.4269)
		(width 0.111252)
		(layer "F.Cu")
		(net "SW_HDD2_P")
	)
	(segment
		(start 192.2907 -292.5445)
		(end 192.912746 -291.922454)
		(width 0.111252)
		(layer "F.Cu")
		(net "SW_HDD2_P")
	)
	(segment
		(start 192.917572 -291.517832)
		(end 192.917572 -290.309808)
		(width 0.111252)
		(layer "F.Cu")
		(net "SW_HDD2_P")
	)
	(via
		(at 198.627746 -275.6027)
		(size 0.7112)
		(drill 0.3556)
		(layers "F.Cu" "B.Cu")
		(net "SW_HDD2_P")
	)
	(segment
		(start 8.28167 -361.608878)
		(end 8.281924 -361.609132)
		(width 0.09525)
		(layer "F.Cu")
		(net "SAS2X28_A_HDD14_RX_-")
	)
	(segment
		(start 11.609832 -356.000558)
		(end 10.354818 -357.255064)
		(width 0.09525)
		(layer "F.Cu")
		(net "SAS2X28_A_HDD14_RX_-")
	)
	(segment
		(start 9.986264 -358.145842)
		(end 9.986264 -359.621836)
		(width 0.09525)
		(layer "F.Cu")
		(net "SAS2X28_A_HDD14_RX_-")
	)
	(segment
		(start 31.742634 -254.693166)
		(end 14.090904 -272.34515)
		(width 0.09525)
		(layer "F.Cu")
		(net "SAS2X28_A_HDD14_RX_-")
	)
	(segment
		(start 7.878318 -363.835188)
		(end 7.787894 -364.053374)
		(width 0.09525)
		(layer "F.Cu")
		(net "SAS2X28_A_HDD14_RX_-")
	)
	(segment
		(start 26.519886 -185.889646)
		(end 31.839154 -191.208914)
		(width 0.09525)
		(layer "F.Cu")
		(net "SAS2X28_A_HDD14_RX_-")
	)
	(segment
		(start 14.090904 -272.34515)
		(end 12.930632 -273.505422)
		(width 0.09525)
		(layer "F.Cu")
		(net "SAS2X28_A_HDD14_RX_-")
	)
	(segment
		(start 28.429966 -124.568966)
		(end 30.066234 -126.205234)
		(width 0.09525)
		(layer "F.Cu")
		(net "SAS2X28_A_HDD14_RX_-")
	)
	(segment
		(start 11.924538 -275.934932)
		(end 11.924538 -355.240844)
		(width 0.09525)
		(layer "F.Cu")
		(net "SAS2X28_A_HDD14_RX_-")
	)
	(segment
		(start 30.8102 -128.001268)
		(end 30.8102 -153.075132)
		(width 0.09525)
		(layer "F.Cu")
		(net "SAS2X28_A_HDD14_RX_-")
	)
	(segment
		(start 27.686 -36.91636)
		(end 27.686 -122.772932)
		(width 0.09525)
		(layer "F.Cu")
		(net "SAS2X28_A_HDD14_RX_-")
	)
	(segment
		(start 25.6794 -160.447228)
		(end 25.6794 -183.859932)
		(width 0.09525)
		(layer "F.Cu")
		(net "SAS2X28_A_HDD14_RX_-")
	)
	(segment
		(start 27.15387 -36.5633)
		(end 27.33294 -36.5633)
		(width 0.09525)
		(layer "F.Cu")
		(net "SAS2X28_A_HDD14_RX_-")
	)
	(segment
		(start 10.354818 -357.255064)
		(end 10.355072 -357.255318)
		(width 0.09525)
		(layer "F.Cu")
		(net "SAS2X28_A_HDD14_RX_-")
	)
	(segment
		(start 7.746746 -364.259622)
		(end 7.746746 -364.3757)
		(width 0.09525)
		(layer "F.Cu")
		(net "SAS2X28_A_HDD14_RX_-")
	)
	(segment
		(start 9.78662 -360.103928)
		(end 8.28167 -361.608878)
		(width 0.09525)
		(layer "F.Cu")
		(net "SAS2X28_A_HDD14_RX_-")
	)
	(segment
		(start 7.924546 -362.47197)
		(end 7.924546 -363.602016)
		(width 0.09525)
		(layer "F.Cu")
		(net "SAS2X28_A_HDD14_RX_-")
	)
	(segment
		(start 30.066234 -154.871166)
		(end 26.519886 -158.417514)
		(width 0.09525)
		(layer "F.Cu")
		(net "SAS2X28_A_HDD14_RX_-")
	)
	(segment
		(start 32.4866 -192.771268)
		(end 32.4866 -252.897132)
		(width 0.09525)
		(layer "F.Cu")
		(net "SAS2X28_A_HDD14_RX_-")
	)
	(via
		(at 7.746746 -364.3757)
		(size 0.5588)
		(drill 0.3048)
		(layers "F.Cu" "B.Cu")
		(net "SAS2X28_A_HDD14_RX_-")
	)
	(arc
		(start 10.355072 -357.255318)
		(mid 10.0821 -357.663895)
		(end 9.986264 -358.145842)
		(width 0.09525)
		(layer "F.Cu")
		(net "SAS2X28_A_HDD14_RX_-")
	)
	(arc
		(start 25.6794 -183.859932)
		(mid 25.897798 -184.958364)
		(end 26.519886 -185.889646)
		(width 0.09525)
		(layer "F.Cu")
		(net "SAS2X28_A_HDD14_RX_-")
	)
	(arc
		(start 7.787894 -364.053374)
		(mid 7.757172 -364.154472)
		(end 7.746746 -364.259622)
		(width 0.09525)
		(layer "F.Cu")
		(net "SAS2X28_A_HDD14_RX_-")
	)
	(arc
		(start 26.519886 -158.417514)
		(mid 25.897734 -159.34877)
		(end 25.6794 -160.447228)
		(width 0.09525)
		(layer "F.Cu")
		(net "SAS2X28_A_HDD14_RX_-")
	)
	(arc
		(start 27.686 -122.772932)
		(mid 27.879346 -123.744948)
		(end 28.429966 -124.568966)
		(width 0.09525)
		(layer "F.Cu")
		(net "SAS2X28_A_HDD14_RX_-")
	)
	(arc
		(start 9.986264 -359.621836)
		(mid 9.93437 -359.882725)
		(end 9.78662 -360.103928)
		(width 0.09525)
		(layer "F.Cu")
		(net "SAS2X28_A_HDD14_RX_-")
	)
	(arc
		(start 26.479246 -36.8427)
		(mid 26.788766 -36.635885)
		(end 27.15387 -36.5633)
		(width 0.09525)
		(layer "F.Cu")
		(net "SAS2X28_A_HDD14_RX_-")
	)
	(arc
		(start 31.839154 -191.208914)
		(mid 32.318251 -191.925699)
		(end 32.4866 -192.771268)
		(width 0.09525)
		(layer "F.Cu")
		(net "SAS2X28_A_HDD14_RX_-")
	)
	(arc
		(start 32.4866 -252.897132)
		(mid 32.293254 -253.869148)
		(end 31.742634 -254.693166)
		(width 0.09525)
		(layer "F.Cu")
		(net "SAS2X28_A_HDD14_RX_-")
	)
	(arc
		(start 30.8102 -153.075132)
		(mid 30.616854 -154.047148)
		(end 30.066234 -154.871166)
		(width 0.09525)
		(layer "F.Cu")
		(net "SAS2X28_A_HDD14_RX_-")
	)
	(arc
		(start 11.924538 -355.240844)
		(mid 11.842753 -355.652007)
		(end 11.609832 -356.000558)
		(width 0.09525)
		(layer "F.Cu")
		(net "SAS2X28_A_HDD14_RX_-")
	)
	(arc
		(start 30.066234 -126.205234)
		(mid 30.616832 -127.029261)
		(end 30.8102 -128.001268)
		(width 0.09525)
		(layer "F.Cu")
		(net "SAS2X28_A_HDD14_RX_-")
	)
	(arc
		(start 12.930632 -273.505422)
		(mid 12.185995 -274.620133)
		(end 11.924538 -275.934932)
		(width 0.09525)
		(layer "F.Cu")
		(net "SAS2X28_A_HDD14_RX_-")
	)
	(arc
		(start 27.33294 -36.5633)
		(mid 27.582591 -36.666709)
		(end 27.686 -36.91636)
		(width 0.09525)
		(layer "F.Cu")
		(net "SAS2X28_A_HDD14_RX_-")
	)
	(arc
		(start 8.281924 -361.609132)
		(mid 8.017439 -362.005006)
		(end 7.924546 -362.47197)
		(width 0.09525)
		(layer "F.Cu")
		(net "SAS2X28_A_HDD14_RX_-")
	)
	(arc
		(start 7.924546 -363.602016)
		(mid 7.912897 -363.720874)
		(end 7.878318 -363.835188)
		(width 0.09525)
		(layer "F.Cu")
		(net "SAS2X28_A_HDD14_RX_-")
	)
	(segment
		(start 4.789932 -360.498898)
		(end 2.811526 -360.498898)
		(width 0.09525)
		(layer "B.Cu")
		(net "SAS2X28_A_HDD14_RX_-")
	)
	(segment
		(start 7.506462 -361.427522)
		(end 6.687566 -360.608626)
		(width 0.09525)
		(layer "B.Cu")
		(net "SAS2X28_A_HDD14_RX_-")
	)
	(segment
		(start 7.83336 -364.166658)
		(end 7.83336 -362.2167)
		(width 0.09525)
		(layer "B.Cu")
		(net "SAS2X28_A_HDD14_RX_-")
	)
	(segment
		(start 5.841746 -360.1847)
		(end 5.553456 -360.1847)
		(width 0.09525)
		(layer "B.Cu")
		(net "SAS2X28_A_HDD14_RX_-")
	)
	(segment
		(start 4.791456 -360.500422)
		(end 4.789932 -360.498898)
		(width 0.09525)
		(layer "B.Cu")
		(net "SAS2X28_A_HDD14_RX_-")
	)
	(segment
		(start 6.687566 -360.608626)
		(end 6.561836 -360.48315)
		(width 0.09525)
		(layer "B.Cu")
		(net "SAS2X28_A_HDD14_RX_-")
	)
	(arc
		(start 5.553456 -360.1847)
		(mid 5.350416 -360.225105)
		(end 5.178298 -360.340148)
		(width 0.09525)
		(layer "B.Cu")
		(net "SAS2X28_A_HDD14_RX_-")
	)
	(arc
		(start 7.746746 -364.3757)
		(mid 7.810831 -364.279791)
		(end 7.83336 -364.166658)
		(width 0.09525)
		(layer "B.Cu")
		(net "SAS2X28_A_HDD14_RX_-")
	)
	(arc
		(start 5.178298 -360.340148)
		(mid 5.000813 -360.458739)
		(end 4.791456 -360.500422)
		(width 0.09525)
		(layer "B.Cu")
		(net "SAS2X28_A_HDD14_RX_-")
	)
	(arc
		(start 7.83336 -362.2167)
		(mid 7.748404 -361.789596)
		(end 7.506462 -361.427522)
		(width 0.09525)
		(layer "B.Cu")
		(net "SAS2X28_A_HDD14_RX_-")
	)
	(arc
		(start 6.561836 -360.48315)
		(mid 6.231471 -360.262314)
		(end 5.841746 -360.1847)
		(width 0.09525)
		(layer "B.Cu")
		(net "SAS2X28_A_HDD14_RX_-")
	)
	(segment
		(start 48.577246 -348.7547)
		(end 48.577246 -347.5482)
		(width 0.111252)
		(layer "F.Cu")
		(net "FLT_NET_HDD6")
	)
	(segment
		(start 48.259746 -348.7547)
		(end 48.577246 -348.7547)
		(width 0.111252)
		(layer "F.Cu")
		(net "FLT_NET_HDD6")
	)
	(segment
		(start 44.571666 -350.565466)
		(end 47.43958 -350.565466)
		(width 0.111252)
		(layer "F.Cu")
		(net "FLT_NET_HDD6")
	)
	(segment
		(start 43.759882 -349.753682)
		(end 44.571666 -350.565466)
		(width 0.111252)
		(layer "F.Cu")
		(net "FLT_NET_HDD6")
	)
	(segment
		(start 43.230292 -349.753682)
		(end 43.759882 -349.753682)
		(width 0.111252)
		(layer "F.Cu")
		(net "FLT_NET_HDD6")
	)
	(segment
		(start 47.43958 -350.565466)
		(end 47.561246 -350.4438)
		(width 0.111252)
		(layer "F.Cu")
		(net "FLT_NET_HDD6")
	)
	(segment
		(start 47.561246 -350.4438)
		(end 47.561246 -349.4532)
		(width 0.111252)
		(layer "F.Cu")
		(net "FLT_NET_HDD6")
	)
	(segment
		(start 48.577246 -347.5482)
		(end 48.386746 -347.3577)
		(width 0.111252)
		(layer "F.Cu")
		(net "FLT_NET_HDD6")
	)
	(segment
		(start 47.561246 -349.4532)
		(end 48.259746 -348.7547)
		(width 0.111252)
		(layer "F.Cu")
		(net "FLT_NET_HDD6")
	)
	(via
		(at 48.386746 -347.3577)
		(size 0.7112)
		(drill 0.3556)
		(layers "F.Cu" "B.Cu")
		(net "FLT_NET_HDD6")
	)
	(segment
		(start 190.754 -394.6525)
		(end 189.0395 -394.6525)
		(width 0.111252)
		(layer "F.Cu")
		(net "SW_HDD1_P")
	)
	(segment
		(start 206.4385 -380.4285)
		(end 205.1177 -379.1077)
		(width 0.111252)
		(layer "F.Cu")
		(net "SW_HDD1_P")
	)
	(segment
		(start 192.818258 -392.235944)
		(end 193.42608 -392.235944)
		(width 0.111252)
		(layer "F.Cu")
		(net "SW_HDD1_P")
	)
	(segment
		(start 188.213746 -393.826746)
		(end 188.213746 -383.4257)
		(width 0.111252)
		(layer "F.Cu")
		(net "SW_HDD1_P")
	)
	(segment
		(start 189.0395 -394.6525)
		(end 188.213746 -393.826746)
		(width 0.111252)
		(layer "F.Cu")
		(net "SW_HDD1_P")
	)
	(segment
		(start 207.264 -380.4285)
		(end 206.4385 -380.4285)
		(width 0.111252)
		(layer "F.Cu")
		(net "SW_HDD1_P")
	)
	(segment
		(start 205.1177 -379.1077)
		(end 201.040746 -379.1077)
		(width 0.111252)
		(layer "F.Cu")
		(net "SW_HDD1_P")
	)
	(segment
		(start 192.531746 -379.1077)
		(end 201.040746 -379.1077)
		(width 0.111252)
		(layer "F.Cu")
		(net "SW_HDD1_P")
	)
	(segment
		(start 207.732122 -385.755388)
		(end 207.307434 -385.3307)
		(width 0.111252)
		(layer "F.Cu")
		(net "SW_HDD1_P")
	)
	(segment
		(start 193.68008 -392.489944)
		(end 193.68008 -393.94892)
		(width 0.111252)
		(layer "F.Cu")
		(net "SW_HDD1_P")
	)
	(segment
		(start 207.307434 -385.3307)
		(end 207.307434 -380.471934)
		(width 0.111252)
		(layer "F.Cu")
		(net "SW_HDD1_P")
	)
	(segment
		(start 188.213746 -383.4257)
		(end 192.531746 -379.1077)
		(width 0.111252)
		(layer "F.Cu")
		(net "SW_HDD1_P")
	)
	(segment
		(start 208.85023 -385.755388)
		(end 207.732122 -385.755388)
		(width 0.111252)
		(layer "F.Cu")
		(net "SW_HDD1_P")
	)
	(segment
		(start 207.307434 -380.471934)
		(end 207.264 -380.4285)
		(width 0.111252)
		(layer "F.Cu")
		(net "SW_HDD1_P")
	)
	(segment
		(start 193.68008 -393.94892)
		(end 192.9765 -394.6525)
		(width 0.111252)
		(layer "F.Cu")
		(net "SW_HDD1_P")
	)
	(segment
		(start 193.42608 -392.235944)
		(end 193.68008 -392.489944)
		(width 0.111252)
		(layer "F.Cu")
		(net "SW_HDD1_P")
	)
	(segment
		(start 192.9765 -394.6525)
		(end 190.754 -394.6525)
		(width 0.111252)
		(layer "F.Cu")
		(net "SW_HDD1_P")
	)
	(via
		(at 201.040746 -379.1077)
		(size 0.7112)
		(drill 0.3556)
		(layers "F.Cu" "B.Cu")
		(net "SW_HDD1_P")
	)
	(segment
		(start 75.564746 -23.523702)
		(end 75.564746 -24.7777)
		(width 0.111252)
		(layer "F.Cu")
		(net "HDD_PRSNT14")
	)
	(via
		(at 11.4554 -201.4474)
		(size 0.5588)
		(drill 0.3048)
		(layers "F.Cu" "B.Cu")
		(net "HDD_PRSNT14")
	)
	(via
		(at 16.637 -207.6958)
		(size 0.5588)
		(drill 0.3048)
		(layers "F.Cu" "B.Cu")
		(net "HDD_PRSNT14")
	)
	(via
		(at 75.564746 -24.7777)
		(size 0.5588)
		(drill 0.3048)
		(layers "F.Cu" "B.Cu")
		(net "HDD_PRSNT14")
	)
	(via
		(at 17.525746 -450.4817)
		(size 0.7112)
		(drill 0.3556)
		(layers "F.Cu" "B.Cu")
		(net "HDD_PRSNT14")
	)
	(via
		(at 12.064746 -450.9389)
		(size 0.5588)
		(drill 0.3048)
		(layers "F.Cu" "B.Cu")
		(net "HDD_PRSNT14")
	)
	(via
		(at 25.755346 -453.3138)
		(size 0.5588)
		(drill 0.3048)
		(layers "F.Cu" "B.Cu")
		(net "HDD_PRSNT14")
	)
	(segment
		(start 19.075146 -450.4817)
		(end 17.525746 -450.4817)
		(width 0.111252)
		(layer "B.Cu")
		(net "HDD_PRSNT14")
	)
	(segment
		(start 25.861772 -445.216534)
		(end 25.591262 -444.946024)
		(width 0.111252)
		(layer "B.Cu")
		(net "HDD_PRSNT14")
	)
	(segment
		(start 25.861772 -453.207374)
		(end 25.861772 -445.216534)
		(width 0.111252)
		(layer "B.Cu")
		(net "HDD_PRSNT14")
	)
	(segment
		(start 25.591262 -444.946024)
		(end 24.610822 -444.946024)
		(width 0.111252)
		(layer "B.Cu")
		(net "HDD_PRSNT14")
	)
	(segment
		(start 25.755346 -453.3138)
		(end 25.861772 -453.207374)
		(width 0.111252)
		(layer "B.Cu")
		(net "HDD_PRSNT14")
	)
	(segment
		(start 12.521946 -450.4817)
		(end 12.064746 -450.9389)
		(width 0.111252)
		(layer "B.Cu")
		(net "HDD_PRSNT14")
	)
	(segment
		(start 12.064746 -450.9389)
		(end 11.785346 -451.2183)
		(width 0.111252)
		(layer "B.Cu")
		(net "HDD_PRSNT14")
	)
	(segment
		(start 7.08279 -451.501256)
		(end 2.812542 -451.501256)
		(width 0.111252)
		(layer "B.Cu")
		(net "HDD_PRSNT14")
	)
	(segment
		(start 17.525746 -450.4817)
		(end 12.521946 -450.4817)
		(width 0.111252)
		(layer "B.Cu")
		(net "HDD_PRSNT14")
	)
	(segment
		(start 11.4554 -201.4474)
		(end 8.509254 -198.501254)
		(width 0.111252)
		(layer "B.Cu")
		(net "HDD_PRSNT14")
	)
	(segment
		(start 11.785346 -451.2183)
		(end 7.365746 -451.2183)
		(width 0.111252)
		(layer "B.Cu")
		(net "HDD_PRSNT14")
	)
	(segment
		(start 2.812542 -198.501254)
		(end 2.80924 -198.504556)
		(width 0.111252)
		(layer "B.Cu")
		(net "HDD_PRSNT14")
	)
	(segment
		(start 2.812542 -451.501256)
		(end 2.80924 -451.504558)
		(width 0.111252)
		(layer "B.Cu")
		(net "HDD_PRSNT14")
	)
	(segment
		(start 8.509254 -198.501254)
		(end 2.812542 -198.501254)
		(width 0.111252)
		(layer "B.Cu")
		(net "HDD_PRSNT14")
	)
	(segment
		(start 7.365746 -451.2183)
		(end 7.08279 -451.501256)
		(width 0.111252)
		(layer "B.Cu")
		(net "HDD_PRSNT14")
	)
	(segment
		(start 24.610822 -444.946024)
		(end 19.075146 -450.4817)
		(width 0.111252)
		(layer "B.Cu")
		(net "HDD_PRSNT14")
	)
	(segment
		(start 18.706846 -377.164854)
		(end 18.706846 -377.22429)
		(width 0.14605)
		(layer "In2.Cu")
		(net "HDD_PRSNT14")
	)
	(segment
		(start 18.7071 -377.1646)
		(end 18.706846 -377.164854)
		(width 0.14605)
		(layer "In2.Cu")
		(net "HDD_PRSNT14")
	)
	(segment
		(start 21.112226 -257.620262)
		(end 21.111972 -257.620516)
		(width 0.14605)
		(layer "In2.Cu")
		(net "HDD_PRSNT14")
	)
	(segment
		(start 22.056852 -419.112446)
		(end 22.056852 -419.547802)
		(width 0.14605)
		(layer "In2.Cu")
		(net "HDD_PRSNT14")
	)
	(segment
		(start 17.900396 -247.534684)
		(end 21.427948 -251.062236)
		(width 0.14605)
		(layer "In2.Cu")
		(net "HDD_PRSNT14")
	)
	(segment
		(start 15.99184 -210.854544)
		(end 18.132298 -212.995002)
		(width 0.14605)
		(layer "In2.Cu")
		(net "HDD_PRSNT14")
	)
	(segment
		(start 16.637 -208.729834)
		(end 15.99184 -209.374994)
		(width 0.14605)
		(layer "In2.Cu")
		(net "HDD_PRSNT14")
	)
	(segment
		(start 17.900396 -214.97671)
		(end 17.900396 -247.534684)
		(width 0.14605)
		(layer "In2.Cu")
		(net "HDD_PRSNT14")
	)
	(segment
		(start 22.0091 -418.87267)
		(end 22.056852 -419.112446)
		(width 0.14605)
		(layer "In2.Cu")
		(net "HDD_PRSNT14")
	)
	(segment
		(start 21.427948 -251.062236)
		(end 21.427948 -255.129284)
		(width 0.14605)
		(layer "In2.Cu")
		(net "HDD_PRSNT14")
	)
	(segment
		(start 18.82013 -320.179446)
		(end 18.82013 -348.986348)
		(width 0.14605)
		(layer "In2.Cu")
		(net "HDD_PRSNT14")
	)
	(segment
		(start 21.606002 -303.226978)
		(end 21.606002 -317.393574)
		(width 0.14605)
		(layer "In2.Cu")
		(net "HDD_PRSNT14")
	)
	(segment
		(start 22.0091 -419.787578)
		(end 22.0091 -421.101012)
		(width 0.14605)
		(layer "In2.Cu")
		(net "HDD_PRSNT14")
	)
	(segment
		(start 17.518888 -445.484758)
		(end 12.064746 -450.9389)
		(width 0.14605)
		(layer "In2.Cu")
		(net "HDD_PRSNT14")
	)
	(segment
		(start 22.0091 -421.101012)
		(end 17.518888 -425.591224)
		(width 0.14605)
		(layer "In2.Cu")
		(net "HDD_PRSNT14")
	)
	(segment
		(start 18.132298 -212.995002)
		(end 18.132298 -214.744808)
		(width 0.14605)
		(layer "In2.Cu")
		(net "HDD_PRSNT14")
	)
	(segment
		(start 15.99184 -209.374994)
		(end 15.99184 -210.854544)
		(width 0.14605)
		(layer "In2.Cu")
		(net "HDD_PRSNT14")
	)
	(segment
		(start 21.393912 -303.014888)
		(end 21.606002 -303.226978)
		(width 0.14605)
		(layer "In2.Cu")
		(net "HDD_PRSNT14")
	)
	(segment
		(start 17.576546 -413.13862)
		(end 22.0091 -417.571174)
		(width 0.14605)
		(layer "In2.Cu")
		(net "HDD_PRSNT14")
	)
	(segment
		(start 22.507702 -357.614474)
		(end 18.7071 -361.415076)
		(width 0.14605)
		(layer "In2.Cu")
		(net "HDD_PRSNT14")
	)
	(segment
		(start 17.668748 -397.96593)
		(end 17.576546 -398.058132)
		(width 0.14605)
		(layer "In2.Cu")
		(net "HDD_PRSNT14")
	)
	(segment
		(start 22.0091 -417.571174)
		(end 22.0091 -418.87267)
		(width 0.14605)
		(layer "In2.Cu")
		(net "HDD_PRSNT14")
	)
	(segment
		(start 18.413222 -395.38021)
		(end 17.668748 -396.124684)
		(width 0.14605)
		(layer "In2.Cu")
		(net "HDD_PRSNT14")
	)
	(segment
		(start 21.606002 -317.393574)
		(end 18.82013 -320.179446)
		(width 0.14605)
		(layer "In2.Cu")
		(net "HDD_PRSNT14")
	)
	(segment
		(start 17.518888 -425.591224)
		(end 17.518888 -445.484758)
		(width 0.14605)
		(layer "In2.Cu")
		(net "HDD_PRSNT14")
	)
	(segment
		(start 17.668748 -396.124684)
		(end 17.668748 -397.96593)
		(width 0.14605)
		(layer "In2.Cu")
		(net "HDD_PRSNT14")
	)
	(segment
		(start 18.413222 -377.517914)
		(end 18.413222 -395.38021)
		(width 0.14605)
		(layer "In2.Cu")
		(net "HDD_PRSNT14")
	)
	(segment
		(start 18.7071 -361.415076)
		(end 18.7071 -377.1646)
		(width 0.14605)
		(layer "In2.Cu")
		(net "HDD_PRSNT14")
	)
	(segment
		(start 20.970748 -255.586484)
		(end 20.970748 -256.731516)
		(width 0.14605)
		(layer "In2.Cu")
		(net "HDD_PRSNT14")
	)
	(segment
		(start 18.132298 -214.744808)
		(end 17.900396 -214.97671)
		(width 0.14605)
		(layer "In2.Cu")
		(net "HDD_PRSNT14")
	)
	(segment
		(start 21.112226 -256.872994)
		(end 21.112226 -257.620262)
		(width 0.14605)
		(layer "In2.Cu")
		(net "HDD_PRSNT14")
	)
	(segment
		(start 21.111972 -257.620516)
		(end 21.111972 -302.732694)
		(width 0.14605)
		(layer "In2.Cu")
		(net "HDD_PRSNT14")
	)
	(segment
		(start 20.970748 -256.731516)
		(end 21.112226 -256.872994)
		(width 0.14605)
		(layer "In2.Cu")
		(net "HDD_PRSNT14")
	)
	(segment
		(start 22.056852 -419.547802)
		(end 22.0091 -419.787578)
		(width 0.14605)
		(layer "In2.Cu")
		(net "HDD_PRSNT14")
	)
	(segment
		(start 21.427948 -255.129284)
		(end 20.970748 -255.586484)
		(width 0.14605)
		(layer "In2.Cu")
		(net "HDD_PRSNT14")
	)
	(segment
		(start 18.82013 -348.986348)
		(end 22.507702 -352.67392)
		(width 0.14605)
		(layer "In2.Cu")
		(net "HDD_PRSNT14")
	)
	(segment
		(start 22.507702 -352.67392)
		(end 22.507702 -357.614474)
		(width 0.14605)
		(layer "In2.Cu")
		(net "HDD_PRSNT14")
	)
	(segment
		(start 16.637 -207.6958)
		(end 16.637 -208.729834)
		(width 0.14605)
		(layer "In2.Cu")
		(net "HDD_PRSNT14")
	)
	(segment
		(start 18.706846 -377.22429)
		(end 18.413222 -377.517914)
		(width 0.14605)
		(layer "In2.Cu")
		(net "HDD_PRSNT14")
	)
	(segment
		(start 17.576546 -398.058132)
		(end 17.576546 -413.13862)
		(width 0.14605)
		(layer "In2.Cu")
		(net "HDD_PRSNT14")
	)
	(segment
		(start 21.111972 -302.732694)
		(end 21.393912 -303.014888)
		(width 0.14605)
		(layer "In2.Cu")
		(net "HDD_PRSNT14")
	)
	(segment
		(start 50.734722 -453.25665)
		(end 50.795174 -453.317102)
		(width 0.14605)
		(layer "In5.Cu")
		(net "HDD_PRSNT14")
	)
	(segment
		(start 101.171248 -159.786828)
		(end 101.155246 -159.770826)
		(width 0.14605)
		(layer "In5.Cu")
		(net "HDD_PRSNT14")
	)
	(segment
		(start 101.155246 -160.573974)
		(end 101.171248 -160.557972)
		(width 0.14605)
		(layer "In5.Cu")
		(net "HDD_PRSNT14")
	)
	(segment
		(start 101.155246 -103.5304)
		(end 101.021896 -103.39705)
		(width 0.14605)
		(layer "In5.Cu")
		(net "HDD_PRSNT14")
	)
	(segment
		(start 51.62677 -453.25665)
		(end 87.3252 -453.25665)
		(width 0.14605)
		(layer "In5.Cu")
		(net "HDD_PRSNT14")
	)
	(segment
		(start 11.4554 -201.4474)
		(end 11.4554 -202.5142)
		(width 0.14605)
		(layer "In5.Cu")
		(net "HDD_PRSNT14")
	)
	(segment
		(start 25.755346 -453.3138)
		(end 29.930852 -453.3138)
		(width 0.14605)
		(layer "In5.Cu")
		(net "HDD_PRSNT14")
	)
	(segment
		(start 11.4554 -202.5142)
		(end 16.637 -207.6958)
		(width 0.14605)
		(layer "In5.Cu")
		(net "HDD_PRSNT14")
	)
	(segment
		(start 101.021896 -50.23485)
		(end 75.564746 -24.7777)
		(width 0.14605)
		(layer "In5.Cu")
		(net "HDD_PRSNT14")
	)
	(segment
		(start 101.155246 -159.770826)
		(end 101.155246 -103.5304)
		(width 0.14605)
		(layer "In5.Cu")
		(net "HDD_PRSNT14")
	)
	(segment
		(start 51.566318 -453.317102)
		(end 51.62677 -453.25665)
		(width 0.14605)
		(layer "In5.Cu")
		(net "HDD_PRSNT14")
	)
	(segment
		(start 29.930852 -453.3138)
		(end 29.988002 -453.25665)
		(width 0.14605)
		(layer "In5.Cu")
		(net "HDD_PRSNT14")
	)
	(segment
		(start 101.021896 -103.39705)
		(end 101.021896 -50.23485)
		(width 0.14605)
		(layer "In5.Cu")
		(net "HDD_PRSNT14")
	)
	(segment
		(start 101.171248 -160.557972)
		(end 101.171248 -159.786828)
		(width 0.14605)
		(layer "In5.Cu")
		(net "HDD_PRSNT14")
	)
	(segment
		(start 87.3252 -453.25665)
		(end 101.155246 -439.426604)
		(width 0.14605)
		(layer "In5.Cu")
		(net "HDD_PRSNT14")
	)
	(segment
		(start 50.795174 -453.317102)
		(end 51.566318 -453.317102)
		(width 0.14605)
		(layer "In5.Cu")
		(net "HDD_PRSNT14")
	)
	(segment
		(start 101.155246 -439.426604)
		(end 101.155246 -160.573974)
		(width 0.14605)
		(layer "In5.Cu")
		(net "HDD_PRSNT14")
	)
	(segment
		(start 29.988002 -453.25665)
		(end 50.734722 -453.25665)
		(width 0.14605)
		(layer "In5.Cu")
		(net "HDD_PRSNT14")
	)
	(segment
		(start 193.128138 -495.313462)
		(end 193.026538 -495.211862)
		(width 0.111252)
		(layer "F.Cu")
		(net "SW_HDD0_P")
	)
	(segment
		(start 192.462912 -497.390674)
		(end 192.945004 -496.908582)
		(width 0.111252)
		(layer "F.Cu")
		(net "SW_HDD0_P")
	)
	(segment
		(start 188.4426 -496.632738)
		(end 189.205362 -497.3955)
		(width 0.111252)
		(layer "F.Cu")
		(net "SW_HDD0_P")
	)
	(segment
		(start 190.373 -497.3955)
		(end 192.451482 -497.3955)
		(width 0.111252)
		(layer "F.Cu")
		(net "SW_HDD0_P")
	)
	(segment
		(start 207.264 -483.8065)
		(end 207.264 -488.915456)
		(width 0.111252)
		(layer "F.Cu")
		(net "SW_HDD0_P")
	)
	(segment
		(start 205.6257 -482.4857)
		(end 206.8195 -483.6795)
		(width 0.111252)
		(layer "F.Cu")
		(net "SW_HDD0_P")
	)
	(segment
		(start 207.391254 -489.04271)
		(end 208.644744 -489.04271)
		(width 0.111252)
		(layer "F.Cu")
		(net "SW_HDD0_P")
	)
	(segment
		(start 188.4426 -488.98302)
		(end 188.4426 -496.632738)
		(width 0.111252)
		(layer "F.Cu")
		(net "SW_HDD0_P")
	)
	(segment
		(start 191.673988 -485.744774)
		(end 191.358774 -486.059988)
		(width 0.111252)
		(layer "F.Cu")
		(net "SW_HDD0_P")
	)
	(segment
		(start 193.026538 -495.211862)
		(end 192.306956 -495.211862)
		(width 0.111252)
		(layer "F.Cu")
		(net "SW_HDD0_P")
	)
	(segment
		(start 206.8195 -483.6795)
		(end 207.137 -483.6795)
		(width 0.111252)
		(layer "F.Cu")
		(net "SW_HDD0_P")
	)
	(segment
		(start 193.123312 -496.730528)
		(end 193.123312 -496.72367)
		(width 0.111252)
		(layer "F.Cu")
		(net "SW_HDD0_P")
	)
	(segment
		(start 194.93992 -482.4857)
		(end 191.680846 -485.744774)
		(width 0.111252)
		(layer "F.Cu")
		(net "SW_HDD0_P")
	)
	(segment
		(start 191.358774 -486.066846)
		(end 188.4426 -488.98302)
		(width 0.111252)
		(layer "F.Cu")
		(net "SW_HDD0_P")
	)
	(segment
		(start 200.786746 -482.4857)
		(end 194.93992 -482.4857)
		(width 0.111252)
		(layer "F.Cu")
		(net "SW_HDD0_P")
	)
	(segment
		(start 192.456308 -497.390674)
		(end 192.462912 -497.390674)
		(width 0.111252)
		(layer "F.Cu")
		(net "SW_HDD0_P")
	)
	(segment
		(start 191.680846 -485.744774)
		(end 191.673988 -485.744774)
		(width 0.111252)
		(layer "F.Cu")
		(net "SW_HDD0_P")
	)
	(segment
		(start 200.786746 -482.4857)
		(end 205.6257 -482.4857)
		(width 0.111252)
		(layer "F.Cu")
		(net "SW_HDD0_P")
	)
	(segment
		(start 189.205362 -497.3955)
		(end 190.373 -497.3955)
		(width 0.111252)
		(layer "F.Cu")
		(net "SW_HDD0_P")
	)
	(segment
		(start 193.128138 -496.718844)
		(end 193.128138 -495.313462)
		(width 0.111252)
		(layer "F.Cu")
		(net "SW_HDD0_P")
	)
	(segment
		(start 207.264 -488.915456)
		(end 207.391254 -489.04271)
		(width 0.111252)
		(layer "F.Cu")
		(net "SW_HDD0_P")
	)
	(segment
		(start 207.137 -483.6795)
		(end 207.264 -483.8065)
		(width 0.111252)
		(layer "F.Cu")
		(net "SW_HDD0_P")
	)
	(segment
		(start 192.451482 -497.3955)
		(end 192.456308 -497.390674)
		(width 0.111252)
		(layer "F.Cu")
		(net "SW_HDD0_P")
	)
	(segment
		(start 192.945004 -496.908582)
		(end 193.123312 -496.730528)
		(width 0.111252)
		(layer "F.Cu")
		(net "SW_HDD0_P")
	)
	(segment
		(start 193.123312 -496.72367)
		(end 193.128138 -496.718844)
		(width 0.111252)
		(layer "F.Cu")
		(net "SW_HDD0_P")
	)
	(segment
		(start 191.358774 -486.059988)
		(end 191.358774 -486.066846)
		(width 0.111252)
		(layer "F.Cu")
		(net "SW_HDD0_P")
	)
	(via
		(at 200.786746 -482.4857)
		(size 0.7112)
		(drill 0.3556)
		(layers "F.Cu" "B.Cu")
		(net "SW_HDD0_P")
	)
	(segment
		(start 4.625086 -362.498894)
		(end 3.192526 -362.498894)
		(width 0.09525)
		(layer "F.Cu")
		(net "SAS2X28_A_HDD14_TX_-")
	)
	(segment
		(start 24.9428 -159.964628)
		(end 24.9428 -184.444132)
		(width 0.09525)
		(layer "F.Cu")
		(net "SAS2X28_A_HDD14_TX_-")
	)
	(segment
		(start 27.667966 -124.863606)
		(end 29.25318 -126.44882)
		(width 0.09525)
		(layer "F.Cu")
		(net "SAS2X28_A_HDD14_TX_-")
	)
	(segment
		(start 30.62478 -191.04102)
		(end 30.845252 -191.261492)
		(width 0.09525)
		(layer "F.Cu")
		(net "SAS2X28_A_HDD14_TX_-")
	)
	(segment
		(start 29.207714 -154.647646)
		(end 25.686766 -158.168594)
		(width 0.09525)
		(layer "F.Cu")
		(net "SAS2X28_A_HDD14_TX_-")
	)
	(segment
		(start 23.11019 -39.72179)
		(end 23.13813 -39.74973)
		(width 0.09525)
		(layer "F.Cu")
		(net "SAS2X28_A_HDD14_TX_-")
	)
	(segment
		(start 9.376664 -357.822754)
		(end 9.376664 -359.228898)
		(width 0.09525)
		(layer "F.Cu")
		(net "SAS2X28_A_HDD14_TX_-")
	)
	(segment
		(start 26.924 -41.777412)
		(end 26.924 -123.067572)
		(width 0.09525)
		(layer "F.Cu")
		(net "SAS2X28_A_HDD14_TX_-")
	)
	(segment
		(start 31.75 -193.446146)
		(end 31.75 -252.414532)
		(width 0.09525)
		(layer "F.Cu")
		(net "SAS2X28_A_HDD14_TX_-")
	)
	(segment
		(start 10.840466 -355.90734)
		(end 10.840212 -355.90734)
		(width 0.09525)
		(layer "F.Cu")
		(net "SAS2X28_A_HDD14_TX_-")
	)
	(segment
		(start 30.909514 -254.444246)
		(end 11.962384 -273.391122)
		(width 0.09525)
		(layer "F.Cu")
		(net "SAS2X28_A_HDD14_TX_-")
	)
	(segment
		(start 9.077706 -359.95102)
		(end 7.575042 -361.453684)
		(width 0.09525)
		(layer "F.Cu")
		(net "SAS2X28_A_HDD14_TX_-")
	)
	(segment
		(start 23.172166 -39.832026)
		(end 23.172166 -40.024812)
		(width 0.09525)
		(layer "F.Cu")
		(net "SAS2X28_A_HDD14_TX_-")
	)
	(segment
		(start 4.62661 -362.500418)
		(end 4.625086 -362.498894)
		(width 0.09525)
		(layer "F.Cu")
		(net "SAS2X28_A_HDD14_TX_-")
	)
	(segment
		(start 5.867908 -362.16082)
		(end 5.446522 -362.16082)
		(width 0.09525)
		(layer "F.Cu")
		(net "SAS2X28_A_HDD14_TX_-")
	)
	(segment
		(start 23.273766 -40.126412)
		(end 25.273 -40.126412)
		(width 0.09525)
		(layer "F.Cu")
		(net "SAS2X28_A_HDD14_TX_-")
	)
	(segment
		(start 21.75002 -39.659814)
		(end 22.960584 -39.659814)
		(width 0.09525)
		(layer "F.Cu")
		(net "SAS2X28_A_HDD14_TX_-")
	)
	(segment
		(start 10.903712 -355.844094)
		(end 10.840466 -355.90734)
		(width 0.09525)
		(layer "F.Cu")
		(net "SAS2X28_A_HDD14_TX_-")
	)
	(segment
		(start 11.314938 -274.953476)
		(end 11.314938 -354.850954)
		(width 0.09525)
		(layer "F.Cu")
		(net "SAS2X28_A_HDD14_TX_-")
	)
	(segment
		(start 25.590246 -186.006486)
		(end 30.624526 -191.04102)
		(width 0.09525)
		(layer "F.Cu")
		(net "SAS2X28_A_HDD14_TX_-")
	)
	(segment
		(start 10.840212 -355.90734)
		(end 9.696196 -357.051356)
		(width 0.09525)
		(layer "F.Cu")
		(net "SAS2X28_A_HDD14_TX_-")
	)
	(segment
		(start 30.0482 -128.368552)
		(end 30.0482 -152.617932)
		(width 0.09525)
		(layer "F.Cu")
		(net "SAS2X28_A_HDD14_TX_-")
	)
	(segment
		(start 30.624526 -191.04102)
		(end 30.62478 -191.04102)
		(width 0.09525)
		(layer "F.Cu")
		(net "SAS2X28_A_HDD14_TX_-")
	)
	(arc
		(start 23.13813 -39.74973)
		(mid 23.163305 -39.787502)
		(end 23.172166 -39.832026)
		(width 0.09525)
		(layer "F.Cu")
		(net "SAS2X28_A_HDD14_TX_-")
	)
	(arc
		(start 29.25318 -126.44882)
		(mid 29.841645 -127.329615)
		(end 30.0482 -128.368552)
		(width 0.09525)
		(layer "F.Cu")
		(net "SAS2X28_A_HDD14_TX_-")
	)
	(arc
		(start 30.0482 -152.617932)
		(mid 29.829802 -153.716364)
		(end 29.207714 -154.647646)
		(width 0.09525)
		(layer "F.Cu")
		(net "SAS2X28_A_HDD14_TX_-")
	)
	(arc
		(start 9.696196 -357.051356)
		(mid 9.459714 -357.405276)
		(end 9.376664 -357.822754)
		(width 0.09525)
		(layer "F.Cu")
		(net "SAS2X28_A_HDD14_TX_-")
	)
	(arc
		(start 31.75 -252.414532)
		(mid 31.531602 -253.512964)
		(end 30.909514 -254.444246)
		(width 0.09525)
		(layer "F.Cu")
		(net "SAS2X28_A_HDD14_TX_-")
	)
	(arc
		(start 26.924 -123.067572)
		(mid 27.117346 -124.039588)
		(end 27.667966 -124.863606)
		(width 0.09525)
		(layer "F.Cu")
		(net "SAS2X28_A_HDD14_TX_-")
	)
	(arc
		(start 5.446522 -362.16082)
		(mid 5.324728 -362.185046)
		(end 5.221478 -362.254038)
		(width 0.09525)
		(layer "F.Cu")
		(net "SAS2X28_A_HDD14_TX_-")
	)
	(arc
		(start 5.221478 -362.254038)
		(mid 4.94855 -362.436402)
		(end 4.62661 -362.500418)
		(width 0.09525)
		(layer "F.Cu")
		(net "SAS2X28_A_HDD14_TX_-")
	)
	(arc
		(start 23.172166 -40.024812)
		(mid 23.191063 -40.083827)
		(end 23.240746 -40.120824)
		(width 0.09525)
		(layer "F.Cu")
		(net "SAS2X28_A_HDD14_TX_-")
	)
	(arc
		(start 11.314938 -354.850954)
		(mid 11.208067 -355.38841)
		(end 10.903712 -355.844094)
		(width 0.09525)
		(layer "F.Cu")
		(net "SAS2X28_A_HDD14_TX_-")
	)
	(arc
		(start 9.376664 -359.228898)
		(mid 9.298969 -359.619677)
		(end 9.077706 -359.95102)
		(width 0.09525)
		(layer "F.Cu")
		(net "SAS2X28_A_HDD14_TX_-")
	)
	(arc
		(start 7.575042 -361.453684)
		(mid 6.791802 -361.977028)
		(end 5.867908 -362.16082)
		(width 0.09525)
		(layer "F.Cu")
		(net "SAS2X28_A_HDD14_TX_-")
	)
	(arc
		(start 24.9428 -184.444132)
		(mid 25.111109 -185.289718)
		(end 25.590246 -186.006486)
		(width 0.09525)
		(layer "F.Cu")
		(net "SAS2X28_A_HDD14_TX_-")
	)
	(arc
		(start 11.962384 -273.391122)
		(mid 11.483287 -274.107907)
		(end 11.314938 -274.953476)
		(width 0.09525)
		(layer "F.Cu")
		(net "SAS2X28_A_HDD14_TX_-")
	)
	(arc
		(start 22.960584 -39.659814)
		(mid 23.041553 -39.67592)
		(end 23.11019 -39.72179)
		(width 0.09525)
		(layer "F.Cu")
		(net "SAS2X28_A_HDD14_TX_-")
	)
	(arc
		(start 30.845252 -191.261492)
		(mid 31.514879 -192.263848)
		(end 31.75 -193.446146)
		(width 0.09525)
		(layer "F.Cu")
		(net "SAS2X28_A_HDD14_TX_-")
	)
	(arc
		(start 23.240746 -40.120824)
		(mid 23.241887 -40.121212)
		(end 23.243032 -40.121586)
		(width 0.09525)
		(layer "F.Cu")
		(net "SAS2X28_A_HDD14_TX_-")
	)
	(arc
		(start 25.686766 -158.168594)
		(mid 25.136168 -158.992621)
		(end 24.9428 -159.964628)
		(width 0.09525)
		(layer "F.Cu")
		(net "SAS2X28_A_HDD14_TX_-")
	)
	(arc
		(start 23.243032 -40.121586)
		(mid 23.258213 -40.125189)
		(end 23.273766 -40.126412)
		(width 0.09525)
		(layer "F.Cu")
		(net "SAS2X28_A_HDD14_TX_-")
	)
	(arc
		(start 25.273 -40.126412)
		(mid 26.440433 -40.609979)
		(end 26.924 -41.777412)
		(width 0.09525)
		(layer "F.Cu")
		(net "SAS2X28_A_HDD14_TX_-")
	)
	(segment
		(start 202.253596 -391.4267)
		(end 201.675746 -391.4267)
		(width 0.111252)
		(layer "F.Cu")
		(net "SAS2X28_B_HDD1_FLT")
	)
	(segment
		(start 201.675746 -391.4267)
		(end 201.374502 -391.125456)
		(width 0.111252)
		(layer "F.Cu")
		(net "SAS2X28_B_HDD1_FLT")
	)
	(segment
		(start 201.374502 -391.125456)
		(end 201.374502 -390.049512)
		(width 0.111252)
		(layer "F.Cu")
		(net "SAS2X28_B_HDD1_FLT")
	)
	(segment
		(start 202.801474 -390.878822)
		(end 202.253596 -391.4267)
		(width 0.111252)
		(layer "F.Cu")
		(net "SAS2X28_B_HDD1_FLT")
	)
	(via
		(at 99.313746 -385.520692)
		(size 0.5588)
		(drill 0.3048)
		(layers "F.Cu" "B.Cu")
		(net "SAS2X28_B_HDD1_FLT")
	)
	(via
		(at 6.497574 -144.211802)
		(size 0.5588)
		(drill 0.3048)
		(layers "F.Cu" "B.Cu")
		(net "SAS2X28_B_HDD1_FLT")
	)
	(via
		(at 202.615546 -391.4267)
		(size 0.7112)
		(drill 0.3556)
		(layers "F.Cu" "B.Cu")
		(net "SAS2X28_B_HDD1_FLT")
	)
	(via
		(at 201.675746 -391.4267)
		(size 0.5588)
		(drill 0.3048)
		(layers "F.Cu" "B.Cu")
		(net "SAS2X28_B_HDD1_FLT")
	)
	(segment
		(start 6.20903 -144.500346)
		(end 2.81305 -144.500346)
		(width 0.111252)
		(layer "B.Cu")
		(net "SAS2X28_B_HDD1_FLT")
	)
	(segment
		(start 2.81305 -144.500346)
		(end 2.811526 -144.498822)
		(width 0.111252)
		(layer "B.Cu")
		(net "SAS2X28_B_HDD1_FLT")
	)
	(segment
		(start 202.615546 -391.4267)
		(end 201.675746 -391.4267)
		(width 0.111252)
		(layer "B.Cu")
		(net "SAS2X28_B_HDD1_FLT")
	)
	(segment
		(start 6.497574 -144.211802)
		(end 6.20903 -144.500346)
		(width 0.111252)
		(layer "B.Cu")
		(net "SAS2X28_B_HDD1_FLT")
	)
	(segment
		(start 195.84035 -388.3914)
		(end 196.17055 -388.0612)
		(width 0.14605)
		(layer "In2.Cu")
		(net "SAS2X28_B_HDD1_FLT")
	)
	(segment
		(start 196.17055 -388.0612)
		(end 197.9803 -388.0612)
		(width 0.14605)
		(layer "In2.Cu")
		(net "SAS2X28_B_HDD1_FLT")
	)
	(segment
		(start 189.835536 -388.3914)
		(end 195.84035 -388.3914)
		(width 0.14605)
		(layer "In2.Cu")
		(net "SAS2X28_B_HDD1_FLT")
	)
	(segment
		(start 99.377754 -385.5847)
		(end 187.028836 -385.5847)
		(width 0.14605)
		(layer "In2.Cu")
		(net "SAS2X28_B_HDD1_FLT")
	)
	(segment
		(start 99.313746 -385.520692)
		(end 99.377754 -385.5847)
		(width 0.14605)
		(layer "In2.Cu")
		(net "SAS2X28_B_HDD1_FLT")
	)
	(segment
		(start 201.3458 -391.4267)
		(end 201.675746 -391.4267)
		(width 0.14605)
		(layer "In2.Cu")
		(net "SAS2X28_B_HDD1_FLT")
	)
	(segment
		(start 187.028836 -385.5847)
		(end 189.835536 -388.3914)
		(width 0.14605)
		(layer "In2.Cu")
		(net "SAS2X28_B_HDD1_FLT")
	)
	(segment
		(start 197.9803 -388.0612)
		(end 201.3458 -391.4267)
		(width 0.14605)
		(layer "In2.Cu")
		(net "SAS2X28_B_HDD1_FLT")
	)
	(segment
		(start 6.497574 -139.977114)
		(end 6.497574 -144.211802)
		(width 0.14605)
		(layer "In5.Cu")
		(net "SAS2X28_B_HDD1_FLT")
	)
	(segment
		(start 98.69043 -106.696002)
		(end 88.777826 -96.783398)
		(width 0.14605)
		(layer "In5.Cu")
		(net "SAS2X28_B_HDD1_FLT")
	)
	(segment
		(start 20.399756 -96.783398)
		(end 8.874252 -108.308902)
		(width 0.14605)
		(layer "In5.Cu")
		(net "SAS2X28_B_HDD1_FLT")
	)
	(segment
		(start 99.313746 -385.520692)
		(end 98.69043 -384.897376)
		(width 0.14605)
		(layer "In5.Cu")
		(net "SAS2X28_B_HDD1_FLT")
	)
	(segment
		(start 8.874252 -108.308902)
		(end 8.874252 -130.188462)
		(width 0.14605)
		(layer "In5.Cu")
		(net "SAS2X28_B_HDD1_FLT")
	)
	(segment
		(start 7.69112 -136.270746)
		(end 7.69112 -138.783314)
		(width 0.14605)
		(layer "In5.Cu")
		(net "SAS2X28_B_HDD1_FLT")
	)
	(segment
		(start 8.874252 -130.188462)
		(end 8.049514 -131.0132)
		(width 0.14605)
		(layer "In5.Cu")
		(net "SAS2X28_B_HDD1_FLT")
	)
	(segment
		(start 98.69043 -384.897376)
		(end 98.69043 -106.696002)
		(width 0.14605)
		(layer "In5.Cu")
		(net "SAS2X28_B_HDD1_FLT")
	)
	(segment
		(start 8.035544 -132.913628)
		(end 7.982204 -133.519418)
		(width 0.14605)
		(layer "In5.Cu")
		(net "SAS2X28_B_HDD1_FLT")
	)
	(segment
		(start 7.982204 -133.519418)
		(end 7.982204 -135.979662)
		(width 0.14605)
		(layer "In5.Cu")
		(net "SAS2X28_B_HDD1_FLT")
	)
	(segment
		(start 8.049514 -131.0132)
		(end 8.049514 -132.899912)
		(width 0.14605)
		(layer "In5.Cu")
		(net "SAS2X28_B_HDD1_FLT")
	)
	(segment
		(start 7.982204 -135.979662)
		(end 7.69112 -136.270746)
		(width 0.14605)
		(layer "In5.Cu")
		(net "SAS2X28_B_HDD1_FLT")
	)
	(segment
		(start 7.69112 -138.783314)
		(end 7.454392 -139.020296)
		(width 0.14605)
		(layer "In5.Cu")
		(net "SAS2X28_B_HDD1_FLT")
	)
	(segment
		(start 8.049514 -132.899912)
		(end 8.035544 -132.913628)
		(width 0.14605)
		(layer "In5.Cu")
		(net "SAS2X28_B_HDD1_FLT")
	)
	(segment
		(start 7.454392 -139.020296)
		(end 6.497574 -139.977114)
		(width 0.14605)
		(layer "In5.Cu")
		(net "SAS2X28_B_HDD1_FLT")
	)
	(segment
		(start 88.777826 -96.783398)
		(end 20.399756 -96.783398)
		(width 0.14605)
		(layer "In5.Cu")
		(net "SAS2X28_B_HDD1_FLT")
	)
	(segment
		(start 101.599746 -9.9822)
		(end 102.742746 -9.9822)
		(width 0.111252)
		(layer "F.Cu")
		(net "SW_PWR_R_HDD14")
	)
	(segment
		(start 101.536246 -9.9187)
		(end 101.599746 -9.9822)
		(width 0.111252)
		(layer "F.Cu")
		(net "SW_PWR_R_HDD14")
	)
	(segment
		(start 100.126546 -9.9187)
		(end 101.536246 -9.9187)
		(width 0.111252)
		(layer "F.Cu")
		(net "SW_PWR_R_HDD14")
	)
	(via
		(at 102.742746 -9.9822)
		(size 0.7112)
		(drill 0.3556)
		(layers "F.Cu" "B.Cu")
		(net "SW_PWR_R_HDD14")
	)
	(segment
		(start 26.36139 -57.984136)
		(end 26.36139 -58.269886)
		(width 0.09525)
		(layer "F.Cu")
		(net "SAS2X28_A_HDD14_TX_+")
	)
	(segment
		(start 4.625594 -361.498896)
		(end 3.192526 -361.498896)
		(width 0.09525)
		(layer "F.Cu")
		(net "SAS2X28_A_HDD14_TX_+")
	)
	(segment
		(start 23.273766 -40.456612)
		(end 25.273 -40.456612)
		(width 0.09525)
		(layer "F.Cu")
		(net "SAS2X28_A_HDD14_TX_+")
	)
	(segment
		(start 26.5938 -86.143338)
		(end 26.5938 -123.067572)
		(width 0.09525)
		(layer "F.Cu")
		(net "SAS2X28_A_HDD14_TX_+")
	)
	(segment
		(start 9.046464 -357.8225)
		(end 9.046464 -359.228644)
		(width 0.09525)
		(layer "F.Cu")
		(net "SAS2X28_A_HDD14_TX_+")
	)
	(segment
		(start 26.5938 -60.235846)
		(end 26.5938 -81.925668)
		(width 0.09525)
		(layer "F.Cu")
		(net "SAS2X28_A_HDD14_TX_+")
	)
	(segment
		(start 21.75002 -40.929814)
		(end 23.011638 -40.929814)
		(width 0.09525)
		(layer "F.Cu")
		(net "SAS2X28_A_HDD14_TX_+")
	)
	(segment
		(start 23.172166 -40.769286)
		(end 23.172166 -40.558212)
		(width 0.09525)
		(layer "F.Cu")
		(net "SAS2X28_A_HDD14_TX_+")
	)
	(segment
		(start 26.36139 -49.669446)
		(end 26.36139 -49.955196)
		(width 0.09525)
		(layer "F.Cu")
		(net "SAS2X28_A_HDD14_TX_+")
	)
	(segment
		(start 24.6126 -159.964628)
		(end 24.6126 -184.444132)
		(width 0.09525)
		(layer "F.Cu")
		(net "SAS2X28_A_HDD14_TX_+")
	)
	(segment
		(start 30.675834 -254.210566)
		(end 11.728704 -273.157442)
		(width 0.09525)
		(layer "F.Cu")
		(net "SAS2X28_A_HDD14_TX_+")
	)
	(segment
		(start 26.5938 -58.734706)
		(end 26.5938 -59.020456)
		(width 0.09525)
		(layer "F.Cu")
		(net "SAS2X28_A_HDD14_TX_+")
	)
	(segment
		(start 26.36139 -82.390488)
		(end 26.36139 -82.676238)
		(width 0.09525)
		(layer "F.Cu")
		(net "SAS2X28_A_HDD14_TX_+")
	)
	(segment
		(start 29.718 -128.368806)
		(end 29.718 -152.617932)
		(width 0.09525)
		(layer "F.Cu")
		(net "SAS2X28_A_HDD14_TX_+")
	)
	(segment
		(start 26.5938 -84.642198)
		(end 26.5938 -84.927948)
		(width 0.09525)
		(layer "F.Cu")
		(net "SAS2X28_A_HDD14_TX_+")
	)
	(segment
		(start 26.5938 -57.233566)
		(end 26.5938 -57.519316)
		(width 0.09525)
		(layer "F.Cu")
		(net "SAS2X28_A_HDD14_TX_+")
	)
	(segment
		(start 26.36139 -85.392768)
		(end 26.36139 -85.678518)
		(width 0.09525)
		(layer "F.Cu")
		(net "SAS2X28_A_HDD14_TX_+")
	)
	(segment
		(start 26.5938 -83.141058)
		(end 26.5938 -83.426808)
		(width 0.09525)
		(layer "F.Cu")
		(net "SAS2X28_A_HDD14_TX_+")
	)
	(segment
		(start 28.974034 -154.413966)
		(end 25.453086 -157.934914)
		(width 0.09525)
		(layer "F.Cu")
		(net "SAS2X28_A_HDD14_TX_+")
	)
	(segment
		(start 26.5938 -41.777412)
		(end 26.5938 -49.204626)
		(width 0.09525)
		(layer "F.Cu")
		(net "SAS2X28_A_HDD14_TX_+")
	)
	(segment
		(start 26.5938 -50.420016)
		(end 26.5938 -56.018176)
		(width 0.09525)
		(layer "F.Cu")
		(net "SAS2X28_A_HDD14_TX_+")
	)
	(segment
		(start 5.8674 -361.83062)
		(end 5.424424 -361.83062)
		(width 0.09525)
		(layer "F.Cu")
		(net "SAS2X28_A_HDD14_TX_+")
	)
	(segment
		(start 10.984738 -274.953476)
		(end 10.984738 -354.8507)
		(width 0.09525)
		(layer "F.Cu")
		(net "SAS2X28_A_HDD14_TX_+")
	)
	(segment
		(start 25.356566 -186.240166)
		(end 30.611572 -191.495172)
		(width 0.09525)
		(layer "F.Cu")
		(net "SAS2X28_A_HDD14_TX_+")
	)
	(segment
		(start 26.36139 -59.485276)
		(end 26.36139 -59.771026)
		(width 0.09525)
		(layer "F.Cu")
		(net "SAS2X28_A_HDD14_TX_+")
	)
	(segment
		(start 31.4198 -193.4464)
		(end 31.4198 -252.414532)
		(width 0.09525)
		(layer "F.Cu")
		(net "SAS2X28_A_HDD14_TX_+")
	)
	(segment
		(start 4.627118 -361.50042)
		(end 4.625594 -361.498896)
		(width 0.09525)
		(layer "F.Cu")
		(net "SAS2X28_A_HDD14_TX_+")
	)
	(segment
		(start 26.36139 -56.482996)
		(end 26.36139 -56.768746)
		(width 0.09525)
		(layer "F.Cu")
		(net "SAS2X28_A_HDD14_TX_+")
	)
	(segment
		(start 26.36139 -83.891628)
		(end 26.36139 -84.177378)
		(width 0.09525)
		(layer "F.Cu")
		(net "SAS2X28_A_HDD14_TX_+")
	)
	(segment
		(start 9.462516 -356.817676)
		(end 9.46277 -356.81793)
		(width 0.09525)
		(layer "F.Cu")
		(net "SAS2X28_A_HDD14_TX_+")
	)
	(segment
		(start 27.434286 -125.097286)
		(end 29.0195 -126.6825)
		(width 0.09525)
		(layer "F.Cu")
		(net "SAS2X28_A_HDD14_TX_+")
	)
	(segment
		(start 8.844026 -359.71734)
		(end 7.341362 -361.220004)
		(width 0.09525)
		(layer "F.Cu")
		(net "SAS2X28_A_HDD14_TX_+")
	)
	(segment
		(start 10.670032 -355.610414)
		(end 9.462516 -356.817676)
		(width 0.09525)
		(layer "F.Cu")
		(net "SAS2X28_A_HDD14_TX_+")
	)
	(arc
		(start 23.125176 -40.882824)
		(mid 23.159929 -40.830718)
		(end 23.172166 -40.769286)
		(width 0.09525)
		(layer "F.Cu")
		(net "SAS2X28_A_HDD14_TX_+")
	)
	(arc
		(start 7.341362 -361.220004)
		(mid 6.665117 -361.67192)
		(end 5.8674 -361.83062)
		(width 0.09525)
		(layer "F.Cu")
		(net "SAS2X28_A_HDD14_TX_+")
	)
	(arc
		(start 26.477468 -56.250586)
		(mid 26.391237 -56.352703)
		(end 26.36139 -56.482996)
		(width 0.09525)
		(layer "F.Cu")
		(net "SAS2X28_A_HDD14_TX_+")
	)
	(arc
		(start 26.36139 -59.771026)
		(mid 26.391187 -59.901344)
		(end 26.477468 -60.003436)
		(width 0.09525)
		(layer "F.Cu")
		(net "SAS2X28_A_HDD14_TX_+")
	)
	(arc
		(start 26.36139 -49.955196)
		(mid 26.391187 -50.085514)
		(end 26.477468 -50.187606)
		(width 0.09525)
		(layer "F.Cu")
		(net "SAS2X28_A_HDD14_TX_+")
	)
	(arc
		(start 26.36139 -84.177378)
		(mid 26.391187 -84.307696)
		(end 26.477468 -84.409788)
		(width 0.09525)
		(layer "F.Cu")
		(net "SAS2X28_A_HDD14_TX_+")
	)
	(arc
		(start 26.477468 -82.158078)
		(mid 26.391237 -82.260195)
		(end 26.36139 -82.390488)
		(width 0.09525)
		(layer "F.Cu")
		(net "SAS2X28_A_HDD14_TX_+")
	)
	(arc
		(start 26.477468 -57.751726)
		(mid 26.391237 -57.853843)
		(end 26.36139 -57.984136)
		(width 0.09525)
		(layer "F.Cu")
		(net "SAS2X28_A_HDD14_TX_+")
	)
	(arc
		(start 26.477468 -85.910928)
		(mid 26.563867 -86.013002)
		(end 26.5938 -86.143338)
		(width 0.09525)
		(layer "F.Cu")
		(net "SAS2X28_A_HDD14_TX_+")
	)
	(arc
		(start 26.5938 -81.925668)
		(mid 26.563864 -82.056003)
		(end 26.477468 -82.158078)
		(width 0.09525)
		(layer "F.Cu")
		(net "SAS2X28_A_HDD14_TX_+")
	)
	(arc
		(start 23.24354 -40.46093)
		(mid 23.258489 -40.457616)
		(end 23.273766 -40.456612)
		(width 0.09525)
		(layer "F.Cu")
		(net "SAS2X28_A_HDD14_TX_+")
	)
	(arc
		(start 23.172166 -40.558212)
		(mid 23.191604 -40.498364)
		(end 23.242524 -40.461438)
		(width 0.09525)
		(layer "F.Cu")
		(net "SAS2X28_A_HDD14_TX_+")
	)
	(arc
		(start 5.424424 -361.83062)
		(mid 5.325181 -361.810879)
		(end 5.241036 -361.754674)
		(width 0.09525)
		(layer "F.Cu")
		(net "SAS2X28_A_HDD14_TX_+")
	)
	(arc
		(start 9.46277 -356.81793)
		(mid 9.154777 -357.27883)
		(end 9.046464 -357.8225)
		(width 0.09525)
		(layer "F.Cu")
		(net "SAS2X28_A_HDD14_TX_+")
	)
	(arc
		(start 26.5938 -56.018176)
		(mid 26.563864 -56.148511)
		(end 26.477468 -56.250586)
		(width 0.09525)
		(layer "F.Cu")
		(net "SAS2X28_A_HDD14_TX_+")
	)
	(arc
		(start 26.477468 -58.502296)
		(mid 26.563867 -58.60437)
		(end 26.5938 -58.734706)
		(width 0.09525)
		(layer "F.Cu")
		(net "SAS2X28_A_HDD14_TX_+")
	)
	(arc
		(start 23.242524 -40.461438)
		(mid 23.243031 -40.461183)
		(end 23.24354 -40.46093)
		(width 0.09525)
		(layer "F.Cu")
		(net "SAS2X28_A_HDD14_TX_+")
	)
	(arc
		(start 29.0195 -126.6825)
		(mid 29.536459 -127.456184)
		(end 29.718 -128.368806)
		(width 0.09525)
		(layer "F.Cu")
		(net "SAS2X28_A_HDD14_TX_+")
	)
	(arc
		(start 26.477468 -60.003436)
		(mid 26.563867 -60.10551)
		(end 26.5938 -60.235846)
		(width 0.09525)
		(layer "F.Cu")
		(net "SAS2X28_A_HDD14_TX_+")
	)
	(arc
		(start 26.36139 -58.269886)
		(mid 26.391187 -58.400204)
		(end 26.477468 -58.502296)
		(width 0.09525)
		(layer "F.Cu")
		(net "SAS2X28_A_HDD14_TX_+")
	)
	(arc
		(start 23.011638 -40.929814)
		(mid 23.073084 -40.91761)
		(end 23.125176 -40.882824)
		(width 0.09525)
		(layer "F.Cu")
		(net "SAS2X28_A_HDD14_TX_+")
	)
	(arc
		(start 26.477468 -59.252866)
		(mid 26.391237 -59.354983)
		(end 26.36139 -59.485276)
		(width 0.09525)
		(layer "F.Cu")
		(net "SAS2X28_A_HDD14_TX_+")
	)
	(arc
		(start 26.5938 -83.426808)
		(mid 26.563864 -83.557143)
		(end 26.477468 -83.659218)
		(width 0.09525)
		(layer "F.Cu")
		(net "SAS2X28_A_HDD14_TX_+")
	)
	(arc
		(start 26.36139 -56.768746)
		(mid 26.391187 -56.899064)
		(end 26.477468 -57.001156)
		(width 0.09525)
		(layer "F.Cu")
		(net "SAS2X28_A_HDD14_TX_+")
	)
	(arc
		(start 26.5938 -123.067572)
		(mid 26.812198 -124.166004)
		(end 27.434286 -125.097286)
		(width 0.09525)
		(layer "F.Cu")
		(net "SAS2X28_A_HDD14_TX_+")
	)
	(arc
		(start 5.241036 -361.754674)
		(mid 4.959368 -361.566469)
		(end 4.627118 -361.50042)
		(width 0.09525)
		(layer "F.Cu")
		(net "SAS2X28_A_HDD14_TX_+")
	)
	(arc
		(start 29.718 -152.617932)
		(mid 29.524654 -153.589948)
		(end 28.974034 -154.413966)
		(width 0.09525)
		(layer "F.Cu")
		(net "SAS2X28_A_HDD14_TX_+")
	)
	(arc
		(start 26.5938 -57.519316)
		(mid 26.563864 -57.649651)
		(end 26.477468 -57.751726)
		(width 0.09525)
		(layer "F.Cu")
		(net "SAS2X28_A_HDD14_TX_+")
	)
	(arc
		(start 26.477468 -84.409788)
		(mid 26.563867 -84.511862)
		(end 26.5938 -84.642198)
		(width 0.09525)
		(layer "F.Cu")
		(net "SAS2X28_A_HDD14_TX_+")
	)
	(arc
		(start 26.477468 -83.659218)
		(mid 26.391237 -83.761335)
		(end 26.36139 -83.891628)
		(width 0.09525)
		(layer "F.Cu")
		(net "SAS2X28_A_HDD14_TX_+")
	)
	(arc
		(start 26.477468 -57.001156)
		(mid 26.563867 -57.10323)
		(end 26.5938 -57.233566)
		(width 0.09525)
		(layer "F.Cu")
		(net "SAS2X28_A_HDD14_TX_+")
	)
	(arc
		(start 25.453086 -157.934914)
		(mid 24.830934 -158.86617)
		(end 24.6126 -159.964628)
		(width 0.09525)
		(layer "F.Cu")
		(net "SAS2X28_A_HDD14_TX_+")
	)
	(arc
		(start 26.5938 -59.020456)
		(mid 26.563864 -59.150791)
		(end 26.477468 -59.252866)
		(width 0.09525)
		(layer "F.Cu")
		(net "SAS2X28_A_HDD14_TX_+")
	)
	(arc
		(start 26.36139 -85.678518)
		(mid 26.391187 -85.808836)
		(end 26.477468 -85.910928)
		(width 0.09525)
		(layer "F.Cu")
		(net "SAS2X28_A_HDD14_TX_+")
	)
	(arc
		(start 9.046464 -359.228644)
		(mid 8.993855 -359.49313)
		(end 8.844026 -359.71734)
		(width 0.09525)
		(layer "F.Cu")
		(net "SAS2X28_A_HDD14_TX_+")
	)
	(arc
		(start 26.477468 -82.908648)
		(mid 26.563867 -83.010722)
		(end 26.5938 -83.141058)
		(width 0.09525)
		(layer "F.Cu")
		(net "SAS2X28_A_HDD14_TX_+")
	)
	(arc
		(start 31.4198 -252.414532)
		(mid 31.226454 -253.386548)
		(end 30.675834 -254.210566)
		(width 0.09525)
		(layer "F.Cu")
		(net "SAS2X28_A_HDD14_TX_+")
	)
	(arc
		(start 26.477468 -49.437036)
		(mid 26.391237 -49.539153)
		(end 26.36139 -49.669446)
		(width 0.09525)
		(layer "F.Cu")
		(net "SAS2X28_A_HDD14_TX_+")
	)
	(arc
		(start 26.5938 -84.927948)
		(mid 26.563864 -85.058283)
		(end 26.477468 -85.160358)
		(width 0.09525)
		(layer "F.Cu")
		(net "SAS2X28_A_HDD14_TX_+")
	)
	(arc
		(start 24.6126 -184.444132)
		(mid 24.805946 -185.416148)
		(end 25.356566 -186.240166)
		(width 0.09525)
		(layer "F.Cu")
		(net "SAS2X28_A_HDD14_TX_+")
	)
	(arc
		(start 26.477468 -50.187606)
		(mid 26.563867 -50.28968)
		(end 26.5938 -50.420016)
		(width 0.09525)
		(layer "F.Cu")
		(net "SAS2X28_A_HDD14_TX_+")
	)
	(arc
		(start 26.5938 -49.204626)
		(mid 26.563864 -49.334961)
		(end 26.477468 -49.437036)
		(width 0.09525)
		(layer "F.Cu")
		(net "SAS2X28_A_HDD14_TX_+")
	)
	(arc
		(start 26.477468 -85.160358)
		(mid 26.391237 -85.262475)
		(end 26.36139 -85.392768)
		(width 0.09525)
		(layer "F.Cu")
		(net "SAS2X28_A_HDD14_TX_+")
	)
	(arc
		(start 11.728704 -273.157442)
		(mid 11.178106 -273.981469)
		(end 10.984738 -274.953476)
		(width 0.09525)
		(layer "F.Cu")
		(net "SAS2X28_A_HDD14_TX_+")
	)
	(arc
		(start 25.273 -40.456612)
		(mid 26.206947 -40.843465)
		(end 26.5938 -41.777412)
		(width 0.09525)
		(layer "F.Cu")
		(net "SAS2X28_A_HDD14_TX_+")
	)
	(arc
		(start 10.984738 -354.8507)
		(mid 10.902953 -355.261863)
		(end 10.670032 -355.610414)
		(width 0.09525)
		(layer "F.Cu")
		(net "SAS2X28_A_HDD14_TX_+")
	)
	(arc
		(start 26.36139 -82.676238)
		(mid 26.391187 -82.806556)
		(end 26.477468 -82.908648)
		(width 0.09525)
		(layer "F.Cu")
		(net "SAS2X28_A_HDD14_TX_+")
	)
	(arc
		(start 30.611572 -191.495172)
		(mid 31.209746 -192.390403)
		(end 31.4198 -193.4464)
		(width 0.09525)
		(layer "F.Cu")
		(net "SAS2X28_A_HDD14_TX_+")
	)
	(segment
		(start 43.230038 -450.558408)
		(end 43.687746 -450.1007)
		(width 0.111252)
		(layer "F.Cu")
		(net "FLT_NET_HDD5")
	)
	(segment
		(start 43.687746 -450.1007)
		(end 45.037756 -450.1007)
		(width 0.111252)
		(layer "F.Cu")
		(net "FLT_NET_HDD5")
	)
	(segment
		(start 45.037756 -451.767702)
		(end 45.037756 -450.1007)
		(width 0.111252)
		(layer "F.Cu")
		(net "FLT_NET_HDD5")
	)
	(segment
		(start 43.230038 -452.753222)
		(end 43.230038 -450.558408)
		(width 0.111252)
		(layer "F.Cu")
		(net "FLT_NET_HDD5")
	)
	(segment
		(start 43.230292 -452.753476)
		(end 43.230038 -452.753222)
		(width 0.111252)
		(layer "F.Cu")
		(net "FLT_NET_HDD5")
	)
	(via
		(at 45.037756 -450.1007)
		(size 0.7112)
		(drill 0.3556)
		(layers "F.Cu" "B.Cu")
		(net "FLT_NET_HDD5")
	)
	(segment
		(start 38.9128 -110.327948)
		(end 38.9128 -110.738666)
		(width 0.111252)
		(layer "F.Cu")
		(net "SW_PWR_R_HDD13")
	)
	(segment
		(start 38.617398 -111.852202)
		(end 38.353746 -111.852202)
		(width 0.111252)
		(layer "F.Cu")
		(net "SW_PWR_R_HDD13")
	)
	(segment
		(start 38.353746 -111.29772)
		(end 38.353746 -111.852202)
		(width 0.111252)
		(layer "F.Cu")
		(net "SW_PWR_R_HDD13")
	)
	(segment
		(start 39.51732 -109.71657)
		(end 39.51732 -109.723428)
		(width 0.111252)
		(layer "F.Cu")
		(net "SW_PWR_R_HDD13")
	)
	(segment
		(start 39.62781 -109.609636)
		(end 39.624254 -109.609636)
		(width 0.111252)
		(layer "F.Cu")
		(net "SW_PWR_R_HDD13")
	)
	(segment
		(start 39.823898 -110.645702)
		(end 38.617398 -111.852202)
		(width 0.111252)
		(layer "F.Cu")
		(net "SW_PWR_R_HDD13")
	)
	(segment
		(start 39.51732 -109.723428)
		(end 38.9128 -110.327948)
		(width 0.111252)
		(layer "F.Cu")
		(net "SW_PWR_R_HDD13")
	)
	(segment
		(start 39.624254 -109.609636)
		(end 39.51732 -109.71657)
		(width 0.111252)
		(layer "F.Cu")
		(net "SW_PWR_R_HDD13")
	)
	(segment
		(start 38.9128 -110.738666)
		(end 38.353746 -111.29772)
		(width 0.111252)
		(layer "F.Cu")
		(net "SW_PWR_R_HDD13")
	)
	(segment
		(start 41.147746 -108.3183)
		(end 40.995346 -108.4707)
		(width 0.111252)
		(layer "F.Cu")
		(net "SW_PWR_R_HDD13")
	)
	(segment
		(start 40.995346 -108.4707)
		(end 40.766746 -108.4707)
		(width 0.111252)
		(layer "F.Cu")
		(net "SW_PWR_R_HDD13")
	)
	(segment
		(start 40.766746 -108.4707)
		(end 39.62781 -109.609636)
		(width 0.111252)
		(layer "F.Cu")
		(net "SW_PWR_R_HDD13")
	)
	(segment
		(start 40.207946 -110.645702)
		(end 39.823898 -110.645702)
		(width 0.111252)
		(layer "F.Cu")
		(net "SW_PWR_R_HDD13")
	)
	(via
		(at 41.147746 -108.3183)
		(size 0.7112)
		(drill 0.3556)
		(layers "F.Cu" "B.Cu")
		(net "SW_PWR_R_HDD13")
	)
	(segment
		(start 200.724262 -391.745216)
		(end 200.724262 -390.049512)
		(width 0.111252)
		(layer "F.Cu")
		(net "SAS2X28_A_HDD1_FLT")
	)
	(segment
		(start 7.682484 -390.500362)
		(end 3.19405 -390.500362)
		(width 0.111252)
		(layer "F.Cu")
		(net "SAS2X28_A_HDD1_FLT")
	)
	(segment
		(start 8.153146 -390.0297)
		(end 7.682484 -390.500362)
		(width 0.111252)
		(layer "F.Cu")
		(net "SAS2X28_A_HDD1_FLT")
	)
	(segment
		(start 201.040746 -392.0617)
		(end 200.724262 -391.745216)
		(width 0.111252)
		(layer "F.Cu")
		(net "SAS2X28_A_HDD1_FLT")
	)
	(segment
		(start 3.19405 -390.500362)
		(end 3.192526 -390.498838)
		(width 0.111252)
		(layer "F.Cu")
		(net "SAS2X28_A_HDD1_FLT")
	)
	(segment
		(start 202.634596 -392.0617)
		(end 201.040746 -392.0617)
		(width 0.111252)
		(layer "F.Cu")
		(net "SAS2X28_A_HDD1_FLT")
	)
	(segment
		(start 202.801474 -391.894822)
		(end 202.634596 -392.0617)
		(width 0.111252)
		(layer "F.Cu")
		(net "SAS2X28_A_HDD1_FLT")
	)
	(via
		(at 201.040746 -392.0617)
		(size 0.5588)
		(drill 0.3048)
		(layers "F.Cu" "B.Cu")
		(net "SAS2X28_A_HDD1_FLT")
	)
	(via
		(at 8.153146 -390.0297)
		(size 0.5588)
		(drill 0.3048)
		(layers "F.Cu" "B.Cu")
		(net "SAS2X28_A_HDD1_FLT")
	)
	(via
		(at 200.100946 -392.0617)
		(size 0.7112)
		(drill 0.3556)
		(layers "F.Cu" "B.Cu")
		(net "SAS2X28_A_HDD1_FLT")
	)
	(segment
		(start 201.040746 -392.0617)
		(end 200.100946 -392.0617)
		(width 0.111252)
		(layer "B.Cu")
		(net "SAS2X28_A_HDD1_FLT")
	)
	(segment
		(start 8.286496 -390.252966)
		(end 9.473946 -391.440416)
		(width 0.14605)
		(layer "In5.Cu")
		(net "SAS2X28_A_HDD1_FLT")
	)
	(segment
		(start 10.350246 -446.929764)
		(end 11.83513 -446.929764)
		(width 0.14605)
		(layer "In5.Cu")
		(net "SAS2X28_A_HDD1_FLT")
	)
	(segment
		(start 14.941296 -449.629276)
		(end 14.941296 -460.530448)
		(width 0.14605)
		(layer "In5.Cu")
		(net "SAS2X28_A_HDD1_FLT")
	)
	(segment
		(start 8.286496 -390.16305)
		(end 8.286496 -390.252966)
		(width 0.14605)
		(layer "In5.Cu")
		(net "SAS2X28_A_HDD1_FLT")
	)
	(segment
		(start 11.162284 -395.554962)
		(end 13.090652 -397.48333)
		(width 0.14605)
		(layer "In5.Cu")
		(net "SAS2X28_A_HDD1_FLT")
	)
	(segment
		(start 12.248388 -446.913762)
		(end 12.529312 -447.194686)
		(width 0.14605)
		(layer "In5.Cu")
		(net "SAS2X28_A_HDD1_FLT")
	)
	(segment
		(start 12.529312 -447.217292)
		(end 14.941296 -449.629276)
		(width 0.14605)
		(layer "In5.Cu")
		(net "SAS2X28_A_HDD1_FLT")
	)
	(segment
		(start 14.941296 -460.530448)
		(end 17.395444 -462.984596)
		(width 0.14605)
		(layer "In5.Cu")
		(net "SAS2X28_A_HDD1_FLT")
	)
	(segment
		(start 9.473946 -394.277088)
		(end 10.75182 -395.554962)
		(width 0.14605)
		(layer "In5.Cu")
		(net "SAS2X28_A_HDD1_FLT")
	)
	(segment
		(start 10.75182 -395.554962)
		(end 11.162284 -395.554962)
		(width 0.14605)
		(layer "In5.Cu")
		(net "SAS2X28_A_HDD1_FLT")
	)
	(segment
		(start 12.529312 -447.194686)
		(end 12.529312 -447.217292)
		(width 0.14605)
		(layer "In5.Cu")
		(net "SAS2X28_A_HDD1_FLT")
	)
	(segment
		(start 11.83513 -446.929764)
		(end 11.851132 -446.913762)
		(width 0.14605)
		(layer "In5.Cu")
		(net "SAS2X28_A_HDD1_FLT")
	)
	(segment
		(start 17.395444 -462.984596)
		(end 130.11785 -462.984596)
		(width 0.14605)
		(layer "In5.Cu")
		(net "SAS2X28_A_HDD1_FLT")
	)
	(segment
		(start 10.273284 -446.852802)
		(end 10.350246 -446.929764)
		(width 0.14605)
		(layer "In5.Cu")
		(net "SAS2X28_A_HDD1_FLT")
	)
	(segment
		(start 10.250678 -446.852802)
		(end 10.273284 -446.852802)
		(width 0.14605)
		(layer "In5.Cu")
		(net "SAS2X28_A_HDD1_FLT")
	)
	(segment
		(start 9.473946 -391.440416)
		(end 9.473946 -394.277088)
		(width 0.14605)
		(layer "In5.Cu")
		(net "SAS2X28_A_HDD1_FLT")
	)
	(segment
		(start 130.11785 -462.984596)
		(end 201.040746 -392.0617)
		(width 0.14605)
		(layer "In5.Cu")
		(net "SAS2X28_A_HDD1_FLT")
	)
	(segment
		(start 8.153146 -390.0297)
		(end 8.286496 -390.16305)
		(width 0.14605)
		(layer "In5.Cu")
		(net "SAS2X28_A_HDD1_FLT")
	)
	(segment
		(start 13.090652 -397.48333)
		(end 13.090652 -400.989292)
		(width 0.14605)
		(layer "In5.Cu")
		(net "SAS2X28_A_HDD1_FLT")
	)
	(segment
		(start 11.851132 -446.913762)
		(end 12.248388 -446.913762)
		(width 0.14605)
		(layer "In5.Cu")
		(net "SAS2X28_A_HDD1_FLT")
	)
	(segment
		(start 12.83589 -401.244054)
		(end 12.83589 -430.74336)
		(width 0.14605)
		(layer "In5.Cu")
		(net "SAS2X28_A_HDD1_FLT")
	)
	(segment
		(start 8.331454 -444.933578)
		(end 10.250678 -446.852802)
		(width 0.14605)
		(layer "In5.Cu")
		(net "SAS2X28_A_HDD1_FLT")
	)
	(segment
		(start 8.331454 -442.802518)
		(end 8.331454 -444.933578)
		(width 0.14605)
		(layer "In5.Cu")
		(net "SAS2X28_A_HDD1_FLT")
	)
	(segment
		(start 7.483348 -436.095902)
		(end 7.483348 -441.954412)
		(width 0.14605)
		(layer "In5.Cu")
		(net "SAS2X28_A_HDD1_FLT")
	)
	(segment
		(start 13.090652 -400.989292)
		(end 12.83589 -401.244054)
		(width 0.14605)
		(layer "In5.Cu")
		(net "SAS2X28_A_HDD1_FLT")
	)
	(segment
		(start 7.483348 -441.954412)
		(end 8.331454 -442.802518)
		(width 0.14605)
		(layer "In5.Cu")
		(net "SAS2X28_A_HDD1_FLT")
	)
	(segment
		(start 12.83589 -430.74336)
		(end 7.483348 -436.095902)
		(width 0.14605)
		(layer "In5.Cu")
		(net "SAS2X28_A_HDD1_FLT")
	)
	(segment
		(start 44.830746 -210.7057)
		(end 45.719746 -209.8167)
		(width 0.111252)
		(layer "F.Cu")
		(net "SW_PWR_R_HDD12")
	)
	(segment
		(start 44.830746 -211.674202)
		(end 44.830746 -210.7057)
		(width 0.111252)
		(layer "F.Cu")
		(net "SW_PWR_R_HDD12")
	)
	(segment
		(start 45.338746 -211.674202)
		(end 44.830746 -211.674202)
		(width 0.111252)
		(layer "F.Cu")
		(net "SW_PWR_R_HDD12")
	)
	(segment
		(start 46.176946 -211.864702)
		(end 45.529246 -211.864702)
		(width 0.111252)
		(layer "F.Cu")
		(net "SW_PWR_R_HDD12")
	)
	(segment
		(start 45.529246 -211.864702)
		(end 45.338746 -211.674202)
		(width 0.111252)
		(layer "F.Cu")
		(net "SW_PWR_R_HDD12")
	)
	(via
		(at 45.719746 -209.8167)
		(size 0.7112)
		(drill 0.3556)
		(layers "F.Cu" "B.Cu")
		(net "SW_PWR_R_HDD12")
	)
	(segment
		(start 27.622246 -32.9057)
		(end 27.939746 -32.9057)
		(width 0.09525)
		(layer "F.Cu")
		(net "SAS2X28_B_HDD14_RX_-")
	)
	(segment
		(start 28.4353 -32.6263)
		(end 29.209746 -32.6263)
		(width 0.09525)
		(layer "F.Cu")
		(net "SAS2X28_B_HDD14_RX_-")
	)
	(segment
		(start 29.432504 -32.849058)
		(end 29.432504 -33.0327)
		(width 0.09525)
		(layer "F.Cu")
		(net "SAS2X28_B_HDD14_RX_-")
	)
	(segment
		(start 28.192476 -32.801052)
		(end 28.29179 -32.701738)
		(width 0.09525)
		(layer "F.Cu")
		(net "SAS2X28_B_HDD14_RX_-")
	)
	(via
		(at 29.432504 -33.0327)
		(size 0.5588)
		(drill 0.3048)
		(layers "F.Cu" "B.Cu")
		(net "SAS2X28_B_HDD14_RX_-")
	)
	(arc
		(start 28.29179 -32.701738)
		(mid 28.311156 -32.684336)
		(end 28.332176 -32.668972)
		(width 0.09525)
		(layer "F.Cu")
		(net "SAS2X28_B_HDD14_RX_-")
	)
	(arc
		(start 28.332176 -32.668972)
		(mid 28.37949 -32.637358)
		(end 28.4353 -32.6263)
		(width 0.09525)
		(layer "F.Cu")
		(net "SAS2X28_B_HDD14_RX_-")
	)
	(arc
		(start 29.209746 -32.6263)
		(mid 29.36726 -32.691544)
		(end 29.432504 -32.849058)
		(width 0.09525)
		(layer "F.Cu")
		(net "SAS2X28_B_HDD14_RX_-")
	)
	(arc
		(start 27.939746 -32.9057)
		(mid 28.076509 -32.878496)
		(end 28.192476 -32.801052)
		(width 0.09525)
		(layer "F.Cu")
		(net "SAS2X28_B_HDD14_RX_-")
	)
	(segment
		(start 25.873456 -32.23641)
		(end 25.001728 -31.364936)
		(width 0.09525)
		(layer "B.Cu")
		(net "SAS2X28_B_HDD14_RX_-")
	)
	(segment
		(start 4.864354 -96.49841)
		(end 2.811526 -96.49841)
		(width 0.09525)
		(layer "B.Cu")
		(net "SAS2X28_B_HDD14_RX_-")
	)
	(segment
		(start 15.98295 -36.480242)
		(end 15.747492 -36.7157)
		(width 0.09525)
		(layer "B.Cu")
		(net "SAS2X28_B_HDD14_RX_-")
	)
	(segment
		(start 15.569946 -37.144452)
		(end 15.569946 -87.948262)
		(width 0.09525)
		(layer "B.Cu")
		(net "SAS2X28_B_HDD14_RX_-")
	)
	(segment
		(start 7.238746 -96.160336)
		(end 5.68579 -96.160336)
		(width 0.09525)
		(layer "B.Cu")
		(net "SAS2X28_B_HDD14_RX_-")
	)
	(segment
		(start 24.12238 -31.0007)
		(end 22.014688 -31.0007)
		(width 0.09525)
		(layer "B.Cu")
		(net "SAS2X28_B_HDD14_RX_-")
	)
	(segment
		(start 15.265146 -88.6841)
		(end 8.184388 -95.764858)
		(width 0.09525)
		(layer "B.Cu")
		(net "SAS2X28_B_HDD14_RX_-")
	)
	(segment
		(start 29.048964 -32.6517)
		(end 26.876756 -32.6517)
		(width 0.09525)
		(layer "B.Cu")
		(net "SAS2X28_B_HDD14_RX_-")
	)
	(segment
		(start 4.865878 -96.499934)
		(end 4.864354 -96.49841)
		(width 0.09525)
		(layer "B.Cu")
		(net "SAS2X28_B_HDD14_RX_-")
	)
	(segment
		(start 29.356304 -32.849312)
		(end 29.261816 -32.754824)
		(width 0.09525)
		(layer "B.Cu")
		(net "SAS2X28_B_HDD14_RX_-")
	)
	(segment
		(start 8.184388 -95.764858)
		(end 8.177784 -95.771208)
		(width 0.09525)
		(layer "B.Cu")
		(net "SAS2X28_B_HDD14_RX_-")
	)
	(segment
		(start 29.147516 -32.678624)
		(end 29.113988 -32.664654)
		(width 0.09525)
		(layer "B.Cu")
		(net "SAS2X28_B_HDD14_RX_-")
	)
	(segment
		(start 16.065246 -36.3982)
		(end 15.98295 -36.480242)
		(width 0.09525)
		(layer "B.Cu")
		(net "SAS2X28_B_HDD14_RX_-")
	)
	(segment
		(start 21.070824 -31.392622)
		(end 16.065246 -36.3982)
		(width 0.09525)
		(layer "B.Cu")
		(net "SAS2X28_B_HDD14_RX_-")
	)
	(arc
		(start 8.177784 -95.771208)
		(mid 7.746965 -96.059165)
		(end 7.238746 -96.160336)
		(width 0.09525)
		(layer "B.Cu")
		(net "SAS2X28_B_HDD14_RX_-")
	)
	(arc
		(start 5.68579 -96.160336)
		(mid 5.549081 -96.178451)
		(end 5.421884 -96.23171)
		(width 0.09525)
		(layer "B.Cu")
		(net "SAS2X28_B_HDD14_RX_-")
	)
	(arc
		(start 26.876756 -32.6517)
		(mid 26.333868 -32.543708)
		(end 25.873456 -32.23641)
		(width 0.09525)
		(layer "B.Cu")
		(net "SAS2X28_B_HDD14_RX_-")
	)
	(arc
		(start 29.432504 -33.0327)
		(mid 29.412646 -32.933428)
		(end 29.356304 -32.849312)
		(width 0.09525)
		(layer "B.Cu")
		(net "SAS2X28_B_HDD14_RX_-")
	)
	(arc
		(start 15.747492 -36.7157)
		(mid 15.616053 -36.912413)
		(end 15.569946 -37.144452)
		(width 0.09525)
		(layer "B.Cu")
		(net "SAS2X28_B_HDD14_RX_-")
	)
	(arc
		(start 25.001728 -31.364936)
		(mid 24.59828 -31.09536)
		(end 24.12238 -31.0007)
		(width 0.09525)
		(layer "B.Cu")
		(net "SAS2X28_B_HDD14_RX_-")
	)
	(arc
		(start 5.315966 -96.313498)
		(mid 5.109464 -96.451478)
		(end 4.865878 -96.499934)
		(width 0.09525)
		(layer "B.Cu")
		(net "SAS2X28_B_HDD14_RX_-")
	)
	(arc
		(start 22.014688 -31.0007)
		(mid 21.536427 -31.089568)
		(end 21.121878 -31.344108)
		(width 0.09525)
		(layer "B.Cu")
		(net "SAS2X28_B_HDD14_RX_-")
	)
	(arc
		(start 21.121878 -31.344108)
		(mid 21.096038 -31.368036)
		(end 21.070824 -31.392622)
		(width 0.09525)
		(layer "B.Cu")
		(net "SAS2X28_B_HDD14_RX_-")
	)
	(arc
		(start 29.113988 -32.664654)
		(mid 29.082115 -32.65497)
		(end 29.048964 -32.6517)
		(width 0.09525)
		(layer "B.Cu")
		(net "SAS2X28_B_HDD14_RX_-")
	)
	(arc
		(start 15.569946 -87.948262)
		(mid 15.490732 -88.346497)
		(end 15.265146 -88.6841)
		(width 0.09525)
		(layer "B.Cu")
		(net "SAS2X28_B_HDD14_RX_-")
	)
	(arc
		(start 29.261816 -32.754824)
		(mid 29.208407 -32.711116)
		(end 29.147516 -32.678624)
		(width 0.09525)
		(layer "B.Cu")
		(net "SAS2X28_B_HDD14_RX_-")
	)
	(arc
		(start 5.421884 -96.23171)
		(mid 5.366309 -96.269215)
		(end 5.315966 -96.313498)
		(width 0.09525)
		(layer "B.Cu")
		(net "SAS2X28_B_HDD14_RX_-")
	)
	(segment
		(start 220.408246 -346.1512)
		(end 220.598746 -346.3417)
		(width 0.111252)
		(layer "F.Cu")
		(net "DRIVE_ACT_1")
	)
	(segment
		(start 219.443046 -346.1512)
		(end 220.408246 -346.1512)
		(width 0.111252)
		(layer "F.Cu")
		(net "DRIVE_ACT_1")
	)
	(segment
		(start 220.916246 -345.3257)
		(end 220.916246 -343.969848)
		(width 0.111252)
		(layer "F.Cu")
		(net "DRIVE_ACT_1")
	)
	(segment
		(start 220.916246 -343.969848)
		(end 220.875098 -343.9287)
		(width 0.111252)
		(layer "F.Cu")
		(net "DRIVE_ACT_1")
	)
	(segment
		(start 220.598746 -346.3417)
		(end 220.916246 -346.3417)
		(width 0.111252)
		(layer "F.Cu")
		(net "DRIVE_ACT_1")
	)
	(segment
		(start 220.916246 -346.3417)
		(end 220.916246 -345.3257)
		(width 0.111252)
		(layer "F.Cu")
		(net "DRIVE_ACT_1")
	)
	(via
		(at 220.875098 -343.9287)
		(size 0.7112)
		(drill 0.3556)
		(layers "F.Cu" "B.Cu")
		(net "DRIVE_ACT_1")
	)
	(segment
		(start 31.317946 -308.892702)
		(end 30.368748 -308.892702)
		(width 0.111252)
		(layer "F.Cu")
		(net "SW_PWR_R_HDD11")
	)
	(segment
		(start 29.590746 -308.6227)
		(end 29.844746 -308.3687)
		(width 0.111252)
		(layer "F.Cu")
		(net "SW_PWR_R_HDD11")
	)
	(segment
		(start 29.590746 -310.861202)
		(end 29.590746 -308.6227)
		(width 0.111252)
		(layer "F.Cu")
		(net "SW_PWR_R_HDD11")
	)
	(segment
		(start 30.368748 -308.892702)
		(end 29.844746 -308.3687)
		(width 0.111252)
		(layer "F.Cu")
		(net "SW_PWR_R_HDD11")
	)
	(via
		(at 29.844746 -308.3687)
		(size 0.7112)
		(drill 0.3556)
		(layers "F.Cu" "B.Cu")
		(net "SW_PWR_R_HDD11")
	)
	(segment
		(start 28.447746 -32.2961)
		(end 29.082746 -32.2961)
		(width 0.09525)
		(layer "F.Cu")
		(net "SAS2X28_B_HDD14_RX_+")
	)
	(segment
		(start 27.622246 -32.0167)
		(end 27.939746 -32.0167)
		(width 0.09525)
		(layer "F.Cu")
		(net "SAS2X28_B_HDD14_RX_+")
	)
	(segment
		(start 28.192476 -32.121348)
		(end 28.310332 -32.239204)
		(width 0.09525)
		(layer "F.Cu")
		(net "SAS2X28_B_HDD14_RX_+")
	)
	(via
		(at 29.432504 -31.997142)
		(size 0.5588)
		(drill 0.3048)
		(layers "F.Cu" "B.Cu")
		(net "SAS2X28_B_HDD14_RX_+")
	)
	(arc
		(start 28.310332 -32.239204)
		(mid 28.373378 -32.28133)
		(end 28.447746 -32.2961)
		(width 0.09525)
		(layer "F.Cu")
		(net "SAS2X28_B_HDD14_RX_+")
	)
	(arc
		(start 29.082746 -32.2961)
		(mid 29.312804 -32.211176)
		(end 29.432504 -31.997142)
		(width 0.09525)
		(layer "F.Cu")
		(net "SAS2X28_B_HDD14_RX_+")
	)
	(arc
		(start 27.939746 -32.0167)
		(mid 28.076509 -32.043904)
		(end 28.192476 -32.121348)
		(width 0.09525)
		(layer "F.Cu")
		(net "SAS2X28_B_HDD14_RX_+")
	)
	(segment
		(start 7.238492 -95.830136)
		(end 5.842 -95.830136)
		(width 0.09525)
		(layer "B.Cu")
		(net "SAS2X28_B_HDD14_RX_+")
	)
	(segment
		(start 7.948676 -95.532956)
		(end 7.944104 -95.537528)
		(width 0.09525)
		(layer "B.Cu")
		(net "SAS2X28_B_HDD14_RX_+")
	)
	(segment
		(start 15.749524 -36.246562)
		(end 15.513812 -36.48202)
		(width 0.09525)
		(layer "B.Cu")
		(net "SAS2X28_B_HDD14_RX_+")
	)
	(segment
		(start 15.031466 -88.45042)
		(end 9.713468 -93.768418)
		(width 0.09525)
		(layer "B.Cu")
		(net "SAS2X28_B_HDD14_RX_+")
	)
	(segment
		(start 9.220454 -93.932756)
		(end 9.018524 -94.134686)
		(width 0.09525)
		(layer "B.Cu")
		(net "SAS2X28_B_HDD14_RX_+")
	)
	(segment
		(start 15.239746 -37.144706)
		(end 15.239746 -87.948008)
		(width 0.09525)
		(layer "B.Cu")
		(net "SAS2X28_B_HDD14_RX_+")
	)
	(segment
		(start 29.015436 -32.3215)
		(end 26.87701 -32.3215)
		(width 0.09525)
		(layer "B.Cu")
		(net "SAS2X28_B_HDD14_RX_+")
	)
	(segment
		(start 24.122126 -30.6705)
		(end 22.014434 -30.6705)
		(width 0.09525)
		(layer "B.Cu")
		(net "SAS2X28_B_HDD14_RX_+")
	)
	(segment
		(start 8.854186 -94.6277)
		(end 7.951216 -95.53067)
		(width 0.09525)
		(layer "B.Cu")
		(net "SAS2X28_B_HDD14_RX_+")
	)
	(segment
		(start 7.951216 -95.53067)
		(end 7.948676 -95.532956)
		(width 0.09525)
		(layer "B.Cu")
		(net "SAS2X28_B_HDD14_RX_+")
	)
	(segment
		(start 20.837144 -31.158942)
		(end 15.926562 -36.069524)
		(width 0.09525)
		(layer "B.Cu")
		(net "SAS2X28_B_HDD14_RX_+")
	)
	(segment
		(start 15.83182 -36.16452)
		(end 15.749524 -36.246562)
		(width 0.09525)
		(layer "B.Cu")
		(net "SAS2X28_B_HDD14_RX_+")
	)
	(segment
		(start 26.106882 -32.00273)
		(end 25.235408 -31.131256)
		(width 0.09525)
		(layer "B.Cu")
		(net "SAS2X28_B_HDD14_RX_+")
	)
	(segment
		(start 15.926562 -36.069524)
		(end 15.83182 -36.16452)
		(width 0.09525)
		(layer "B.Cu")
		(net "SAS2X28_B_HDD14_RX_+")
	)
	(segment
		(start 4.996434 -95.503746)
		(end 2.811526 -95.498412)
		(width 0.09525)
		(layer "B.Cu")
		(net "SAS2X28_B_HDD14_RX_+")
	)
	(arc
		(start 9.018524 -94.134686)
		(mid 8.947427 -94.248005)
		(end 8.936228 -94.38132)
		(width 0.09525)
		(layer "B.Cu")
		(net "SAS2X28_B_HDD14_RX_+")
	)
	(arc
		(start 29.432504 -31.997142)
		(mid 29.279621 -32.230887)
		(end 29.015436 -32.3215)
		(width 0.09525)
		(layer "B.Cu")
		(net "SAS2X28_B_HDD14_RX_+")
	)
	(arc
		(start 22.014434 -30.6705)
		(mid 21.417674 -30.781247)
		(end 20.90039 -31.098744)
		(width 0.09525)
		(layer "B.Cu")
		(net "SAS2X28_B_HDD14_RX_+")
	)
	(arc
		(start 15.239746 -87.948008)
		(mid 15.218741 -88.119456)
		(end 15.156942 -88.280748)
		(width 0.09525)
		(layer "B.Cu")
		(net "SAS2X28_B_HDD14_RX_+")
	)
	(arc
		(start 15.513812 -36.48202)
		(mid 15.310906 -36.786108)
		(end 15.239746 -37.144706)
		(width 0.09525)
		(layer "B.Cu")
		(net "SAS2X28_B_HDD14_RX_+")
	)
	(arc
		(start 15.156942 -88.280748)
		(mid 15.100541 -88.37027)
		(end 15.031466 -88.45042)
		(width 0.09525)
		(layer "B.Cu")
		(net "SAS2X28_B_HDD14_RX_+")
	)
	(arc
		(start 9.713468 -93.768418)
		(mid 9.600243 -93.839377)
		(end 9.467088 -93.85046)
		(width 0.09525)
		(layer "B.Cu")
		(net "SAS2X28_B_HDD14_RX_+")
	)
	(arc
		(start 9.467088 -93.85046)
		(mid 9.333762 -93.861626)
		(end 9.220454 -93.932756)
		(width 0.09525)
		(layer "B.Cu")
		(net "SAS2X28_B_HDD14_RX_+")
	)
	(arc
		(start 8.936228 -94.38132)
		(mid 8.925119 -94.514475)
		(end 8.854186 -94.6277)
		(width 0.09525)
		(layer "B.Cu")
		(net "SAS2X28_B_HDD14_RX_+")
	)
	(arc
		(start 26.87701 -32.3215)
		(mid 26.689683 -32.305233)
		(end 26.507948 -32.256984)
		(width 0.09525)
		(layer "B.Cu")
		(net "SAS2X28_B_HDD14_RX_+")
	)
	(arc
		(start 26.507948 -32.256984)
		(mid 26.293383 -32.151986)
		(end 26.106882 -32.00273)
		(width 0.09525)
		(layer "B.Cu")
		(net "SAS2X28_B_HDD14_RX_+")
	)
	(arc
		(start 5.331714 -95.63354)
		(mid 5.1762 -95.53734)
		(end 4.996434 -95.503746)
		(width 0.09525)
		(layer "B.Cu")
		(net "SAS2X28_B_HDD14_RX_+")
	)
	(arc
		(start 5.842 -95.830136)
		(mid 5.56858 -95.779283)
		(end 5.331714 -95.63354)
		(width 0.09525)
		(layer "B.Cu")
		(net "SAS2X28_B_HDD14_RX_+")
	)
	(arc
		(start 20.90039 -31.098744)
		(mid 20.86838 -31.128437)
		(end 20.837144 -31.158942)
		(width 0.09525)
		(layer "B.Cu")
		(net "SAS2X28_B_HDD14_RX_+")
	)
	(arc
		(start 7.944104 -95.537528)
		(mid 7.62041 -95.754033)
		(end 7.238492 -95.830136)
		(width 0.09525)
		(layer "B.Cu")
		(net "SAS2X28_B_HDD14_RX_+")
	)
	(arc
		(start 25.235408 -31.131256)
		(mid 24.7246 -30.790131)
		(end 24.122126 -30.6705)
		(width 0.09525)
		(layer "B.Cu")
		(net "SAS2X28_B_HDD14_RX_+")
	)
	(segment
		(start 231.996742 -41.763696)
		(end 230.983282 -40.750236)
		(width 0.111252)
		(layer "F.Cu")
		(net "FLT_NET_HDD4")
	)
	(segment
		(start 230.983282 -40.750236)
		(end 230.504746 -40.750236)
		(width 0.111252)
		(layer "F.Cu")
		(net "FLT_NET_HDD4")
	)
	(segment
		(start 234.309412 -41.763696)
		(end 231.996742 -41.763696)
		(width 0.111252)
		(layer "F.Cu")
		(net "FLT_NET_HDD4")
	)
	(segment
		(start 228.230176 -40.753538)
		(end 228.233478 -40.750236)
		(width 0.111252)
		(layer "F.Cu")
		(net "FLT_NET_HDD4")
	)
	(segment
		(start 228.233478 -40.750236)
		(end 230.504746 -40.750236)
		(width 0.111252)
		(layer "F.Cu")
		(net "FLT_NET_HDD4")
	)
	(via
		(at 230.504746 -40.750236)
		(size 0.7112)
		(drill 0.3556)
		(layers "F.Cu" "B.Cu")
		(net "FLT_NET_HDD4")
	)
	(segment
		(start 43.290744 -419.001702)
		(end 42.925746 -419.3667)
		(width 0.111252)
		(layer "F.Cu")
		(net "SW_PWR_R_HDD10")
	)
	(segment
		(start 45.719746 -419.208458)
		(end 45.51299 -419.001702)
		(width 0.111252)
		(layer "F.Cu")
		(net "SW_PWR_R_HDD10")
	)
	(segment
		(start 44.322746 -419.001702)
		(end 43.290744 -419.001702)
		(width 0.111252)
		(layer "F.Cu")
		(net "SW_PWR_R_HDD10")
	)
	(segment
		(start 45.51299 -419.001702)
		(end 44.322746 -419.001702)
		(width 0.111252)
		(layer "F.Cu")
		(net "SW_PWR_R_HDD10")
	)
	(via
		(at 42.925746 -419.3667)
		(size 0.7112)
		(drill 0.3556)
		(layers "F.Cu" "B.Cu")
		(net "SW_PWR_R_HDD10")
	)
	(segment
		(start 32.072834 -190.975234)
		(end 26.753566 -185.655966)
		(width 0.09525)
		(layer "F.Cu")
		(net "SAS2X28_A_HDD14_RX_+")
	)
	(segment
		(start 26.0096 -183.859932)
		(end 26.0096 -160.447228)
		(width 0.09525)
		(layer "F.Cu")
		(net "SAS2X28_A_HDD14_RX_+")
	)
	(segment
		(start 8.254746 -363.38383)
		(end 8.254746 -362.471716)
		(width 0.09525)
		(layer "F.Cu")
		(net "SAS2X28_A_HDD14_RX_+")
	)
	(segment
		(start 14.324076 -272.579338)
		(end 14.324076 -272.579084)
		(width 0.09525)
		(layer "F.Cu")
		(net "SAS2X28_A_HDD14_RX_+")
	)
	(segment
		(start 32.8168 -252.897132)
		(end 32.8168 -192.771268)
		(width 0.09525)
		(layer "F.Cu")
		(net "SAS2X28_A_HDD14_RX_+")
	)
	(segment
		(start 10.588498 -357.488744)
		(end 10.588752 -357.488998)
		(width 0.09525)
		(layer "F.Cu")
		(net "SAS2X28_A_HDD14_RX_+")
	)
	(segment
		(start 13.164312 -273.739102)
		(end 14.324076 -272.579338)
		(width 0.09525)
		(layer "F.Cu")
		(net "SAS2X28_A_HDD14_RX_+")
	)
	(segment
		(start 10.0203 -360.337608)
		(end 10.020046 -360.337354)
		(width 0.09525)
		(layer "F.Cu")
		(net "SAS2X28_A_HDD14_RX_+")
	)
	(segment
		(start 30.299914 -125.971554)
		(end 28.663646 -124.335286)
		(width 0.09525)
		(layer "F.Cu")
		(net "SAS2X28_A_HDD14_RX_+")
	)
	(segment
		(start 27.33294 -36.2331)
		(end 27.15387 -36.2331)
		(width 0.09525)
		(layer "F.Cu")
		(net "SAS2X28_A_HDD14_RX_+")
	)
	(segment
		(start 8.51535 -361.842558)
		(end 10.0203 -360.337608)
		(width 0.09525)
		(layer "F.Cu")
		(net "SAS2X28_A_HDD14_RX_+")
	)
	(segment
		(start 10.588752 -357.488998)
		(end 10.822178 -357.255318)
		(width 0.09525)
		(layer "F.Cu")
		(net "SAS2X28_A_HDD14_RX_+")
	)
	(segment
		(start 10.316464 -359.621582)
		(end 10.316464 -358.145588)
		(width 0.09525)
		(layer "F.Cu")
		(net "SAS2X28_A_HDD14_RX_+")
	)
	(segment
		(start 23.150322 -263.752838)
		(end 31.976314 -254.926846)
		(width 0.09525)
		(layer "F.Cu")
		(net "SAS2X28_A_HDD14_RX_+")
	)
	(segment
		(start 28.0162 -122.772932)
		(end 28.0162 -36.91636)
		(width 0.09525)
		(layer "F.Cu")
		(net "SAS2X28_A_HDD14_RX_+")
	)
	(segment
		(start 10.822178 -357.255318)
		(end 10.821924 -357.255064)
		(width 0.09525)
		(layer "F.Cu")
		(net "SAS2X28_A_HDD14_RX_+")
	)
	(segment
		(start 14.324584 -272.57883)
		(end 23.150322 -263.752838)
		(width 0.09525)
		(layer "F.Cu")
		(net "SAS2X28_A_HDD14_RX_+")
	)
	(segment
		(start 31.1404 -153.075132)
		(end 31.1404 -128.001268)
		(width 0.09525)
		(layer "F.Cu")
		(net "SAS2X28_A_HDD14_RX_+")
	)
	(segment
		(start 12.254738 -355.241098)
		(end 12.254738 -275.935186)
		(width 0.09525)
		(layer "F.Cu")
		(net "SAS2X28_A_HDD14_RX_+")
	)
	(segment
		(start 10.821924 -357.255064)
		(end 11.843512 -356.234238)
		(width 0.09525)
		(layer "F.Cu")
		(net "SAS2X28_A_HDD14_RX_+")
	)
	(segment
		(start 26.753566 -158.651194)
		(end 30.299914 -155.104846)
		(width 0.09525)
		(layer "F.Cu")
		(net "SAS2X28_A_HDD14_RX_+")
	)
	(via
		(at 8.434324 -363.817408)
		(size 0.5588)
		(drill 0.3048)
		(layers "F.Cu" "B.Cu")
		(net "SAS2X28_A_HDD14_RX_+")
	)
	(arc
		(start 27.15387 -36.2331)
		(mid 26.788781 -36.160479)
		(end 26.479246 -35.9537)
		(width 0.09525)
		(layer "F.Cu")
		(net "SAS2X28_A_HDD14_RX_+")
	)
	(arc
		(start 14.324076 -272.579084)
		(mid 14.32433 -272.578956)
		(end 14.324584 -272.57883)
		(width 0.09525)
		(layer "F.Cu")
		(net "SAS2X28_A_HDD14_RX_+")
	)
	(arc
		(start 8.434324 -363.817408)
		(mid 8.301405 -363.618481)
		(end 8.254746 -363.38383)
		(width 0.09525)
		(layer "F.Cu")
		(net "SAS2X28_A_HDD14_RX_+")
	)
	(arc
		(start 26.753566 -185.655966)
		(mid 26.202968 -184.831939)
		(end 26.0096 -183.859932)
		(width 0.09525)
		(layer "F.Cu")
		(net "SAS2X28_A_HDD14_RX_+")
	)
	(arc
		(start 28.663646 -124.335286)
		(mid 28.184549 -123.618501)
		(end 28.0162 -122.772932)
		(width 0.09525)
		(layer "F.Cu")
		(net "SAS2X28_A_HDD14_RX_+")
	)
	(arc
		(start 26.0096 -160.447228)
		(mid 26.202946 -159.475212)
		(end 26.753566 -158.651194)
		(width 0.09525)
		(layer "F.Cu")
		(net "SAS2X28_A_HDD14_RX_+")
	)
	(arc
		(start 10.020046 -360.337354)
		(mid 10.239446 -360.008954)
		(end 10.316464 -359.621582)
		(width 0.09525)
		(layer "F.Cu")
		(net "SAS2X28_A_HDD14_RX_+")
	)
	(arc
		(start 28.0162 -36.91636)
		(mid 27.816078 -36.433222)
		(end 27.33294 -36.2331)
		(width 0.09525)
		(layer "F.Cu")
		(net "SAS2X28_A_HDD14_RX_+")
	)
	(arc
		(start 32.8168 -192.771268)
		(mid 32.623454 -191.799252)
		(end 32.072834 -190.975234)
		(width 0.09525)
		(layer "F.Cu")
		(net "SAS2X28_A_HDD14_RX_+")
	)
	(arc
		(start 10.316464 -358.145588)
		(mid 10.387171 -357.790122)
		(end 10.588498 -357.488744)
		(width 0.09525)
		(layer "F.Cu")
		(net "SAS2X28_A_HDD14_RX_+")
	)
	(arc
		(start 8.254746 -362.471716)
		(mid 8.322475 -362.131219)
		(end 8.51535 -361.842558)
		(width 0.09525)
		(layer "F.Cu")
		(net "SAS2X28_A_HDD14_RX_+")
	)
	(arc
		(start 12.254738 -275.935186)
		(mid 12.491127 -274.746688)
		(end 13.164312 -273.739102)
		(width 0.09525)
		(layer "F.Cu")
		(net "SAS2X28_A_HDD14_RX_+")
	)
	(arc
		(start 11.843512 -356.234238)
		(mid 12.147865 -355.778553)
		(end 12.254738 -355.241098)
		(width 0.09525)
		(layer "F.Cu")
		(net "SAS2X28_A_HDD14_RX_+")
	)
	(arc
		(start 31.976314 -254.926846)
		(mid 32.598466 -253.99559)
		(end 32.8168 -252.897132)
		(width 0.09525)
		(layer "F.Cu")
		(net "SAS2X28_A_HDD14_RX_+")
	)
	(arc
		(start 31.1404 -128.001268)
		(mid 30.922002 -126.902836)
		(end 30.299914 -125.971554)
		(width 0.09525)
		(layer "F.Cu")
		(net "SAS2X28_A_HDD14_RX_+")
	)
	(arc
		(start 30.299914 -155.104846)
		(mid 30.922066 -154.17359)
		(end 31.1404 -153.075132)
		(width 0.09525)
		(layer "F.Cu")
		(net "SAS2X28_A_HDD14_RX_+")
	)
	(segment
		(start 4.907788 -359.4989)
		(end 2.811526 -359.4989)
		(width 0.09525)
		(layer "B.Cu")
		(net "SAS2X28_A_HDD14_RX_+")
	)
	(segment
		(start 7.740142 -361.193842)
		(end 6.920992 -360.374946)
		(width 0.09525)
		(layer "B.Cu")
		(net "SAS2X28_A_HDD14_RX_+")
	)
	(segment
		(start 8.16356 -363.163612)
		(end 8.16356 -362.2167)
		(width 0.09525)
		(layer "B.Cu")
		(net "SAS2X28_A_HDD14_RX_+")
	)
	(segment
		(start 4.909312 -359.500424)
		(end 4.907788 -359.4989)
		(width 0.09525)
		(layer "B.Cu")
		(net "SAS2X28_A_HDD14_RX_+")
	)
	(segment
		(start 5.841746 -359.8545)
		(end 5.764022 -359.8545)
		(width 0.09525)
		(layer "B.Cu")
		(net "SAS2X28_A_HDD14_RX_+")
	)
	(segment
		(start 5.841746 -359.854754)
		(end 5.841746 -359.8545)
		(width 0.09525)
		(layer "B.Cu")
		(net "SAS2X28_A_HDD14_RX_+")
	)
	(segment
		(start 6.920992 -360.374946)
		(end 6.795262 -360.24947)
		(width 0.09525)
		(layer "B.Cu")
		(net "SAS2X28_A_HDD14_RX_+")
	)
	(arc
		(start 6.795262 -360.24947)
		(mid 6.357756 -359.957294)
		(end 5.841746 -359.854754)
		(width 0.09525)
		(layer "B.Cu")
		(net "SAS2X28_A_HDD14_RX_+")
	)
	(arc
		(start 8.16356 -362.2167)
		(mid 8.053552 -361.66318)
		(end 7.740142 -361.193842)
		(width 0.09525)
		(layer "B.Cu")
		(net "SAS2X28_A_HDD14_RX_+")
	)
	(arc
		(start 8.434324 -363.817408)
		(mid 8.233894 -363.517444)
		(end 8.16356 -363.163612)
		(width 0.09525)
		(layer "B.Cu")
		(net "SAS2X28_A_HDD14_RX_+")
	)
	(arc
		(start 5.764022 -359.8545)
		(mid 5.530738 -359.808097)
		(end 5.332984 -359.675938)
		(width 0.09525)
		(layer "B.Cu")
		(net "SAS2X28_A_HDD14_RX_+")
	)
	(arc
		(start 5.332984 -359.675938)
		(mid 5.138602 -359.546056)
		(end 4.909312 -359.500424)
		(width 0.09525)
		(layer "B.Cu")
		(net "SAS2X28_A_HDD14_RX_+")
	)
	(segment
		(start 79.756 -87.867744)
		(end 79.479648 -87.867744)
		(width 0.111252)
		(layer "F.Cu")
		(net "SW_PWR_R_HDD9")
	)
	(segment
		(start 79.772256 -87.884)
		(end 79.756 -87.867744)
		(width 0.111252)
		(layer "F.Cu")
		(net "SW_PWR_R_HDD9")
	)
	(segment
		(start 80.898746 -89.4969)
		(end 80.898746 -88.8111)
		(width 0.111252)
		(layer "F.Cu")
		(net "SW_PWR_R_HDD9")
	)
	(segment
		(start 79.971646 -87.884)
		(end 79.772256 -87.884)
		(width 0.111252)
		(layer "F.Cu")
		(net "SW_PWR_R_HDD9")
	)
	(segment
		(start 78.422246 -87.2617)
		(end 78.873604 -87.2617)
		(width 0.111252)
		(layer "F.Cu")
		(net "SW_PWR_R_HDD9")
	)
	(segment
		(start 80.898746 -88.8111)
		(end 79.971646 -87.884)
		(width 0.111252)
		(layer "F.Cu")
		(net "SW_PWR_R_HDD9")
	)
	(segment
		(start 78.873604 -87.2617)
		(end 79.479648 -87.867744)
		(width 0.111252)
		(layer "F.Cu")
		(net "SW_PWR_R_HDD9")
	)
	(via
		(at 79.479648 -87.867744)
		(size 0.7112)
		(drill 0.3556)
		(layers "F.Cu" "B.Cu")
		(net "SW_PWR_R_HDD9")
	)
	(segment
		(start 6.679946 -98.457766)
		(end 6.54939 -98.32721)
		(width 0.09525)
		(layer "F.Cu")
		(net "SAS2X28_B_HDD14_TX_-")
	)
	(segment
		(start 20.089876 -32.209994)
		(end 20.093178 -32.206692)
		(width 0.09525)
		(layer "F.Cu")
		(net "SAS2X28_B_HDD14_TX_-")
	)
	(segment
		(start 6.146546 -98.160332)
		(end 5.615686 -98.160332)
		(width 0.09525)
		(layer "F.Cu")
		(net "SAS2X28_B_HDD14_TX_-")
	)
	(segment
		(start 4.795774 -98.49993)
		(end 3.19405 -98.49993)
		(width 0.09525)
		(layer "F.Cu")
		(net "SAS2X28_B_HDD14_TX_-")
	)
	(segment
		(start 20.733766 -32.472122)
		(end 21.462746 -32.472122)
		(width 0.09525)
		(layer "F.Cu")
		(net "SAS2X28_B_HDD14_TX_-")
	)
	(segment
		(start 21.899372 -32.291274)
		(end 21.996146 -32.1945)
		(width 0.09525)
		(layer "F.Cu")
		(net "SAS2X28_B_HDD14_TX_-")
	)
	(segment
		(start 19.600164 -32.209994)
		(end 20.089876 -32.209994)
		(width 0.09525)
		(layer "F.Cu")
		(net "SAS2X28_B_HDD14_TX_-")
	)
	(segment
		(start 3.19405 -98.49993)
		(end 3.192526 -98.498406)
		(width 0.09525)
		(layer "F.Cu")
		(net "SAS2X28_B_HDD14_TX_-")
	)
	(via
		(at 21.996146 -32.1945)
		(size 0.5588)
		(drill 0.3048)
		(layers "F.Cu" "B.Cu")
		(net "SAS2X28_B_HDD14_TX_-")
	)
	(via
		(at 6.679946 -98.457766)
		(size 0.5588)
		(drill 0.3048)
		(layers "F.Cu" "B.Cu")
		(net "SAS2X28_B_HDD14_TX_-")
	)
	(arc
		(start 21.462746 -32.472122)
		(mid 21.699043 -32.42512)
		(end 21.899372 -32.291274)
		(width 0.09525)
		(layer "F.Cu")
		(net "SAS2X28_B_HDD14_TX_-")
	)
	(arc
		(start 20.093178 -32.206692)
		(mid 20.325781 -32.25296)
		(end 20.522946 -32.384746)
		(width 0.09525)
		(layer "F.Cu")
		(net "SAS2X28_B_HDD14_TX_-")
	)
	(arc
		(start 5.615686 -98.160332)
		(mid 5.442473 -98.194786)
		(end 5.295646 -98.29292)
		(width 0.09525)
		(layer "F.Cu")
		(net "SAS2X28_B_HDD14_TX_-")
	)
	(arc
		(start 6.54939 -98.32721)
		(mid 6.364564 -98.203713)
		(end 6.146546 -98.160332)
		(width 0.09525)
		(layer "F.Cu")
		(net "SAS2X28_B_HDD14_TX_-")
	)
	(arc
		(start 20.522946 -32.384746)
		(mid 20.619671 -32.449376)
		(end 20.733766 -32.472122)
		(width 0.09525)
		(layer "F.Cu")
		(net "SAS2X28_B_HDD14_TX_-")
	)
	(arc
		(start 5.295646 -98.29292)
		(mid 5.066303 -98.446162)
		(end 4.795774 -98.49993)
		(width 0.09525)
		(layer "F.Cu")
		(net "SAS2X28_B_HDD14_TX_-")
	)
	(segment
		(start 21.996146 -32.1945)
		(end 22.014434 -32.212788)
		(width 0.09525)
		(layer "B.Cu")
		(net "SAS2X28_B_HDD14_TX_-")
	)
	(segment
		(start 25.729946 -34.288984)
		(end 25.729946 -45.0215)
		(width 0.09525)
		(layer "B.Cu")
		(net "SAS2X28_B_HDD14_TX_-")
	)
	(segment
		(start 23.603458 -50.155348)
		(end 16.859504 -56.899302)
		(width 0.09525)
		(layer "B.Cu")
		(net "SAS2X28_B_HDD14_TX_-")
	)
	(segment
		(start 16.227044 -90.282776)
		(end 8.649208 -97.860612)
		(width 0.09525)
		(layer "B.Cu")
		(net "SAS2X28_B_HDD14_TX_-")
	)
	(segment
		(start 22.459442 -32.3977)
		(end 23.37181 -32.3977)
		(width 0.09525)
		(layer "B.Cu")
		(net "SAS2X28_B_HDD14_TX_-")
	)
	(segment
		(start 16.509746 -57.74309)
		(end 16.509746 -89.600278)
		(width 0.09525)
		(layer "B.Cu")
		(net "SAS2X28_B_HDD14_TX_-")
	)
	(segment
		(start 6.821678 -98.316034)
		(end 6.679946 -98.457766)
		(width 0.09525)
		(layer "B.Cu")
		(net "SAS2X28_B_HDD14_TX_-")
	)
	(segment
		(start 7.96671 -98.143314)
		(end 7.238746 -98.143314)
		(width 0.09525)
		(layer "B.Cu")
		(net "SAS2X28_B_HDD14_TX_-")
	)
	(arc
		(start 22.31009 -32.379412)
		(mid 22.349361 -32.38778)
		(end 22.389084 -32.393636)
		(width 0.09525)
		(layer "B.Cu")
		(net "SAS2X28_B_HDD14_TX_-")
	)
	(arc
		(start 22.389084 -32.393636)
		(mid 22.424206 -32.396658)
		(end 22.459442 -32.3977)
		(width 0.09525)
		(layer "B.Cu")
		(net "SAS2X28_B_HDD14_TX_-")
	)
	(arc
		(start 16.509746 -89.600278)
		(mid 16.436275 -89.969644)
		(end 16.227044 -90.282776)
		(width 0.09525)
		(layer "B.Cu")
		(net "SAS2X28_B_HDD14_TX_-")
	)
	(arc
		(start 25.272746 -33.1851)
		(mid 25.611156 -33.691566)
		(end 25.729946 -34.288984)
		(width 0.09525)
		(layer "B.Cu")
		(net "SAS2X28_B_HDD14_TX_-")
	)
	(arc
		(start 25.729946 -45.0215)
		(mid 25.177286 -47.79991)
		(end 23.603458 -50.155348)
		(width 0.09525)
		(layer "B.Cu")
		(net "SAS2X28_B_HDD14_TX_-")
	)
	(arc
		(start 23.37181 -32.3977)
		(mid 24.400592 -32.602337)
		(end 25.272746 -33.1851)
		(width 0.09525)
		(layer "B.Cu")
		(net "SAS2X28_B_HDD14_TX_-")
	)
	(arc
		(start 22.014434 -32.212788)
		(mid 22.150853 -32.316342)
		(end 22.31009 -32.379412)
		(width 0.09525)
		(layer "B.Cu")
		(net "SAS2X28_B_HDD14_TX_-")
	)
	(arc
		(start 16.859504 -56.899302)
		(mid 16.600747 -57.28642)
		(end 16.509746 -57.74309)
		(width 0.09525)
		(layer "B.Cu")
		(net "SAS2X28_B_HDD14_TX_-")
	)
	(arc
		(start 8.649208 -97.860612)
		(mid 8.336075 -98.069841)
		(end 7.96671 -98.143314)
		(width 0.09525)
		(layer "B.Cu")
		(net "SAS2X28_B_HDD14_TX_-")
	)
	(arc
		(start 7.238746 -98.143314)
		(mid 7.013044 -98.188209)
		(end 6.821678 -98.316034)
		(width 0.09525)
		(layer "B.Cu")
		(net "SAS2X28_B_HDD14_TX_-")
	)
	(segment
		(start 81.152746 -192.8749)
		(end 81.152746 -191.2747)
		(width 0.111252)
		(layer "F.Cu")
		(net "SW_PWR_R_HDD8")
	)
	(segment
		(start 80.390746 -190.5127)
		(end 80.898746 -191.0207)
		(width 0.111252)
		(layer "F.Cu")
		(net "SW_PWR_R_HDD8")
	)
	(segment
		(start 81.152746 -191.2747)
		(end 80.898746 -191.0207)
		(width 0.111252)
		(layer "F.Cu")
		(net "SW_PWR_R_HDD8")
	)
	(segment
		(start 78.803246 -190.5127)
		(end 80.390746 -190.5127)
		(width 0.111252)
		(layer "F.Cu")
		(net "SW_PWR_R_HDD8")
	)
	(via
		(at 80.898746 -191.0207)
		(size 0.7112)
		(drill 0.3556)
		(layers "F.Cu" "B.Cu")
		(net "SW_PWR_R_HDD8")
	)
	(segment
		(start 6.679946 -97.498916)
		(end 6.74116 -97.559876)
		(width 0.09525)
		(layer "F.Cu")
		(net "SAS2X28_B_HDD14_TX_+")
	)
	(segment
		(start 20.17903 -33.00984)
		(end 20.182332 -33.006538)
		(width 0.09525)
		(layer "F.Cu")
		(net "SAS2X28_B_HDD14_TX_+")
	)
	(segment
		(start 5.351272 -97.712784)
		(end 5.351018 -97.712784)
		(width 0.09525)
		(layer "F.Cu")
		(net "SAS2X28_B_HDD14_TX_+")
	)
	(segment
		(start 6.629146 -97.830132)
		(end 5.634228 -97.830132)
		(width 0.09525)
		(layer "F.Cu")
		(net "SAS2X28_B_HDD14_TX_+")
	)
	(segment
		(start 22.072346 -33.157922)
		(end 22.072346 -33.164018)
		(width 0.09525)
		(layer "F.Cu")
		(net "SAS2X28_B_HDD14_TX_+")
	)
	(segment
		(start 20.73021 -32.802322)
		(end 21.716746 -32.802322)
		(width 0.09525)
		(layer "F.Cu")
		(net "SAS2X28_B_HDD14_TX_+")
	)
	(segment
		(start 4.837176 -97.499932)
		(end 3.19405 -97.499932)
		(width 0.09525)
		(layer "F.Cu")
		(net "SAS2X28_B_HDD14_TX_+")
	)
	(segment
		(start 19.600164 -33.00984)
		(end 20.17903 -33.00984)
		(width 0.09525)
		(layer "F.Cu")
		(net "SAS2X28_B_HDD14_TX_+")
	)
	(segment
		(start 3.19405 -97.499932)
		(end 3.192526 -97.498408)
		(width 0.09525)
		(layer "F.Cu")
		(net "SAS2X28_B_HDD14_TX_+")
	)
	(via
		(at 6.679946 -97.498916)
		(size 0.5588)
		(drill 0.3048)
		(layers "F.Cu" "B.Cu")
		(net "SAS2X28_B_HDD14_TX_+")
	)
	(via
		(at 22.072346 -33.164018)
		(size 0.5588)
		(drill 0.3048)
		(layers "F.Cu" "B.Cu")
		(net "SAS2X28_B_HDD14_TX_+")
	)
	(arc
		(start 5.351018 -97.712784)
		(mid 5.115265 -97.555259)
		(end 4.837176 -97.499932)
		(width 0.09525)
		(layer "F.Cu")
		(net "SAS2X28_B_HDD14_TX_+")
	)
	(arc
		(start 5.634228 -97.830132)
		(mid 5.481067 -97.799631)
		(end 5.351272 -97.712784)
		(width 0.09525)
		(layer "F.Cu")
		(net "SAS2X28_B_HDD14_TX_+")
	)
	(arc
		(start 6.74116 -97.559876)
		(mid 6.775499 -97.732512)
		(end 6.629146 -97.830132)
		(width 0.09525)
		(layer "F.Cu")
		(net "SAS2X28_B_HDD14_TX_+")
	)
	(arc
		(start 20.630134 -32.843724)
		(mid 20.676049 -32.813044)
		(end 20.73021 -32.802322)
		(width 0.09525)
		(layer "F.Cu")
		(net "SAS2X28_B_HDD14_TX_+")
	)
	(arc
		(start 20.182332 -33.006538)
		(mid 20.420573 -32.964572)
		(end 20.630134 -32.843724)
		(width 0.09525)
		(layer "F.Cu")
		(net "SAS2X28_B_HDD14_TX_+")
	)
	(arc
		(start 21.716746 -32.802322)
		(mid 21.968193 -32.906475)
		(end 22.072346 -33.157922)
		(width 0.09525)
		(layer "F.Cu")
		(net "SAS2X28_B_HDD14_TX_+")
	)
	(segment
		(start 15.993618 -90.049096)
		(end 8.415528 -97.627186)
		(width 0.09525)
		(layer "B.Cu")
		(net "SAS2X28_B_HDD14_TX_+")
	)
	(segment
		(start 16.179546 -57.742836)
		(end 16.179546 -89.600024)
		(width 0.09525)
		(layer "B.Cu")
		(net "SAS2X28_B_HDD14_TX_+")
	)
	(segment
		(start 6.839204 -97.658174)
		(end 6.679946 -97.498916)
		(width 0.09525)
		(layer "B.Cu")
		(net "SAS2X28_B_HDD14_TX_+")
	)
	(segment
		(start 22.102064 -32.7279)
		(end 23.371556 -32.7279)
		(width 0.09525)
		(layer "B.Cu")
		(net "SAS2X28_B_HDD14_TX_+")
	)
	(segment
		(start 25.399492 -34.288984)
		(end 25.399746 -34.28873)
		(width 0.09525)
		(layer "B.Cu")
		(net "SAS2X28_B_HDD14_TX_+")
	)
	(segment
		(start 23.369778 -49.921668)
		(end 16.625824 -56.665622)
		(width 0.09525)
		(layer "B.Cu")
		(net "SAS2X28_B_HDD14_TX_+")
	)
	(segment
		(start 7.966456 -97.813114)
		(end 7.213346 -97.813114)
		(width 0.09525)
		(layer "B.Cu")
		(net "SAS2X28_B_HDD14_TX_+")
	)
	(segment
		(start 25.399746 -34.28873)
		(end 25.399746 -45.0215)
		(width 0.09525)
		(layer "B.Cu")
		(net "SAS2X28_B_HDD14_TX_+")
	)
	(arc
		(start 25.039066 -33.41878)
		(mid 25.305838 -33.818033)
		(end 25.399492 -34.288984)
		(width 0.09525)
		(layer "B.Cu")
		(net "SAS2X28_B_HDD14_TX_+")
	)
	(arc
		(start 16.625824 -56.665622)
		(mid 16.295561 -57.159851)
		(end 16.179546 -57.742836)
		(width 0.09525)
		(layer "B.Cu")
		(net "SAS2X28_B_HDD14_TX_+")
	)
	(arc
		(start 21.869146 -32.960818)
		(mid 21.937366 -32.79612)
		(end 22.102064 -32.7279)
		(width 0.09525)
		(layer "B.Cu")
		(net "SAS2X28_B_HDD14_TX_+")
	)
	(arc
		(start 16.179546 -89.600024)
		(mid 16.13121 -89.843028)
		(end 15.993618 -90.049096)
		(width 0.09525)
		(layer "B.Cu")
		(net "SAS2X28_B_HDD14_TX_+")
	)
	(arc
		(start 23.371556 -32.7279)
		(mid 24.274044 -32.907452)
		(end 25.039066 -33.41878)
		(width 0.09525)
		(layer "B.Cu")
		(net "SAS2X28_B_HDD14_TX_+")
	)
	(arc
		(start 7.213346 -97.813114)
		(mid 7.010875 -97.77284)
		(end 6.839204 -97.658174)
		(width 0.09525)
		(layer "B.Cu")
		(net "SAS2X28_B_HDD14_TX_+")
	)
	(arc
		(start 25.399746 -45.0215)
		(mid 24.872138 -47.673495)
		(end 23.369778 -49.921668)
		(width 0.09525)
		(layer "B.Cu")
		(net "SAS2X28_B_HDD14_TX_+")
	)
	(arc
		(start 8.415528 -97.627186)
		(mid 8.209492 -97.764855)
		(end 7.966456 -97.813114)
		(width 0.09525)
		(layer "B.Cu")
		(net "SAS2X28_B_HDD14_TX_+")
	)
	(arc
		(start 22.072346 -33.164018)
		(mid 21.928662 -33.104502)
		(end 21.869146 -32.960818)
		(width 0.09525)
		(layer "B.Cu")
		(net "SAS2X28_B_HDD14_TX_+")
	)
	(segment
		(start 30.352746 -281.8892)
		(end 31.229046 -281.8892)
		(width 0.111252)
		(layer "F.Cu")
		(net "SW_PWR_R_HDD7")
	)
	(segment
		(start 28.828746 -281.7368)
		(end 30.200346 -281.7368)
		(width 0.111252)
		(layer "F.Cu")
		(net "SW_PWR_R_HDD7")
	)
	(segment
		(start 30.200346 -281.7368)
		(end 30.352746 -281.8892)
		(width 0.111252)
		(layer "F.Cu")
		(net "SW_PWR_R_HDD7")
	)
	(segment
		(start 31.229046 -281.8892)
		(end 31.559246 -281.559)
		(width 0.111252)
		(layer "F.Cu")
		(net "SW_PWR_R_HDD7")
	)
	(via
		(at 31.559246 -281.559)
		(size 0.7112)
		(drill 0.3556)
		(layers "F.Cu" "B.Cu")
		(net "SW_PWR_R_HDD7")
	)
	(segment
		(start 87.375746 -16.3957)
		(end 88.328246 -16.3957)
		(width 0.111252)
		(layer "F.Cu")
		(net "SAS2X28_A_HDD14_FLT")
	)
	(segment
		(start 85.788246 -16.0147)
		(end 86.740746 -16.0147)
		(width 0.111252)
		(layer "F.Cu")
		(net "SAS2X28_A_HDD14_FLT")
	)
	(segment
		(start 86.740746 -16.0147)
		(end 86.994746 -16.0147)
		(width 0.111252)
		(layer "F.Cu")
		(net "SAS2X28_A_HDD14_FLT")
	)
	(segment
		(start 86.994746 -16.0147)
		(end 87.375746 -16.3957)
		(width 0.111252)
		(layer "F.Cu")
		(net "SAS2X28_A_HDD14_FLT")
	)
	(via
		(at 18.440146 -392.8491)
		(size 0.7112)
		(drill 0.3556)
		(layers "F.Cu" "B.Cu")
		(net "SAS2X28_A_HDD14_FLT")
	)
	(via
		(at 25.4 -392.8491)
		(size 0.5588)
		(drill 0.3048)
		(layers "F.Cu" "B.Cu")
		(net "SAS2X28_A_HDD14_FLT")
	)
	(via
		(at 101.853746 -400.1897)
		(size 0.5588)
		(drill 0.3048)
		(layers "F.Cu" "B.Cu")
		(net "SAS2X28_A_HDD14_FLT")
	)
	(via
		(at 86.740746 -16.0147)
		(size 0.5588)
		(drill 0.3048)
		(layers "F.Cu" "B.Cu")
		(net "SAS2X28_A_HDD14_FLT")
	)
	(segment
		(start 5.550408 -390.500362)
		(end 6.679946 -391.6299)
		(width 0.111252)
		(layer "B.Cu")
		(net "SAS2X28_A_HDD14_FLT")
	)
	(segment
		(start 25.4 -392.8491)
		(end 18.440146 -392.8491)
		(width 0.111252)
		(layer "B.Cu")
		(net "SAS2X28_A_HDD14_FLT")
	)
	(segment
		(start 8.364982 -391.6299)
		(end 8.628634 -391.893552)
		(width 0.111252)
		(layer "B.Cu")
		(net "SAS2X28_A_HDD14_FLT")
	)
	(segment
		(start 8.628634 -391.893552)
		(end 15.274798 -391.893552)
		(width 0.111252)
		(layer "B.Cu")
		(net "SAS2X28_A_HDD14_FLT")
	)
	(segment
		(start 2.811526 -390.498838)
		(end 2.81305 -390.500362)
		(width 0.111252)
		(layer "B.Cu")
		(net "SAS2X28_A_HDD14_FLT")
	)
	(segment
		(start 15.274798 -391.893552)
		(end 16.230346 -392.8491)
		(width 0.111252)
		(layer "B.Cu")
		(net "SAS2X28_A_HDD14_FLT")
	)
	(segment
		(start 6.679946 -391.6299)
		(end 8.364982 -391.6299)
		(width 0.111252)
		(layer "B.Cu")
		(net "SAS2X28_A_HDD14_FLT")
	)
	(segment
		(start 2.81305 -390.500362)
		(end 5.550408 -390.500362)
		(width 0.111252)
		(layer "B.Cu")
		(net "SAS2X28_A_HDD14_FLT")
	)
	(segment
		(start 16.230346 -392.8491)
		(end 18.440146 -392.8491)
		(width 0.111252)
		(layer "B.Cu")
		(net "SAS2X28_A_HDD14_FLT")
	)
	(segment
		(start 85.5726 -401.3454)
		(end 100.698046 -401.3454)
		(width 0.14605)
		(layer "In2.Cu")
		(net "SAS2X28_A_HDD14_FLT")
	)
	(segment
		(start 32.40913 -401.41525)
		(end 85.50275 -401.41525)
		(width 0.14605)
		(layer "In2.Cu")
		(net "SAS2X28_A_HDD14_FLT")
	)
	(segment
		(start 27.59075 -395.113256)
		(end 27.59075 -396.59687)
		(width 0.14605)
		(layer "In2.Cu")
		(net "SAS2X28_A_HDD14_FLT")
	)
	(segment
		(start 25.4 -392.922506)
		(end 27.59075 -395.113256)
		(width 0.14605)
		(layer "In2.Cu")
		(net "SAS2X28_A_HDD14_FLT")
	)
	(segment
		(start 85.50275 -401.41525)
		(end 85.5726 -401.3454)
		(width 0.14605)
		(layer "In2.Cu")
		(net "SAS2X28_A_HDD14_FLT")
	)
	(segment
		(start 100.698046 -401.3454)
		(end 101.853746 -400.1897)
		(width 0.14605)
		(layer "In2.Cu")
		(net "SAS2X28_A_HDD14_FLT")
	)
	(segment
		(start 25.4 -392.8491)
		(end 25.4 -392.922506)
		(width 0.14605)
		(layer "In2.Cu")
		(net "SAS2X28_A_HDD14_FLT")
	)
	(segment
		(start 27.59075 -396.59687)
		(end 32.40913 -401.41525)
		(width 0.14605)
		(layer "In2.Cu")
		(net "SAS2X28_A_HDD14_FLT")
	)
	(segment
		(start 87.115396 -16.38935)
		(end 87.115396 -16.74241)
		(width 0.14605)
		(layer "In5.Cu")
		(net "SAS2X28_A_HDD14_FLT")
	)
	(segment
		(start 101.923596 -49.609756)
		(end 101.923596 -49.654714)
		(width 0.14605)
		(layer "In5.Cu")
		(net "SAS2X28_A_HDD14_FLT")
	)
	(segment
		(start 87.220298 -16.847312)
		(end 87.220298 -17.244568)
		(width 0.14605)
		(layer "In5.Cu")
		(net "SAS2X28_A_HDD14_FLT")
	)
	(segment
		(start 86.740746 -16.0147)
		(end 87.115396 -16.38935)
		(width 0.14605)
		(layer "In5.Cu")
		(net "SAS2X28_A_HDD14_FLT")
	)
	(segment
		(start 101.755194 -400.028156)
		(end 101.853746 -400.126708)
		(width 0.14605)
		(layer "In5.Cu")
		(net "SAS2X28_A_HDD14_FLT")
	)
	(segment
		(start 102.234746 -371.5131)
		(end 101.755194 -371.992652)
		(width 0.14605)
		(layer "In5.Cu")
		(net "SAS2X28_A_HDD14_FLT")
	)
	(segment
		(start 87.115396 -34.801556)
		(end 101.923596 -49.609756)
		(width 0.14605)
		(layer "In5.Cu")
		(net "SAS2X28_A_HDD14_FLT")
	)
	(segment
		(start 87.115396 -17.34947)
		(end 87.115396 -34.801556)
		(width 0.14605)
		(layer "In5.Cu")
		(net "SAS2X28_A_HDD14_FLT")
	)
	(segment
		(start 101.755194 -371.992652)
		(end 101.755194 -400.028156)
		(width 0.14605)
		(layer "In5.Cu")
		(net "SAS2X28_A_HDD14_FLT")
	)
	(segment
		(start 102.234746 -50.02911)
		(end 102.234746 -371.5131)
		(width 0.14605)
		(layer "In5.Cu")
		(net "SAS2X28_A_HDD14_FLT")
	)
	(segment
		(start 101.853746 -400.126708)
		(end 101.853746 -400.1897)
		(width 0.14605)
		(layer "In5.Cu")
		(net "SAS2X28_A_HDD14_FLT")
	)
	(segment
		(start 101.923596 -49.654714)
		(end 102.190042 -49.92116)
		(width 0.14605)
		(layer "In5.Cu")
		(net "SAS2X28_A_HDD14_FLT")
	)
	(segment
		(start 87.115396 -16.74241)
		(end 87.220298 -16.847312)
		(width 0.14605)
		(layer "In5.Cu")
		(net "SAS2X28_A_HDD14_FLT")
	)
	(segment
		(start 87.220298 -17.244568)
		(end 87.115396 -17.34947)
		(width 0.14605)
		(layer "In5.Cu")
		(net "SAS2X28_A_HDD14_FLT")
	)
	(arc
		(start 102.190042 -49.92116)
		(mid 102.223135 -49.970688)
		(end 102.234746 -50.02911)
		(width 0.14605)
		(layer "In5.Cu")
		(net "SAS2X28_A_HDD14_FLT")
	)
	(segment
		(start 78.244446 -397.2179)
		(end 77.914246 -396.8877)
		(width 0.111252)
		(layer "F.Cu")
		(net "SW_PWR_R_HDD6")
	)
	(segment
		(start 81.2038 -397.7894)
		(end 80.898746 -398.094454)
		(width 0.111252)
		(layer "F.Cu")
		(net "SW_PWR_R_HDD6")
	)
	(segment
		(start 83.4644 -397.7894)
		(end 81.2038 -397.7894)
		(width 0.111252)
		(layer "F.Cu")
		(net "SW_PWR_R_HDD6")
	)
	(segment
		(start 80.898746 -398.7419)
		(end 80.898746 -398.094454)
		(width 0.111252)
		(layer "F.Cu")
		(net "SW_PWR_R_HDD6")
	)
	(segment
		(start 80.898746 -397.916146)
		(end 80.2005 -397.2179)
		(width 0.111252)
		(layer "F.Cu")
		(net "SW_PWR_R_HDD6")
	)
	(segment
		(start 80.898746 -398.094454)
		(end 80.898746 -397.916146)
		(width 0.111252)
		(layer "F.Cu")
		(net "SW_PWR_R_HDD6")
	)
	(segment
		(start 80.2005 -397.2179)
		(end 78.244446 -397.2179)
		(width 0.111252)
		(layer "F.Cu")
		(net "SW_PWR_R_HDD6")
	)
	(via
		(at 83.4644 -397.7894)
		(size 0.7112)
		(drill 0.3556)
		(layers "F.Cu" "B.Cu")
		(net "SW_PWR_R_HDD6")
	)
	(segment
		(start 79.656432 -496.145312)
		(end 80.855312 -496.145312)
		(width 0.111252)
		(layer "F.Cu")
		(net "SW_PWR_R_HDD5")
	)
	(segment
		(start 80.855312 -496.145312)
		(end 81.153 -496.443)
		(width 0.111252)
		(layer "F.Cu")
		(net "SW_PWR_R_HDD5")
	)
	(segment
		(start 81.69656 -496.98656)
		(end 81.153 -496.443)
		(width 0.111252)
		(layer "F.Cu")
		(net "SW_PWR_R_HDD5")
	)
	(segment
		(start 81.69656 -497.604288)
		(end 81.69656 -496.98656)
		(width 0.111252)
		(layer "F.Cu")
		(net "SW_PWR_R_HDD5")
	)
	(via
		(at 81.153 -496.443)
		(size 0.7112)
		(drill 0.3556)
		(layers "F.Cu" "B.Cu")
		(net "SW_PWR_R_HDD5")
	)
	(segment
		(start 191.256412 -87.256366)
		(end 191.261746 -87.2617)
		(width 0.111252)
		(layer "F.Cu")
		(net "SW_PWR_R_HDD4")
	)
	(segment
		(start 191.319912 -86.213696)
		(end 191.256412 -86.150196)
		(width 0.111252)
		(layer "F.Cu")
		(net "SW_PWR_R_HDD4")
	)
	(segment
		(start 192.729612 -86.213696)
		(end 191.319912 -86.213696)
		(width 0.111252)
		(layer "F.Cu")
		(net "SW_PWR_R_HDD4")
	)
	(segment
		(start 191.256412 -86.150196)
		(end 191.256412 -87.256366)
		(width 0.111252)
		(layer "F.Cu")
		(net "SW_PWR_R_HDD4")
	)
	(via
		(at 191.261746 -87.2617)
		(size 0.7112)
		(drill 0.3556)
		(layers "F.Cu" "B.Cu")
		(net "SW_PWR_R_HDD4")
	)
	(segment
		(start 190.118746 -188.7347)
		(end 189.737746 -188.3537)
		(width 0.111252)
		(layer "F.Cu")
		(net "SW_PWR_R_HDD3")
	)
	(segment
		(start 191.890396 -187.930028)
		(end 191.085724 -188.7347)
		(width 0.111252)
		(layer "F.Cu")
		(net "SW_PWR_R_HDD3")
	)
	(segment
		(start 192.276984 -187.930028)
		(end 191.890396 -187.930028)
		(width 0.111252)
		(layer "F.Cu")
		(net "SW_PWR_R_HDD3")
	)
	(segment
		(start 191.085724 -188.7347)
		(end 190.118746 -188.7347)
		(width 0.111252)
		(layer "F.Cu")
		(net "SW_PWR_R_HDD3")
	)
	(segment
		(start 190.803784 -187.612528)
		(end 190.351918 -187.612528)
		(width 0.111252)
		(layer "F.Cu")
		(net "SW_PWR_R_HDD3")
	)
	(segment
		(start 190.351918 -187.612528)
		(end 189.737746 -188.2267)
		(width 0.111252)
		(layer "F.Cu")
		(net "SW_PWR_R_HDD3")
	)
	(segment
		(start 189.737746 -188.3537)
		(end 189.737746 -188.2267)
		(width 0.111252)
		(layer "F.Cu")
		(net "SW_PWR_R_HDD3")
	)
	(via
		(at 189.737746 -188.2267)
		(size 0.7112)
		(drill 0.3556)
		(layers "F.Cu" "B.Cu")
		(net "SW_PWR_R_HDD3")
	)
	(segment
		(start 190.0555 -290.5252)
		(end 189.738 -290.2077)
		(width 0.111252)
		(layer "F.Cu")
		(net "SW_PWR_R_HDD2")
	)
	(segment
		(start 190.880746 -290.5252)
		(end 190.0555 -290.5252)
		(width 0.111252)
		(layer "F.Cu")
		(net "SW_PWR_R_HDD2")
	)
	(segment
		(start 192.226946 -290.5887)
		(end 190.944246 -290.5887)
		(width 0.111252)
		(layer "F.Cu")
		(net "SW_PWR_R_HDD2")
	)
	(segment
		(start 190.944246 -290.5887)
		(end 190.880746 -290.5252)
		(width 0.111252)
		(layer "F.Cu")
		(net "SW_PWR_R_HDD2")
	)
	(via
		(at 189.738 -290.2077)
		(size 0.7112)
		(drill 0.3556)
		(layers "F.Cu" "B.Cu")
		(net "SW_PWR_R_HDD2")
	)
	(segment
		(start 41.363646 -141.605)
		(end 41.275 -141.605)
		(width 0.111252)
		(layer "F.Cu")
		(net "I2C_B_TMP2_ALERT")
	)
	(segment
		(start 42.274744 -139.565126)
		(end 42.274744 -140.693902)
		(width 0.111252)
		(layer "F.Cu")
		(net "I2C_B_TMP2_ALERT")
	)
	(segment
		(start 42.274998 -139.564872)
		(end 42.274744 -139.565126)
		(width 0.111252)
		(layer "F.Cu")
		(net "I2C_B_TMP2_ALERT")
	)
	(segment
		(start 42.274744 -140.693902)
		(end 41.363646 -141.605)
		(width 0.111252)
		(layer "F.Cu")
		(net "I2C_B_TMP2_ALERT")
	)
	(segment
		(start 227.898706 -451.55866)
		(end 227.898706 -449.961)
		(width 0.111252)
		(layer "F.Cu")
		(net "FLT_NET_HDD0")
	)
	(segment
		(start 227.964746 -451.6247)
		(end 227.898706 -451.55866)
		(width 0.111252)
		(layer "F.Cu")
		(net "FLT_NET_HDD0")
	)
	(segment
		(start 228.098096 -451.758304)
		(end 227.964746 -451.6247)
		(width 0.111252)
		(layer "F.Cu")
		(net "FLT_NET_HDD0")
	)
	(segment
		(start 228.230176 -451.890384)
		(end 228.098096 -451.758304)
		(width 0.111252)
		(layer "F.Cu")
		(net "FLT_NET_HDD0")
	)
	(segment
		(start 228.058726 -449.80098)
		(end 227.898706 -449.961)
		(width 0.111252)
		(layer "F.Cu")
		(net "FLT_NET_HDD0")
	)
	(segment
		(start 229.822756 -450.30771)
		(end 229.316026 -449.80098)
		(width 0.111252)
		(layer "F.Cu")
		(net "FLT_NET_HDD0")
	)
	(segment
		(start 229.822756 -451.513702)
		(end 229.822756 -450.30771)
		(width 0.111252)
		(layer "F.Cu")
		(net "FLT_NET_HDD0")
	)
	(segment
		(start 228.230176 -452.753476)
		(end 228.230176 -451.890384)
		(width 0.111252)
		(layer "F.Cu")
		(net "FLT_NET_HDD0")
	)
	(segment
		(start 229.316026 -449.80098)
		(end 228.058726 -449.80098)
		(width 0.111252)
		(layer "F.Cu")
		(net "FLT_NET_HDD0")
	)
	(via
		(at 227.898706 -449.961)
		(size 0.7112)
		(drill 0.3556)
		(layers "F.Cu" "B.Cu")
		(net "FLT_NET_HDD0")
	)
	(segment
		(start 192.818258 -392.886184)
		(end 191.535558 -392.886184)
		(width 0.111252)
		(layer "F.Cu")
		(net "SW_PWR_R_HDD1")
	)
	(segment
		(start 191.535558 -392.886184)
		(end 191.472058 -392.949684)
		(width 0.111252)
		(layer "F.Cu")
		(net "SW_PWR_R_HDD1")
	)
	(segment
		(start 190.765684 -392.949684)
		(end 190.5 -392.684)
		(width 0.111252)
		(layer "F.Cu")
		(net "SW_PWR_R_HDD1")
	)
	(segment
		(start 191.472058 -392.949684)
		(end 190.765684 -392.949684)
		(width 0.111252)
		(layer "F.Cu")
		(net "SW_PWR_R_HDD1")
	)
	(via
		(at 190.5 -392.684)
		(size 0.7112)
		(drill 0.3556)
		(layers "F.Cu" "B.Cu")
		(net "SW_PWR_R_HDD1")
	)
	(segment
		(start 28.174696 -381.295148)
		(end 28.174696 -382.96215)
		(width 0.111252)
		(layer "F.Cu")
		(net "I2C_B_TMP1_ALERT")
	)
	(segment
		(start 28.17495 -381.294894)
		(end 28.174696 -381.295148)
		(width 0.111252)
		(layer "F.Cu")
		(net "I2C_B_TMP1_ALERT")
	)
	(segment
		(start 28.174696 -382.96215)
		(end 27.355546 -383.7813)
		(width 0.111252)
		(layer "F.Cu")
		(net "I2C_B_TMP1_ALERT")
	)
	(segment
		(start 217.122756 -479.3615)
		(end 217.122756 -478.4217)
		(width 0.111252)
		(layer "F.Cu")
		(net "HDD_PRSNT0")
	)
	(segment
		(start 217.122756 -480.596702)
		(end 217.122756 -479.3615)
		(width 0.111252)
		(layer "F.Cu")
		(net "HDD_PRSNT0")
	)
	(via
		(at 217.122756 -478.4217)
		(size 0.5588)
		(drill 0.3048)
		(layers "F.Cu" "B.Cu")
		(net "HDD_PRSNT0")
	)
	(via
		(at 217.122756 -479.3615)
		(size 0.7112)
		(drill 0.3556)
		(layers "F.Cu" "B.Cu")
		(net "HDD_PRSNT0")
	)
	(via
		(at 8.051546 -206.8449)
		(size 0.5588)
		(drill 0.3048)
		(layers "F.Cu" "B.Cu")
		(net "HDD_PRSNT0")
	)
	(via
		(at 10.235946 -464.5025)
		(size 0.7112)
		(drill 0.3556)
		(layers "F.Cu" "B.Cu")
		(net "HDD_PRSNT0")
	)
	(via
		(at 9.245346 -464.5025)
		(size 0.5588)
		(drill 0.3048)
		(layers "F.Cu" "B.Cu")
		(net "HDD_PRSNT0")
	)
	(via
		(at 6.629146 -463.5373)
		(size 0.5588)
		(drill 0.3048)
		(layers "F.Cu" "B.Cu")
		(net "HDD_PRSNT0")
	)
	(segment
		(start 10.235946 -464.5025)
		(end 9.245346 -464.5025)
		(width 0.111252)
		(layer "B.Cu")
		(net "HDD_PRSNT0")
	)
	(segment
		(start 6.920484 -206.501238)
		(end 2.812542 -206.501238)
		(width 0.111252)
		(layer "B.Cu")
		(net "HDD_PRSNT0")
	)
	(segment
		(start 7.264146 -206.8449)
		(end 6.920484 -206.501238)
		(width 0.111252)
		(layer "B.Cu")
		(net "HDD_PRSNT0")
	)
	(segment
		(start 6.593332 -463.501486)
		(end 2.812542 -463.501486)
		(width 0.111252)
		(layer "B.Cu")
		(net "HDD_PRSNT0")
	)
	(segment
		(start 8.280146 -463.5373)
		(end 6.629146 -463.5373)
		(width 0.111252)
		(layer "B.Cu")
		(net "HDD_PRSNT0")
	)
	(segment
		(start 2.812542 -206.501238)
		(end 2.80924 -206.50454)
		(width 0.111252)
		(layer "B.Cu")
		(net "HDD_PRSNT0")
	)
	(segment
		(start 9.245346 -464.5025)
		(end 8.280146 -463.5373)
		(width 0.111252)
		(layer "B.Cu")
		(net "HDD_PRSNT0")
	)
	(segment
		(start 8.051546 -206.8449)
		(end 7.264146 -206.8449)
		(width 0.111252)
		(layer "B.Cu")
		(net "HDD_PRSNT0")
	)
	(segment
		(start 2.812542 -463.501486)
		(end 2.80924 -463.504788)
		(width 0.111252)
		(layer "B.Cu")
		(net "HDD_PRSNT0")
	)
	(segment
		(start 6.629146 -463.5373)
		(end 6.593332 -463.501486)
		(width 0.111252)
		(layer "B.Cu")
		(net "HDD_PRSNT0")
	)
	(segment
		(start 7.727188 -461.370172)
		(end 7.73684 -461.321404)
		(width 0.14605)
		(layer "In2.Cu")
		(net "HDD_PRSNT0")
	)
	(segment
		(start 8.96874 -394.372084)
		(end 8.96874 -391.036302)
		(width 0.14605)
		(layer "In2.Cu")
		(net "HDD_PRSNT0")
	)
	(segment
		(start 9.822688 -219.35567)
		(end 8.273288 -217.80627)
		(width 0.14605)
		(layer "In2.Cu")
		(net "HDD_PRSNT0")
	)
	(segment
		(start 10.902696 -260.64083)
		(end 10.902696 -260.07568)
		(width 0.14605)
		(layer "In2.Cu")
		(net "HDD_PRSNT0")
	)
	(segment
		(start 5.582412 -438.383426)
		(end 10.04951 -433.916328)
		(width 0.14605)
		(layer "In2.Cu")
		(net "HDD_PRSNT0")
	)
	(segment
		(start 10.90295 -263.764522)
		(end 10.90295 -260.641084)
		(width 0.14605)
		(layer "In2.Cu")
		(net "HDD_PRSNT0")
	)
	(segment
		(start 10.04951 -433.916328)
		(end 10.04951 -407.643838)
		(width 0.14605)
		(layer "In2.Cu")
		(net "HDD_PRSNT0")
	)
	(segment
		(start 10.04951 -407.643838)
		(end 9.718548 -407.312876)
		(width 0.14605)
		(layer "In2.Cu")
		(net "HDD_PRSNT0")
	)
	(segment
		(start 7.73684 -458.081888)
		(end 7.727442 -458.03439)
		(width 0.14605)
		(layer "In2.Cu")
		(net "HDD_PRSNT0")
	)
	(segment
		(start 8.384032 -394.956792)
		(end 8.96874 -394.372084)
		(width 0.14605)
		(layer "In2.Cu")
		(net "HDD_PRSNT0")
	)
	(segment
		(start 8.273288 -217.80627)
		(end 8.273288 -212.517482)
		(width 0.14605)
		(layer "In2.Cu")
		(net "HDD_PRSNT0")
	)
	(segment
		(start 8.384032 -395.881098)
		(end 8.384032 -394.956792)
		(width 0.14605)
		(layer "In2.Cu")
		(net "HDD_PRSNT0")
	)
	(segment
		(start 10.074148 -387.194298)
		(end 10.074148 -374.376696)
		(width 0.14605)
		(layer "In2.Cu")
		(net "HDD_PRSNT0")
	)
	(segment
		(start 9.22528 -403.427184)
		(end 9.22528 -396.722346)
		(width 0.14605)
		(layer "In2.Cu")
		(net "HDD_PRSNT0")
	)
	(segment
		(start 7.727442 -458.03439)
		(end 5.582412 -455.88936)
		(width 0.14605)
		(layer "In2.Cu")
		(net "HDD_PRSNT0")
	)
	(segment
		(start 10.385552 -258.355592)
		(end 9.822688 -257.792728)
		(width 0.14605)
		(layer "In2.Cu")
		(net "HDD_PRSNT0")
	)
	(segment
		(start 9.22528 -396.722346)
		(end 8.384032 -395.881098)
		(width 0.14605)
		(layer "In2.Cu")
		(net "HDD_PRSNT0")
	)
	(segment
		(start 6.629146 -462.468214)
		(end 7.727188 -461.370172)
		(width 0.14605)
		(layer "In2.Cu")
		(net "HDD_PRSNT0")
	)
	(segment
		(start 5.582412 -455.88936)
		(end 5.582412 -438.383426)
		(width 0.14605)
		(layer "In2.Cu")
		(net "HDD_PRSNT0")
	)
	(segment
		(start 10.074148 -374.376696)
		(end 10.5918 -373.859044)
		(width 0.14605)
		(layer "In2.Cu")
		(net "HDD_PRSNT0")
	)
	(segment
		(start 7.787894 -212.032088)
		(end 7.787894 -207.108552)
		(width 0.14605)
		(layer "In2.Cu")
		(net "HDD_PRSNT0")
	)
	(segment
		(start 6.629146 -463.5373)
		(end 6.629146 -462.468214)
		(width 0.14605)
		(layer "In2.Cu")
		(net "HDD_PRSNT0")
	)
	(segment
		(start 10.90295 -260.641084)
		(end 10.902696 -260.64083)
		(width 0.14605)
		(layer "In2.Cu")
		(net "HDD_PRSNT0")
	)
	(segment
		(start 7.73684 -461.321404)
		(end 7.73684 -458.081888)
		(width 0.14605)
		(layer "In2.Cu")
		(net "HDD_PRSNT0")
	)
	(segment
		(start 10.5918 -367.55578)
		(end 10.13079 -367.09477)
		(width 0.14605)
		(layer "In2.Cu")
		(net "HDD_PRSNT0")
	)
	(segment
		(start 10.130536 -269.023084)
		(end 10.130536 -264.536936)
		(width 0.14605)
		(layer "In2.Cu")
		(net "HDD_PRSNT0")
	)
	(segment
		(start 10.385552 -259.519674)
		(end 10.385552 -258.355592)
		(width 0.14605)
		(layer "In2.Cu")
		(net "HDD_PRSNT0")
	)
	(segment
		(start 8.96874 -391.036302)
		(end 9.149842 -390.8552)
		(width 0.14605)
		(layer "In2.Cu")
		(net "HDD_PRSNT0")
	)
	(segment
		(start 8.273288 -212.517482)
		(end 7.787894 -212.032088)
		(width 0.14605)
		(layer "In2.Cu")
		(net "HDD_PRSNT0")
	)
	(segment
		(start 10.13079 -269.023338)
		(end 10.130536 -269.023084)
		(width 0.14605)
		(layer "In2.Cu")
		(net "HDD_PRSNT0")
	)
	(segment
		(start 9.149842 -388.118604)
		(end 10.074148 -387.194298)
		(width 0.14605)
		(layer "In2.Cu")
		(net "HDD_PRSNT0")
	)
	(segment
		(start 10.902696 -260.07568)
		(end 10.385552 -259.519674)
		(width 0.14605)
		(layer "In2.Cu")
		(net "HDD_PRSNT0")
	)
	(segment
		(start 10.13079 -367.09477)
		(end 10.13079 -269.023338)
		(width 0.14605)
		(layer "In2.Cu")
		(net "HDD_PRSNT0")
	)
	(segment
		(start 10.5918 -373.859044)
		(end 10.5918 -367.55578)
		(width 0.14605)
		(layer "In2.Cu")
		(net "HDD_PRSNT0")
	)
	(segment
		(start 9.718548 -407.312876)
		(end 9.718548 -403.920452)
		(width 0.14605)
		(layer "In2.Cu")
		(net "HDD_PRSNT0")
	)
	(segment
		(start 9.718548 -403.920452)
		(end 9.22528 -403.427184)
		(width 0.14605)
		(layer "In2.Cu")
		(net "HDD_PRSNT0")
	)
	(segment
		(start 10.130536 -264.536936)
		(end 10.90295 -263.764522)
		(width 0.14605)
		(layer "In2.Cu")
		(net "HDD_PRSNT0")
	)
	(segment
		(start 7.787894 -207.108552)
		(end 8.051546 -206.8449)
		(width 0.14605)
		(layer "In2.Cu")
		(net "HDD_PRSNT0")
	)
	(segment
		(start 9.149842 -390.8552)
		(end 9.149842 -388.118604)
		(width 0.14605)
		(layer "In2.Cu")
		(net "HDD_PRSNT0")
	)
	(segment
		(start 9.822688 -257.792728)
		(end 9.822688 -219.35567)
		(width 0.14605)
		(layer "In2.Cu")
		(net "HDD_PRSNT0")
	)
	(segment
		(start 211.026756 -472.3257)
		(end 217.122756 -478.4217)
		(width 0.14605)
		(layer "In5.Cu")
		(net "HDD_PRSNT0")
	)
	(segment
		(start 13.935964 -471.23985)
		(end 34.977324 -471.23985)
		(width 0.14605)
		(layer "In5.Cu")
		(net "HDD_PRSNT0")
	)
	(segment
		(start 38.3413 -472.3257)
		(end 211.026756 -472.3257)
		(width 0.14605)
		(layer "In5.Cu")
		(net "HDD_PRSNT0")
	)
	(segment
		(start 13.840714 -471.144854)
		(end 13.840968 -471.144854)
		(width 0.14605)
		(layer "In5.Cu")
		(net "HDD_PRSNT0")
	)
	(segment
		(start 9.245346 -465.872068)
		(end 10.598912 -467.225634)
		(width 0.14605)
		(layer "In5.Cu")
		(net "HDD_PRSNT0")
	)
	(segment
		(start 10.598912 -467.903052)
		(end 13.840714 -471.144854)
		(width 0.14605)
		(layer "In5.Cu")
		(net "HDD_PRSNT0")
	)
	(segment
		(start 13.840968 -471.144854)
		(end 13.935964 -471.23985)
		(width 0.14605)
		(layer "In5.Cu")
		(net "HDD_PRSNT0")
	)
	(segment
		(start 9.245346 -464.5025)
		(end 9.245346 -465.872068)
		(width 0.14605)
		(layer "In5.Cu")
		(net "HDD_PRSNT0")
	)
	(segment
		(start 35.332162 -470.885012)
		(end 36.900612 -470.885012)
		(width 0.14605)
		(layer "In5.Cu")
		(net "HDD_PRSNT0")
	)
	(segment
		(start 36.900612 -470.885012)
		(end 38.3413 -472.3257)
		(width 0.14605)
		(layer "In5.Cu")
		(net "HDD_PRSNT0")
	)
	(segment
		(start 34.977324 -471.23985)
		(end 35.332162 -470.885012)
		(width 0.14605)
		(layer "In5.Cu")
		(net "HDD_PRSNT0")
	)
	(segment
		(start 10.598912 -467.225634)
		(end 10.598912 -467.903052)
		(width 0.14605)
		(layer "In5.Cu")
		(net "HDD_PRSNT0")
	)
	(segment
		(start 190.754 -495.4905)
		(end 190.1825 -495.4905)
		(width 0.111252)
		(layer "F.Cu")
		(net "SW_PWR_R_HDD0")
	)
	(segment
		(start 190.1825 -495.4905)
		(end 189.484 -496.189)
		(width 0.111252)
		(layer "F.Cu")
		(net "SW_PWR_R_HDD0")
	)
	(segment
		(start 191.125602 -495.862102)
		(end 190.754 -495.4905)
		(width 0.111252)
		(layer "F.Cu")
		(net "SW_PWR_R_HDD0")
	)
	(segment
		(start 192.306956 -495.862102)
		(end 191.125602 -495.862102)
		(width 0.111252)
		(layer "F.Cu")
		(net "SW_PWR_R_HDD0")
	)
	(via
		(at 189.484 -496.189)
		(size 0.7112)
		(drill 0.3556)
		(layers "F.Cu" "B.Cu")
		(net "SW_PWR_R_HDD0")
	)
	(segment
		(start 209.676746 -50.6857)
		(end 209.676746 -51.8287)
		(width 0.111252)
		(layer "F.Cu")
		(net "I2C_B_TMP4_ALERT")
	)
	(segment
		(start 210.284568 -49.05502)
		(end 210.284568 -50.077878)
		(width 0.111252)
		(layer "F.Cu")
		(net "I2C_B_TMP4_ALERT")
	)
	(segment
		(start 210.284568 -50.077878)
		(end 209.676746 -50.6857)
		(width 0.111252)
		(layer "F.Cu")
		(net "I2C_B_TMP4_ALERT")
	)
	(segment
		(start 210.284822 -49.054766)
		(end 210.284568 -49.05502)
		(width 0.111252)
		(layer "F.Cu")
		(net "I2C_B_TMP4_ALERT")
	)
	(segment
		(start 209.676746 -51.8287)
		(end 209.422746 -52.0827)
		(width 0.111252)
		(layer "F.Cu")
		(net "I2C_B_TMP4_ALERT")
	)
	(segment
		(start 46.329346 -125.4379)
		(end 44.906946 -125.4379)
		(width 0.111252)
		(layer "F.Cu")
		(net "SAS2X28_B_HDD13_FLT")
	)
	(segment
		(start 44.906946 -125.4379)
		(end 44.957746 -125.3871)
		(width 0.111252)
		(layer "F.Cu")
		(net "SAS2X28_B_HDD13_FLT")
	)
	(segment
		(start 5.555488 -138.500358)
		(end 3.19405 -138.500358)
		(width 0.111252)
		(layer "F.Cu")
		(net "SAS2X28_B_HDD13_FLT")
	)
	(segment
		(start 3.19405 -138.500358)
		(end 3.192526 -138.498834)
		(width 0.111252)
		(layer "F.Cu")
		(net "SAS2X28_B_HDD13_FLT")
	)
	(segment
		(start 15.6845 -138.1125)
		(end 5.943346 -138.1125)
		(width 0.111252)
		(layer "F.Cu")
		(net "SAS2X28_B_HDD13_FLT")
	)
	(segment
		(start 16.662146 -137.134854)
		(end 15.6845 -138.1125)
		(width 0.111252)
		(layer "F.Cu")
		(net "SAS2X28_B_HDD13_FLT")
	)
	(segment
		(start 5.943346 -138.1125)
		(end 5.555488 -138.500358)
		(width 0.111252)
		(layer "F.Cu")
		(net "SAS2X28_B_HDD13_FLT")
	)
	(segment
		(start 44.957746 -125.3871)
		(end 44.957746 -124.691902)
		(width 0.111252)
		(layer "F.Cu")
		(net "SAS2X28_B_HDD13_FLT")
	)
	(segment
		(start 47.243746 -126.0856)
		(end 46.977046 -126.0856)
		(width 0.111252)
		(layer "F.Cu")
		(net "SAS2X28_B_HDD13_FLT")
	)
	(segment
		(start 16.662146 -130.6195)
		(end 16.662146 -137.134854)
		(width 0.111252)
		(layer "F.Cu")
		(net "SAS2X28_B_HDD13_FLT")
	)
	(segment
		(start 46.977046 -126.0856)
		(end 46.329346 -125.4379)
		(width 0.111252)
		(layer "F.Cu")
		(net "SAS2X28_B_HDD13_FLT")
	)
	(via
		(at 44.906946 -125.4379)
		(size 0.5588)
		(drill 0.3048)
		(layers "F.Cu" "B.Cu")
		(net "SAS2X28_B_HDD13_FLT")
	)
	(via
		(at 31.495746 -125.7427)
		(size 0.7112)
		(drill 0.3556)
		(layers "F.Cu" "B.Cu")
		(net "SAS2X28_B_HDD13_FLT")
	)
	(via
		(at 16.662146 -130.6195)
		(size 0.5588)
		(drill 0.3048)
		(layers "F.Cu" "B.Cu")
		(net "SAS2X28_B_HDD13_FLT")
	)
	(segment
		(start 20.930362 -125.7554)
		(end 20.943062 -125.7427)
		(width 0.111252)
		(layer "B.Cu")
		(net "SAS2X28_B_HDD13_FLT")
	)
	(segment
		(start 20.5486 -125.7554)
		(end 20.930362 -125.7554)
		(width 0.111252)
		(layer "B.Cu")
		(net "SAS2X28_B_HDD13_FLT")
	)
	(segment
		(start 16.662146 -130.6195)
		(end 16.662146 -129.641854)
		(width 0.111252)
		(layer "B.Cu")
		(net "SAS2X28_B_HDD13_FLT")
	)
	(segment
		(start 16.662146 -129.641854)
		(end 20.5486 -125.7554)
		(width 0.111252)
		(layer "B.Cu")
		(net "SAS2X28_B_HDD13_FLT")
	)
	(segment
		(start 44.906946 -125.4379)
		(end 44.602146 -125.7427)
		(width 0.111252)
		(layer "B.Cu")
		(net "SAS2X28_B_HDD13_FLT")
	)
	(segment
		(start 20.943062 -125.7427)
		(end 31.495746 -125.7427)
		(width 0.111252)
		(layer "B.Cu")
		(net "SAS2X28_B_HDD13_FLT")
	)
	(segment
		(start 44.602146 -125.7427)
		(end 31.495746 -125.7427)
		(width 0.111252)
		(layer "B.Cu")
		(net "SAS2X28_B_HDD13_FLT")
	)
	(segment
		(start 210.284568 -459.852522)
		(end 210.057746 -459.6257)
		(width 0.111252)
		(layer "F.Cu")
		(net "I2C_B_TMP3_ALERT")
	)
	(segment
		(start 210.057746 -459.6257)
		(end 207.009746 -459.6257)
		(width 0.111252)
		(layer "F.Cu")
		(net "I2C_B_TMP3_ALERT")
	)
	(segment
		(start 210.284822 -461.054958)
		(end 210.284568 -461.054704)
		(width 0.111252)
		(layer "F.Cu")
		(net "I2C_B_TMP3_ALERT")
	)
	(segment
		(start 207.009746 -459.6257)
		(end 206.882746 -459.4987)
		(width 0.111252)
		(layer "F.Cu")
		(net "I2C_B_TMP3_ALERT")
	)
	(segment
		(start 210.284568 -461.054704)
		(end 210.284568 -459.852522)
		(width 0.111252)
		(layer "F.Cu")
		(net "I2C_B_TMP3_ALERT")
	)
	(segment
		(start 28.575 -151.989536)
		(end 28.575 -152.275286)
		(width 0.09525)
		(layer "F.Cu")
		(net "SAS2X28_A_HDD13_RX_-")
	)
	(segment
		(start 26.851864 -139.7)
		(end 27.834844 -139.7)
		(width 0.09525)
		(layer "F.Cu")
		(net "SAS2X28_A_HDD13_RX_-")
	)
	(segment
		(start 24.13 -186.8932)
		(end 29.592524 -192.355724)
		(width 0.09525)
		(layer "F.Cu")
		(net "SAS2X28_A_HDD13_RX_-")
	)
	(segment
		(start 28.575 -147.537932)
		(end 28.575 -149.273006)
		(width 0.09525)
		(layer "F.Cu")
		(net "SAS2X28_A_HDD13_RX_-")
	)
	(segment
		(start 25.343612 -156.317188)
		(end 24.289766 -157.371034)
		(width 0.09525)
		(layer "F.Cu")
		(net "SAS2X28_A_HDD13_RX_-")
	)
	(segment
		(start 23.5458 -159.167068)
		(end 23.5458 -185.482484)
		(width 0.09525)
		(layer "F.Cu")
		(net "SAS2X28_A_HDD13_RX_-")
	)
	(segment
		(start 10.044938 -274.47113)
		(end 10.044938 -354.348034)
		(width 0.09525)
		(layer "F.Cu")
		(net "SAS2X28_A_HDD13_RX_-")
	)
	(segment
		(start 26.46553 -139.950952)
		(end 26.620724 -139.795758)
		(width 0.09525)
		(layer "F.Cu")
		(net "SAS2X28_A_HDD13_RX_-")
	)
	(segment
		(start 28.575 -144.535652)
		(end 28.575 -144.821402)
		(width 0.09525)
		(layer "F.Cu")
		(net "SAS2X28_A_HDD13_RX_-")
	)
	(segment
		(start 28.34259 -149.737826)
		(end 28.34259 -150.023576)
		(width 0.09525)
		(layer "F.Cu")
		(net "SAS2X28_A_HDD13_RX_-")
	)
	(segment
		(start 7.43712 -358.462326)
		(end 7.365746 -358.5337)
		(width 0.09525)
		(layer "F.Cu")
		(net "SAS2X28_A_HDD13_RX_-")
	)
	(segment
		(start 28.34259 -142.283942)
		(end 28.34259 -142.569692)
		(width 0.09525)
		(layer "F.Cu")
		(net "SAS2X28_A_HDD13_RX_-")
	)
	(segment
		(start 28.34259 -146.787362)
		(end 28.34259 -147.073112)
		(width 0.09525)
		(layer "F.Cu")
		(net "SAS2X28_A_HDD13_RX_-")
	)
	(segment
		(start 30.4546 -194.437)
		(end 30.4546 -251.957332)
		(width 0.09525)
		(layer "F.Cu")
		(net "SAS2X28_A_HDD13_RX_-")
	)
	(segment
		(start 28.34259 -145.286222)
		(end 28.34259 -145.571972)
		(width 0.09525)
		(layer "F.Cu")
		(net "SAS2X28_A_HDD13_RX_-")
	)
	(segment
		(start 28.575 -143.034512)
		(end 28.575 -143.320262)
		(width 0.09525)
		(layer "F.Cu")
		(net "SAS2X28_A_HDD13_RX_-")
	)
	(segment
		(start 29.710634 -253.753366)
		(end 10.788904 -272.675096)
		(width 0.09525)
		(layer "F.Cu")
		(net "SAS2X28_A_HDD13_RX_-")
	)
	(segment
		(start 28.34259 -151.238966)
		(end 28.34259 -151.524716)
		(width 0.09525)
		(layer "F.Cu")
		(net "SAS2X28_A_HDD13_RX_-")
	)
	(segment
		(start 7.670546 -357.555038)
		(end 7.670546 -357.8987)
		(width 0.09525)
		(layer "F.Cu")
		(net "SAS2X28_A_HDD13_RX_-")
	)
	(segment
		(start 28.575 -140.260578)
		(end 28.575 -141.819122)
		(width 0.09525)
		(layer "F.Cu")
		(net "SAS2X28_A_HDD13_RX_-")
	)
	(segment
		(start 28.00096 -153.660094)
		(end 25.343612 -156.317188)
		(width 0.09525)
		(layer "F.Cu")
		(net "SAS2X28_A_HDD13_RX_-")
	)
	(segment
		(start 28.575 -150.488396)
		(end 28.575 -150.774146)
		(width 0.09525)
		(layer "F.Cu")
		(net "SAS2X28_A_HDD13_RX_-")
	)
	(segment
		(start 28.34259 -143.785082)
		(end 28.34259 -144.070832)
		(width 0.09525)
		(layer "F.Cu")
		(net "SAS2X28_A_HDD13_RX_-")
	)
	(segment
		(start 9.776714 -355.089714)
		(end 7.924292 -356.942136)
		(width 0.09525)
		(layer "F.Cu")
		(net "SAS2X28_A_HDD13_RX_-")
	)
	(segment
		(start 28.575 -146.036792)
		(end 28.575 -146.322542)
		(width 0.09525)
		(layer "F.Cu")
		(net "SAS2X28_A_HDD13_RX_-")
	)
	(via
		(at 7.365746 -358.5337)
		(size 0.5588)
		(drill 0.3048)
		(layers "F.Cu" "B.Cu")
		(net "SAS2X28_A_HDD13_RX_-")
	)
	(arc
		(start 28.458668 -142.802102)
		(mid 28.545067 -142.904176)
		(end 28.575 -143.034512)
		(width 0.09525)
		(layer "F.Cu")
		(net "SAS2X28_A_HDD13_RX_-")
	)
	(arc
		(start 28.458668 -149.505416)
		(mid 28.372437 -149.607533)
		(end 28.34259 -149.737826)
		(width 0.09525)
		(layer "F.Cu")
		(net "SAS2X28_A_HDD13_RX_-")
	)
	(arc
		(start 28.34259 -144.070832)
		(mid 28.372387 -144.20115)
		(end 28.458668 -144.303242)
		(width 0.09525)
		(layer "F.Cu")
		(net "SAS2X28_A_HDD13_RX_-")
	)
	(arc
		(start 28.458668 -151.006556)
		(mid 28.372437 -151.108673)
		(end 28.34259 -151.238966)
		(width 0.09525)
		(layer "F.Cu")
		(net "SAS2X28_A_HDD13_RX_-")
	)
	(arc
		(start 28.575 -152.275286)
		(mid 28.425763 -153.024808)
		(end 28.00096 -153.660094)
		(width 0.09525)
		(layer "F.Cu")
		(net "SAS2X28_A_HDD13_RX_-")
	)
	(arc
		(start 28.34259 -147.073112)
		(mid 28.372387 -147.20343)
		(end 28.458668 -147.305522)
		(width 0.09525)
		(layer "F.Cu")
		(net "SAS2X28_A_HDD13_RX_-")
	)
	(arc
		(start 7.924292 -356.942136)
		(mid 7.736506 -357.223366)
		(end 7.670546 -357.555038)
		(width 0.09525)
		(layer "F.Cu")
		(net "SAS2X28_A_HDD13_RX_-")
	)
	(arc
		(start 28.575 -146.322542)
		(mid 28.545064 -146.452877)
		(end 28.458668 -146.554952)
		(width 0.09525)
		(layer "F.Cu")
		(net "SAS2X28_A_HDD13_RX_-")
	)
	(arc
		(start 28.458668 -144.303242)
		(mid 28.545067 -144.405316)
		(end 28.575 -144.535652)
		(width 0.09525)
		(layer "F.Cu")
		(net "SAS2X28_A_HDD13_RX_-")
	)
	(arc
		(start 28.458668 -143.552672)
		(mid 28.372437 -143.654789)
		(end 28.34259 -143.785082)
		(width 0.09525)
		(layer "F.Cu")
		(net "SAS2X28_A_HDD13_RX_-")
	)
	(arc
		(start 28.458668 -147.305522)
		(mid 28.545067 -147.407596)
		(end 28.575 -147.537932)
		(width 0.09525)
		(layer "F.Cu")
		(net "SAS2X28_A_HDD13_RX_-")
	)
	(arc
		(start 30.4546 -251.957332)
		(mid 30.261254 -252.929348)
		(end 29.710634 -253.753366)
		(width 0.09525)
		(layer "F.Cu")
		(net "SAS2X28_A_HDD13_RX_-")
	)
	(arc
		(start 28.458668 -146.554952)
		(mid 28.372437 -146.657069)
		(end 28.34259 -146.787362)
		(width 0.09525)
		(layer "F.Cu")
		(net "SAS2X28_A_HDD13_RX_-")
	)
	(arc
		(start 7.670546 -357.8987)
		(mid 7.609874 -358.203719)
		(end 7.43712 -358.462326)
		(width 0.09525)
		(layer "F.Cu")
		(net "SAS2X28_A_HDD13_RX_-")
	)
	(arc
		(start 10.044938 -354.348034)
		(mid 9.99346 -354.748762)
		(end 9.776714 -355.089714)
		(width 0.09525)
		(layer "F.Cu")
		(net "SAS2X28_A_HDD13_RX_-")
	)
	(arc
		(start 28.575 -149.273006)
		(mid 28.545064 -149.403341)
		(end 28.458668 -149.505416)
		(width 0.09525)
		(layer "F.Cu")
		(net "SAS2X28_A_HDD13_RX_-")
	)
	(arc
		(start 28.575 -144.821402)
		(mid 28.545064 -144.951737)
		(end 28.458668 -145.053812)
		(width 0.09525)
		(layer "F.Cu")
		(net "SAS2X28_A_HDD13_RX_-")
	)
	(arc
		(start 28.34259 -142.569692)
		(mid 28.372387 -142.70001)
		(end 28.458668 -142.802102)
		(width 0.09525)
		(layer "F.Cu")
		(net "SAS2X28_A_HDD13_RX_-")
	)
	(arc
		(start 28.448 -139.954)
		(mid 28.541985 -140.094659)
		(end 28.575 -140.260578)
		(width 0.09525)
		(layer "F.Cu")
		(net "SAS2X28_A_HDD13_RX_-")
	)
	(arc
		(start 28.575 -150.774146)
		(mid 28.545064 -150.904481)
		(end 28.458668 -151.006556)
		(width 0.09525)
		(layer "F.Cu")
		(net "SAS2X28_A_HDD13_RX_-")
	)
	(arc
		(start 27.834844 -139.7)
		(mid 28.16669 -139.766008)
		(end 28.448 -139.954)
		(width 0.09525)
		(layer "F.Cu")
		(net "SAS2X28_A_HDD13_RX_-")
	)
	(arc
		(start 28.458668 -145.053812)
		(mid 28.372437 -145.155929)
		(end 28.34259 -145.286222)
		(width 0.09525)
		(layer "F.Cu")
		(net "SAS2X28_A_HDD13_RX_-")
	)
	(arc
		(start 10.788904 -272.675096)
		(mid 10.238306 -273.499123)
		(end 10.044938 -274.47113)
		(width 0.09525)
		(layer "F.Cu")
		(net "SAS2X28_A_HDD13_RX_-")
	)
	(arc
		(start 28.34259 -150.023576)
		(mid 28.372387 -150.153894)
		(end 28.458668 -150.255986)
		(width 0.09525)
		(layer "F.Cu")
		(net "SAS2X28_A_HDD13_RX_-")
	)
	(arc
		(start 29.592524 -192.355724)
		(mid 30.230566 -193.310622)
		(end 30.4546 -194.437)
		(width 0.09525)
		(layer "F.Cu")
		(net "SAS2X28_A_HDD13_RX_-")
	)
	(arc
		(start 23.5458 -185.482484)
		(mid 23.697624 -186.245934)
		(end 24.13 -186.8932)
		(width 0.09525)
		(layer "F.Cu")
		(net "SAS2X28_A_HDD13_RX_-")
	)
	(arc
		(start 24.289766 -157.371034)
		(mid 23.739168 -158.195061)
		(end 23.5458 -159.167068)
		(width 0.09525)
		(layer "F.Cu")
		(net "SAS2X28_A_HDD13_RX_-")
	)
	(arc
		(start 28.34259 -145.571972)
		(mid 28.372387 -145.70229)
		(end 28.458668 -145.804382)
		(width 0.09525)
		(layer "F.Cu")
		(net "SAS2X28_A_HDD13_RX_-")
	)
	(arc
		(start 28.458668 -150.255986)
		(mid 28.545067 -150.35806)
		(end 28.575 -150.488396)
		(width 0.09525)
		(layer "F.Cu")
		(net "SAS2X28_A_HDD13_RX_-")
	)
	(arc
		(start 28.34259 -151.524716)
		(mid 28.372387 -151.655034)
		(end 28.458668 -151.757126)
		(width 0.09525)
		(layer "F.Cu")
		(net "SAS2X28_A_HDD13_RX_-")
	)
	(arc
		(start 28.458668 -151.757126)
		(mid 28.545067 -151.8592)
		(end 28.575 -151.989536)
		(width 0.09525)
		(layer "F.Cu")
		(net "SAS2X28_A_HDD13_RX_-")
	)
	(arc
		(start 28.458668 -145.804382)
		(mid 28.545067 -145.906456)
		(end 28.575 -146.036792)
		(width 0.09525)
		(layer "F.Cu")
		(net "SAS2X28_A_HDD13_RX_-")
	)
	(arc
		(start 28.575 -141.819122)
		(mid 28.545064 -141.949457)
		(end 28.458668 -142.051532)
		(width 0.09525)
		(layer "F.Cu")
		(net "SAS2X28_A_HDD13_RX_-")
	)
	(arc
		(start 28.458668 -142.051532)
		(mid 28.372437 -142.153649)
		(end 28.34259 -142.283942)
		(width 0.09525)
		(layer "F.Cu")
		(net "SAS2X28_A_HDD13_RX_-")
	)
	(arc
		(start 28.575 -143.320262)
		(mid 28.545064 -143.450597)
		(end 28.458668 -143.552672)
		(width 0.09525)
		(layer "F.Cu")
		(net "SAS2X28_A_HDD13_RX_-")
	)
	(arc
		(start 26.620724 -139.795758)
		(mid 26.726772 -139.724899)
		(end 26.851864 -139.7)
		(width 0.09525)
		(layer "F.Cu")
		(net "SAS2X28_A_HDD13_RX_-")
	)
	(segment
		(start 4.97332 -354.499926)
		(end 4.971796 -354.498402)
		(width 0.09525)
		(layer "B.Cu")
		(net "SAS2X28_A_HDD13_RX_-")
	)
	(segment
		(start 7.670546 -356.094284)
		(end 7.670292 -356.094538)
		(width 0.09525)
		(layer "B.Cu")
		(net "SAS2X28_A_HDD13_RX_-")
	)
	(segment
		(start 6.092952 -354.212398)
		(end 5.893054 -354.212398)
		(width 0.09525)
		(layer "B.Cu")
		(net "SAS2X28_A_HDD13_RX_-")
	)
	(segment
		(start 7.365492 -355.358446)
		(end 6.400038 -354.392992)
		(width 0.09525)
		(layer "B.Cu")
		(net "SAS2X28_A_HDD13_RX_-")
	)
	(segment
		(start 5.889752 -354.2157)
		(end 5.659374 -354.2157)
		(width 0.09525)
		(layer "B.Cu")
		(net "SAS2X28_A_HDD13_RX_-")
	)
	(segment
		(start 7.365746 -355.358446)
		(end 7.365492 -355.358446)
		(width 0.09525)
		(layer "B.Cu")
		(net "SAS2X28_A_HDD13_RX_-")
	)
	(segment
		(start 5.893054 -354.212398)
		(end 5.889752 -354.2157)
		(width 0.09525)
		(layer "B.Cu")
		(net "SAS2X28_A_HDD13_RX_-")
	)
	(segment
		(start 4.971796 -354.498402)
		(end 2.811526 -354.498402)
		(width 0.09525)
		(layer "B.Cu")
		(net "SAS2X28_A_HDD13_RX_-")
	)
	(segment
		(start 7.365746 -358.5337)
		(end 7.43712 -358.462326)
		(width 0.09525)
		(layer "B.Cu")
		(net "SAS2X28_A_HDD13_RX_-")
	)
	(segment
		(start 6.400038 -354.392992)
		(end 6.309106 -354.301806)
		(width 0.09525)
		(layer "B.Cu")
		(net "SAS2X28_A_HDD13_RX_-")
	)
	(segment
		(start 7.670546 -357.8987)
		(end 7.670546 -356.094284)
		(width 0.09525)
		(layer "B.Cu")
		(net "SAS2X28_A_HDD13_RX_-")
	)
	(arc
		(start 7.670292 -356.094538)
		(mid 7.591259 -355.696181)
		(end 7.365746 -355.358446)
		(width 0.09525)
		(layer "B.Cu")
		(net "SAS2X28_A_HDD13_RX_-")
	)
	(arc
		(start 7.43712 -358.462326)
		(mid 7.609907 -358.203732)
		(end 7.670546 -357.8987)
		(width 0.09525)
		(layer "B.Cu")
		(net "SAS2X28_A_HDD13_RX_-")
	)
	(arc
		(start 5.320284 -354.356162)
		(mid 5.161096 -354.462528)
		(end 4.97332 -354.499926)
		(width 0.09525)
		(layer "B.Cu")
		(net "SAS2X28_A_HDD13_RX_-")
	)
	(arc
		(start 6.309106 -354.301806)
		(mid 6.209919 -354.235595)
		(end 6.092952 -354.212398)
		(width 0.09525)
		(layer "B.Cu")
		(net "SAS2X28_A_HDD13_RX_-")
	)
	(arc
		(start 5.659374 -354.2157)
		(mid 5.475857 -354.252204)
		(end 5.320284 -354.356162)
		(width 0.09525)
		(layer "B.Cu")
		(net "SAS2X28_A_HDD13_RX_-")
	)
	(segment
		(start 24.523446 -157.604714)
		(end 25.577292 -156.550868)
		(width 0.09525)
		(layer "F.Cu")
		(net "SAS2X28_A_HDD13_RX_+")
	)
	(segment
		(start 23.876 -185.48223)
		(end 23.876 -159.167068)
		(width 0.09525)
		(layer "F.Cu")
		(net "SAS2X28_A_HDD13_RX_+")
	)
	(segment
		(start 29.826204 -192.122044)
		(end 24.36368 -186.65952)
		(width 0.09525)
		(layer "F.Cu")
		(net "SAS2X28_A_HDD13_RX_+")
	)
	(segment
		(start 8.000746 -357.92918)
		(end 8.000746 -357.555292)
		(width 0.09525)
		(layer "F.Cu")
		(net "SAS2X28_A_HDD13_RX_+")
	)
	(segment
		(start 28.9052 -152.275286)
		(end 28.9052 -140.260324)
		(width 0.09525)
		(layer "F.Cu")
		(net "SAS2X28_A_HDD13_RX_+")
	)
	(segment
		(start 8.157972 -357.175816)
		(end 10.010394 -355.323394)
		(width 0.09525)
		(layer "F.Cu")
		(net "SAS2X28_A_HDD13_RX_+")
	)
	(segment
		(start 30.7848 -251.957332)
		(end 30.7848 -194.437254)
		(width 0.09525)
		(layer "F.Cu")
		(net "SAS2X28_A_HDD13_RX_+")
	)
	(segment
		(start 27.835098 -139.3698)
		(end 27.208734 -139.3698)
		(width 0.09525)
		(layer "F.Cu")
		(net "SAS2X28_A_HDD13_RX_+")
	)
	(segment
		(start 25.577292 -156.550868)
		(end 28.23464 -153.893774)
		(width 0.09525)
		(layer "F.Cu")
		(net "SAS2X28_A_HDD13_RX_+")
	)
	(segment
		(start 10.375138 -354.334064)
		(end 10.375138 -274.47113)
		(width 0.09525)
		(layer "F.Cu")
		(net "SAS2X28_A_HDD13_RX_+")
	)
	(segment
		(start 11.022584 -272.908776)
		(end 29.944314 -253.987046)
		(width 0.09525)
		(layer "F.Cu")
		(net "SAS2X28_A_HDD13_RX_+")
	)
	(via
		(at 8.242554 -358.512872)
		(size 0.5588)
		(drill 0.3048)
		(layers "F.Cu" "B.Cu")
		(net "SAS2X28_A_HDD13_RX_+")
	)
	(arc
		(start 28.9052 -140.260324)
		(mid 28.84711 -139.968108)
		(end 28.68168 -139.72032)
		(width 0.09525)
		(layer "F.Cu")
		(net "SAS2X28_A_HDD13_RX_+")
	)
	(arc
		(start 10.010394 -355.323394)
		(mid 10.301271 -354.868736)
		(end 10.375138 -354.334064)
		(width 0.09525)
		(layer "F.Cu")
		(net "SAS2X28_A_HDD13_RX_+")
	)
	(arc
		(start 10.375138 -274.47113)
		(mid 10.543447 -273.625544)
		(end 11.022584 -272.908776)
		(width 0.09525)
		(layer "F.Cu")
		(net "SAS2X28_A_HDD13_RX_+")
	)
	(arc
		(start 28.23464 -153.893774)
		(mid 28.730916 -153.151234)
		(end 28.9052 -152.275286)
		(width 0.09525)
		(layer "F.Cu")
		(net "SAS2X28_A_HDD13_RX_+")
	)
	(arc
		(start 23.876 -159.167068)
		(mid 24.044309 -158.321482)
		(end 24.523446 -157.604714)
		(width 0.09525)
		(layer "F.Cu")
		(net "SAS2X28_A_HDD13_RX_+")
	)
	(arc
		(start 27.20467 -139.369546)
		(mid 26.804664 -139.288884)
		(end 26.46553 -139.061952)
		(width 0.09525)
		(layer "F.Cu")
		(net "SAS2X28_A_HDD13_RX_+")
	)
	(arc
		(start 30.7848 -194.437254)
		(mid 30.535762 -193.184315)
		(end 29.826204 -192.122044)
		(width 0.09525)
		(layer "F.Cu")
		(net "SAS2X28_A_HDD13_RX_+")
	)
	(arc
		(start 24.36368 -186.65952)
		(mid 24.002766 -186.119375)
		(end 23.876 -185.48223)
		(width 0.09525)
		(layer "F.Cu")
		(net "SAS2X28_A_HDD13_RX_+")
	)
	(arc
		(start 29.944314 -253.987046)
		(mid 30.566466 -253.05579)
		(end 30.7848 -251.957332)
		(width 0.09525)
		(layer "F.Cu")
		(net "SAS2X28_A_HDD13_RX_+")
	)
	(arc
		(start 28.68168 -139.72032)
		(mid 28.293236 -139.460897)
		(end 27.835098 -139.3698)
		(width 0.09525)
		(layer "F.Cu")
		(net "SAS2X28_A_HDD13_RX_+")
	)
	(arc
		(start 8.242554 -358.512872)
		(mid 8.063616 -358.245072)
		(end 8.000746 -357.92918)
		(width 0.09525)
		(layer "F.Cu")
		(net "SAS2X28_A_HDD13_RX_+")
	)
	(arc
		(start 8.000746 -357.555292)
		(mid 8.0416 -357.349905)
		(end 8.157972 -357.175816)
		(width 0.09525)
		(layer "F.Cu")
		(net "SAS2X28_A_HDD13_RX_+")
	)
	(arc
		(start 27.208734 -139.3698)
		(mid 27.206702 -139.369675)
		(end 27.20467 -139.369546)
		(width 0.09525)
		(layer "F.Cu")
		(net "SAS2X28_A_HDD13_RX_+")
	)
	(segment
		(start 6.633972 -354.15982)
		(end 6.542786 -354.06838)
		(width 0.09525)
		(layer "B.Cu")
		(net "SAS2X28_A_HDD13_RX_+")
	)
	(segment
		(start 2.81305 -353.499928)
		(end 2.811526 -353.498404)
		(width 0.09525)
		(layer "B.Cu")
		(net "SAS2X28_A_HDD13_RX_+")
	)
	(segment
		(start 5.092954 -353.499928)
		(end 2.81305 -353.499928)
		(width 0.09525)
		(layer "B.Cu")
		(net "SAS2X28_A_HDD13_RX_+")
	)
	(segment
		(start 6.092952 -353.882198)
		(end 5.893054 -353.882198)
		(width 0.09525)
		(layer "B.Cu")
		(net "SAS2X28_A_HDD13_RX_+")
	)
	(segment
		(start 8.000746 -357.92918)
		(end 8.000746 -356.094538)
		(width 0.09525)
		(layer "B.Cu")
		(net "SAS2X28_A_HDD13_RX_+")
	)
	(segment
		(start 5.545582 -353.706938)
		(end 5.512308 -353.673664)
		(width 0.09525)
		(layer "B.Cu")
		(net "SAS2X28_A_HDD13_RX_+")
	)
	(segment
		(start 7.599172 -355.12502)
		(end 6.633972 -354.15982)
		(width 0.09525)
		(layer "B.Cu")
		(net "SAS2X28_A_HDD13_RX_+")
	)
	(segment
		(start 5.893054 -353.882198)
		(end 5.889752 -353.878896)
		(width 0.09525)
		(layer "B.Cu")
		(net "SAS2X28_A_HDD13_RX_+")
	)
	(arc
		(start 6.542786 -354.06838)
		(mid 6.336385 -353.930561)
		(end 6.092952 -353.882198)
		(width 0.09525)
		(layer "B.Cu")
		(net "SAS2X28_A_HDD13_RX_+")
	)
	(arc
		(start 8.000746 -356.094538)
		(mid 7.896378 -355.569844)
		(end 7.599172 -355.12502)
		(width 0.09525)
		(layer "B.Cu")
		(net "SAS2X28_A_HDD13_RX_+")
	)
	(arc
		(start 8.242554 -358.512872)
		(mid 8.063616 -358.245072)
		(end 8.000746 -357.92918)
		(width 0.09525)
		(layer "B.Cu")
		(net "SAS2X28_A_HDD13_RX_+")
	)
	(arc
		(start 5.889752 -353.878896)
		(mid 5.703741 -353.82079)
		(end 5.545582 -353.706938)
		(width 0.09525)
		(layer "B.Cu")
		(net "SAS2X28_A_HDD13_RX_+")
	)
	(arc
		(start 5.512308 -353.673664)
		(mid 5.319907 -353.545106)
		(end 5.092954 -353.499928)
		(width 0.09525)
		(layer "B.Cu")
		(net "SAS2X28_A_HDD13_RX_+")
	)
	(segment
		(start 29.845 -194.777868)
		(end 29.845 -251.550678)
		(width 0.09525)
		(layer "F.Cu")
		(net "SAS2X28_A_HDD13_TX_-")
	)
	(segment
		(start 23.273766 -143.12646)
		(end 24.516842 -143.12646)
		(width 0.09525)
		(layer "F.Cu")
		(net "SAS2X28_A_HDD13_TX_-")
	)
	(segment
		(start 12.090908 -270.494252)
		(end 10.387076 -272.198084)
		(width 0.09525)
		(layer "F.Cu")
		(net "SAS2X28_A_HDD13_TX_-")
	)
	(segment
		(start 22.9108 -157.577028)
		(end 22.9108 -185.739532)
		(width 0.09525)
		(layer "F.Cu")
		(net "SAS2X28_A_HDD13_TX_-")
	)
	(segment
		(start 21.75002 -142.659862)
		(end 23.009098 -142.659862)
		(width 0.09525)
		(layer "F.Cu")
		(net "SAS2X28_A_HDD13_TX_-")
	)
	(segment
		(start 7.060946 -356.882954)
		(end 7.060946 -357.095298)
		(width 0.09525)
		(layer "F.Cu")
		(net "SAS2X28_A_HDD13_TX_-")
	)
	(segment
		(start 5.615432 -358.152192)
		(end 5.524754 -358.152192)
		(width 0.09525)
		(layer "F.Cu")
		(net "SAS2X28_A_HDD13_TX_-")
	)
	(segment
		(start 9.397746 -274.586446)
		(end 9.397746 -354.156772)
		(width 0.09525)
		(layer "F.Cu")
		(net "SAS2X28_A_HDD13_TX_-")
	)
	(segment
		(start 25.602946 -144.693894)
		(end 25.602946 -152.923494)
		(width 0.09525)
		(layer "F.Cu")
		(net "SAS2X28_A_HDD13_TX_-")
	)
	(segment
		(start 24.96058 -154.47518)
		(end 23.65502 -155.78074)
		(width 0.09525)
		(layer "F.Cu")
		(net "SAS2X28_A_HDD13_TX_-")
	)
	(segment
		(start 6.150864 -358.0257)
		(end 5.920994 -358.0257)
		(width 0.09525)
		(layer "F.Cu")
		(net "SAS2X28_A_HDD13_TX_-")
	)
	(segment
		(start 4.688078 -358.498902)
		(end 3.192526 -358.498902)
		(width 0.09525)
		(layer "F.Cu")
		(net "SAS2X28_A_HDD13_TX_-")
	)
	(segment
		(start 29.004514 -253.580392)
		(end 20.547584 -262.037322)
		(width 0.09525)
		(layer "F.Cu")
		(net "SAS2X28_A_HDD13_TX_-")
	)
	(segment
		(start 5.19938 -358.286812)
		(end 5.19557 -358.290876)
		(width 0.09525)
		(layer "F.Cu")
		(net "SAS2X28_A_HDD13_TX_-")
	)
	(segment
		(start 9.1694 -354.707952)
		(end 7.10819 -356.769162)
		(width 0.09525)
		(layer "F.Cu")
		(net "SAS2X28_A_HDD13_TX_-")
	)
	(segment
		(start 23.558246 -187.301886)
		(end 29.004514 -192.748154)
		(width 0.09525)
		(layer "F.Cu")
		(net "SAS2X28_A_HDD13_TX_-")
	)
	(segment
		(start 4.689602 -358.500426)
		(end 4.688078 -358.498902)
		(width 0.09525)
		(layer "F.Cu")
		(net "SAS2X28_A_HDD13_TX_-")
	)
	(segment
		(start 23.172166 -142.82293)
		(end 23.172166 -143.02486)
		(width 0.09525)
		(layer "F.Cu")
		(net "SAS2X28_A_HDD13_TX_-")
	)
	(segment
		(start 20.547584 -262.037322)
		(end 12.090908 -270.494252)
		(width 0.09525)
		(layer "F.Cu")
		(net "SAS2X28_A_HDD13_TX_-")
	)
	(arc
		(start 7.060946 -357.095298)
		(mid 6.989284 -357.456509)
		(end 6.784848 -357.76281)
		(width 0.09525)
		(layer "F.Cu")
		(net "SAS2X28_A_HDD13_TX_-")
	)
	(arc
		(start 5.38607 -358.173274)
		(mid 5.285892 -358.218806)
		(end 5.19938 -358.286812)
		(width 0.09525)
		(layer "F.Cu")
		(net "SAS2X28_A_HDD13_TX_-")
	)
	(arc
		(start 5.761482 -358.09174)
		(mid 5.694474 -358.136514)
		(end 5.615432 -358.152192)
		(width 0.09525)
		(layer "F.Cu")
		(net "SAS2X28_A_HDD13_TX_-")
	)
	(arc
		(start 23.172166 -143.02486)
		(mid 23.190922 -143.083596)
		(end 23.240238 -143.120618)
		(width 0.09525)
		(layer "F.Cu")
		(net "SAS2X28_A_HDD13_TX_-")
	)
	(arc
		(start 6.458712 -357.97109)
		(mid 6.307195 -358.011972)
		(end 6.150864 -358.0257)
		(width 0.09525)
		(layer "F.Cu")
		(net "SAS2X28_A_HDD13_TX_-")
	)
	(arc
		(start 29.004514 -192.748154)
		(mid 29.626666 -193.67941)
		(end 29.845 -194.777868)
		(width 0.09525)
		(layer "F.Cu")
		(net "SAS2X28_A_HDD13_TX_-")
	)
	(arc
		(start 23.009098 -142.659862)
		(mid 23.071501 -142.672275)
		(end 23.124414 -142.707614)
		(width 0.09525)
		(layer "F.Cu")
		(net "SAS2X28_A_HDD13_TX_-")
	)
	(arc
		(start 24.516842 -143.12646)
		(mid 24.802226 -143.183226)
		(end 25.044146 -143.3449)
		(width 0.09525)
		(layer "F.Cu")
		(net "SAS2X28_A_HDD13_TX_-")
	)
	(arc
		(start 5.442204 -358.159558)
		(mid 5.413922 -358.165537)
		(end 5.38607 -358.173274)
		(width 0.09525)
		(layer "F.Cu")
		(net "SAS2X28_A_HDD13_TX_-")
	)
	(arc
		(start 23.240238 -143.120618)
		(mid 23.240619 -143.120746)
		(end 23.241 -143.120872)
		(width 0.09525)
		(layer "F.Cu")
		(net "SAS2X28_A_HDD13_TX_-")
	)
	(arc
		(start 23.124414 -142.707614)
		(mid 23.159766 -142.760521)
		(end 23.172166 -142.82293)
		(width 0.09525)
		(layer "F.Cu")
		(net "SAS2X28_A_HDD13_TX_-")
	)
	(arc
		(start 25.602946 -152.923494)
		(mid 25.436047 -153.763204)
		(end 24.96058 -154.47518)
		(width 0.09525)
		(layer "F.Cu")
		(net "SAS2X28_A_HDD13_TX_-")
	)
	(arc
		(start 7.10819 -356.769162)
		(mid 7.073306 -356.82137)
		(end 7.060946 -356.882954)
		(width 0.09525)
		(layer "F.Cu")
		(net "SAS2X28_A_HDD13_TX_-")
	)
	(arc
		(start 6.784848 -357.76281)
		(mid 6.633126 -357.884716)
		(end 6.458712 -357.97109)
		(width 0.09525)
		(layer "F.Cu")
		(net "SAS2X28_A_HDD13_TX_-")
	)
	(arc
		(start 29.845 -251.550678)
		(mid 29.626602 -252.64911)
		(end 29.004514 -253.580392)
		(width 0.09525)
		(layer "F.Cu")
		(net "SAS2X28_A_HDD13_TX_-")
	)
	(arc
		(start 5.920994 -358.0257)
		(mid 5.834679 -358.042869)
		(end 5.761482 -358.09174)
		(width 0.09525)
		(layer "F.Cu")
		(net "SAS2X28_A_HDD13_TX_-")
	)
	(arc
		(start 25.044146 -143.3449)
		(mid 25.457698 -143.963824)
		(end 25.602946 -144.693894)
		(width 0.09525)
		(layer "F.Cu")
		(net "SAS2X28_A_HDD13_TX_-")
	)
	(arc
		(start 5.524754 -358.152192)
		(mid 5.483313 -358.154017)
		(end 5.442204 -358.159558)
		(width 0.09525)
		(layer "F.Cu")
		(net "SAS2X28_A_HDD13_TX_-")
	)
	(arc
		(start 22.9108 -185.739532)
		(mid 23.079109 -186.585118)
		(end 23.558246 -187.301886)
		(width 0.09525)
		(layer "F.Cu")
		(net "SAS2X28_A_HDD13_TX_-")
	)
	(arc
		(start 9.397746 -354.156772)
		(mid 9.338408 -354.455084)
		(end 9.1694 -354.707952)
		(width 0.09525)
		(layer "F.Cu")
		(net "SAS2X28_A_HDD13_TX_-")
	)
	(arc
		(start 23.241 -143.120872)
		(mid 23.257152 -143.125021)
		(end 23.273766 -143.12646)
		(width 0.09525)
		(layer "F.Cu")
		(net "SAS2X28_A_HDD13_TX_-")
	)
	(arc
		(start 5.19557 -358.290876)
		(mid 4.96343 -358.445987)
		(end 4.689602 -358.500426)
		(width 0.09525)
		(layer "F.Cu")
		(net "SAS2X28_A_HDD13_TX_-")
	)
	(arc
		(start 23.65502 -155.78074)
		(mid 23.104237 -156.604855)
		(end 22.9108 -157.577028)
		(width 0.09525)
		(layer "F.Cu")
		(net "SAS2X28_A_HDD13_TX_-")
	)
	(arc
		(start 10.387076 -272.198084)
		(mid 9.654839 -273.29386)
		(end 9.397746 -274.586446)
		(width 0.09525)
		(layer "F.Cu")
		(net "SAS2X28_A_HDD13_TX_-")
	)
	(segment
		(start 35.026346 -138.544554)
		(end 35.026346 -137.2108)
		(width 0.111252)
		(layer "F.Cu")
		(net "HDD_PRSNT13")
	)
	(segment
		(start 36.448746 -135.7884)
		(end 36.448746 -132.997702)
		(width 0.111252)
		(layer "F.Cu")
		(net "HDD_PRSNT13")
	)
	(segment
		(start 35.026346 -137.2108)
		(end 36.448746 -135.7884)
		(width 0.111252)
		(layer "F.Cu")
		(net "HDD_PRSNT13")
	)
	(via
		(at 11.628628 -450.056758)
		(size 0.5588)
		(drill 0.3048)
		(layers "F.Cu" "B.Cu")
		(net "HDD_PRSNT13")
	)
	(via
		(at 35.026346 -138.544554)
		(size 0.5588)
		(drill 0.3048)
		(layers "F.Cu" "B.Cu")
		(net "HDD_PRSNT13")
	)
	(via
		(at 15.85087 -208.3562)
		(size 0.5588)
		(drill 0.3048)
		(layers "F.Cu" "B.Cu")
		(net "HDD_PRSNT13")
	)
	(via
		(at 15.1892 -206.4385)
		(size 0.7112)
		(drill 0.3556)
		(layers "F.Cu" "B.Cu")
		(net "HDD_PRSNT13")
	)
	(via
		(at 39.0906 -211.3788)
		(size 0.5588)
		(drill 0.3048)
		(layers "F.Cu" "B.Cu")
		(net "HDD_PRSNT13")
	)
	(via
		(at 16.128746 -214.1347)
		(size 0.5588)
		(drill 0.3048)
		(layers "F.Cu" "B.Cu")
		(net "HDD_PRSNT13")
	)
	(via
		(at 22.987 -211.201)
		(size 0.5588)
		(drill 0.3048)
		(layers "F.Cu" "B.Cu")
		(net "HDD_PRSNT13")
	)
	(segment
		(start 11.184128 -450.501258)
		(end 2.812542 -450.501258)
		(width 0.111252)
		(layer "B.Cu")
		(net "HDD_PRSNT13")
	)
	(segment
		(start 17.528032 -213.647274)
		(end 16.616172 -213.647274)
		(width 0.111252)
		(layer "B.Cu")
		(net "HDD_PRSNT13")
	)
	(segment
		(start 12.640564 -207.501236)
		(end 13.7033 -206.4385)
		(width 0.111252)
		(layer "B.Cu")
		(net "HDD_PRSNT13")
	)
	(segment
		(start 2.812542 -450.501258)
		(end 2.80924 -450.50456)
		(width 0.111252)
		(layer "B.Cu")
		(net "HDD_PRSNT13")
	)
	(segment
		(start 19.997674 -211.201)
		(end 19.927062 -211.248244)
		(width 0.111252)
		(layer "B.Cu")
		(net "HDD_PRSNT13")
	)
	(segment
		(start 2.80924 -207.504538)
		(end 2.812542 -207.501236)
		(width 0.111252)
		(layer "B.Cu")
		(net "HDD_PRSNT13")
	)
	(segment
		(start 15.857728 -208.349342)
		(end 15.85087 -208.3562)
		(width 0.111252)
		(layer "B.Cu")
		(net "HDD_PRSNT13")
	)
	(segment
		(start 22.987 -211.201)
		(end 19.997674 -211.201)
		(width 0.111252)
		(layer "B.Cu")
		(net "HDD_PRSNT13")
	)
	(segment
		(start 13.7033 -206.4385)
		(end 15.1892 -206.4385)
		(width 0.111252)
		(layer "B.Cu")
		(net "HDD_PRSNT13")
	)
	(segment
		(start 11.628628 -450.056758)
		(end 11.184128 -450.501258)
		(width 0.111252)
		(layer "B.Cu")
		(net "HDD_PRSNT13")
	)
	(segment
		(start 19.927062 -211.248244)
		(end 17.528032 -213.647274)
		(width 0.111252)
		(layer "B.Cu")
		(net "HDD_PRSNT13")
	)
	(segment
		(start 16.616172 -213.647274)
		(end 16.128746 -214.1347)
		(width 0.111252)
		(layer "B.Cu")
		(net "HDD_PRSNT13")
	)
	(segment
		(start 15.1892 -206.4385)
		(end 15.857728 -207.107028)
		(width 0.111252)
		(layer "B.Cu")
		(net "HDD_PRSNT13")
	)
	(segment
		(start 2.812542 -207.501236)
		(end 12.640564 -207.501236)
		(width 0.111252)
		(layer "B.Cu")
		(net "HDD_PRSNT13")
	)
	(segment
		(start 15.857728 -207.107028)
		(end 15.857728 -208.349342)
		(width 0.111252)
		(layer "B.Cu")
		(net "HDD_PRSNT13")
	)
	(segment
		(start 17.7038 -256.828544)
		(end 17.7038 -257.95478)
		(width 0.14605)
		(layer "In2.Cu")
		(net "HDD_PRSNT13")
	)
	(segment
		(start 16.290798 -212.029802)
		(end 15.169642 -210.908646)
		(width 0.14605)
		(layer "In2.Cu")
		(net "HDD_PRSNT13")
	)
	(segment
		(start 20.037298 -313.619896)
		(end 17.46758 -316.189614)
		(width 0.14605)
		(layer "In2.Cu")
		(net "HDD_PRSNT13")
	)
	(segment
		(start 17.46758 -349.54718)
		(end 21.155152 -353.234752)
		(width 0.14605)
		(layer "In2.Cu")
		(net "HDD_PRSNT13")
	)
	(segment
		(start 16.134588 -214.140542)
		(end 16.134588 -250.792742)
		(width 0.14605)
		(layer "In2.Cu")
		(net "HDD_PRSNT13")
	)
	(segment
		(start 17.46758 -316.189614)
		(end 17.46758 -349.54718)
		(width 0.14605)
		(layer "In2.Cu")
		(net "HDD_PRSNT13")
	)
	(segment
		(start 16.316198 -397.400526)
		(end 16.223996 -397.492728)
		(width 0.14605)
		(layer "In2.Cu")
		(net "HDD_PRSNT13")
	)
	(segment
		(start 17.35455 -364.390432)
		(end 17.35455 -376.663204)
		(width 0.14605)
		(layer "In2.Cu")
		(net "HDD_PRSNT13")
	)
	(segment
		(start 11.560048 -447.200274)
		(end 11.560048 -449.988178)
		(width 0.14605)
		(layer "In2.Cu")
		(net "HDD_PRSNT13")
	)
	(segment
		(start 16.128746 -214.1347)
		(end 16.134588 -214.140542)
		(width 0.14605)
		(layer "In2.Cu")
		(net "HDD_PRSNT13")
	)
	(segment
		(start 20.037298 -303.57191)
		(end 20.037298 -313.619896)
		(width 0.14605)
		(layer "In2.Cu")
		(net "HDD_PRSNT13")
	)
	(segment
		(start 16.316198 -395.563852)
		(end 16.316198 -397.400526)
		(width 0.14605)
		(layer "In2.Cu")
		(net "HDD_PRSNT13")
	)
	(segment
		(start 15.85087 -208.659984)
		(end 15.85087 -208.3562)
		(width 0.14605)
		(layer "In2.Cu")
		(net "HDD_PRSNT13")
	)
	(segment
		(start 17.35455 -376.663204)
		(end 17.060672 -376.957082)
		(width 0.14605)
		(layer "In2.Cu")
		(net "HDD_PRSNT13")
	)
	(segment
		(start 15.99184 -442.768482)
		(end 11.560048 -447.200274)
		(width 0.14605)
		(layer "In2.Cu")
		(net "HDD_PRSNT13")
	)
	(segment
		(start 18.979896 -302.514508)
		(end 20.037298 -303.57191)
		(width 0.14605)
		(layer "In2.Cu")
		(net "HDD_PRSNT13")
	)
	(segment
		(start 16.134588 -250.792742)
		(end 19.008344 -253.666752)
		(width 0.14605)
		(layer "In2.Cu")
		(net "HDD_PRSNT13")
	)
	(segment
		(start 30.7848 -142.7861)
		(end 30.7848 -203.962)
		(width 0.14605)
		(layer "In2.Cu")
		(net "HDD_PRSNT13")
	)
	(segment
		(start 38.227 -211.4042)
		(end 39.0652 -211.4042)
		(width 0.14605)
		(layer "In2.Cu")
		(net "HDD_PRSNT13")
	)
	(segment
		(start 17.060672 -376.957082)
		(end 17.060672 -394.819378)
		(width 0.14605)
		(layer "In2.Cu")
		(net "HDD_PRSNT13")
	)
	(segment
		(start 21.155152 -353.234752)
		(end 21.155152 -357.053642)
		(width 0.14605)
		(layer "In2.Cu")
		(net "HDD_PRSNT13")
	)
	(segment
		(start 11.560048 -449.988178)
		(end 11.628628 -450.056758)
		(width 0.14605)
		(layer "In2.Cu")
		(net "HDD_PRSNT13")
	)
	(segment
		(start 17.224248 -364.26013)
		(end 17.35455 -364.390432)
		(width 0.14605)
		(layer "In2.Cu")
		(net "HDD_PRSNT13")
	)
	(segment
		(start 18.979896 -302.514254)
		(end 18.979896 -302.514508)
		(width 0.14605)
		(layer "In2.Cu")
		(net "HDD_PRSNT13")
	)
	(segment
		(start 39.0652 -211.4042)
		(end 39.0906 -211.3788)
		(width 0.14605)
		(layer "In2.Cu")
		(net "HDD_PRSNT13")
	)
	(segment
		(start 18.938748 -302.473106)
		(end 18.979896 -302.514254)
		(width 0.14605)
		(layer "In2.Cu")
		(net "HDD_PRSNT13")
	)
	(segment
		(start 19.008344 -253.666752)
		(end 19.008344 -255.524)
		(width 0.14605)
		(layer "In2.Cu")
		(net "HDD_PRSNT13")
	)
	(segment
		(start 21.155152 -357.053642)
		(end 17.224248 -360.984546)
		(width 0.14605)
		(layer "In2.Cu")
		(net "HDD_PRSNT13")
	)
	(segment
		(start 16.223996 -415.699448)
		(end 15.99184 -415.931604)
		(width 0.14605)
		(layer "In2.Cu")
		(net "HDD_PRSNT13")
	)
	(segment
		(start 17.060672 -394.819378)
		(end 16.316198 -395.563852)
		(width 0.14605)
		(layer "In2.Cu")
		(net "HDD_PRSNT13")
	)
	(segment
		(start 15.99184 -415.931604)
		(end 15.99184 -442.768482)
		(width 0.14605)
		(layer "In2.Cu")
		(net "HDD_PRSNT13")
	)
	(segment
		(start 16.128746 -214.01151)
		(end 16.290798 -213.849458)
		(width 0.14605)
		(layer "In2.Cu")
		(net "HDD_PRSNT13")
	)
	(segment
		(start 15.169642 -210.908646)
		(end 15.169642 -209.341212)
		(width 0.14605)
		(layer "In2.Cu")
		(net "HDD_PRSNT13")
	)
	(segment
		(start 15.169642 -209.341212)
		(end 15.85087 -208.659984)
		(width 0.14605)
		(layer "In2.Cu")
		(net "HDD_PRSNT13")
	)
	(segment
		(start 30.7848 -203.962)
		(end 38.227 -211.4042)
		(width 0.14605)
		(layer "In2.Cu")
		(net "HDD_PRSNT13")
	)
	(segment
		(start 16.290798 -213.849458)
		(end 16.290798 -212.029802)
		(width 0.14605)
		(layer "In2.Cu")
		(net "HDD_PRSNT13")
	)
	(segment
		(start 17.224248 -360.984546)
		(end 17.224248 -364.26013)
		(width 0.14605)
		(layer "In2.Cu")
		(net "HDD_PRSNT13")
	)
	(segment
		(start 17.7038 -257.95478)
		(end 18.938748 -259.189728)
		(width 0.14605)
		(layer "In2.Cu")
		(net "HDD_PRSNT13")
	)
	(segment
		(start 16.223996 -397.492728)
		(end 16.223996 -415.699448)
		(width 0.14605)
		(layer "In2.Cu")
		(net "HDD_PRSNT13")
	)
	(segment
		(start 35.026346 -138.544554)
		(end 30.7848 -142.7861)
		(width 0.14605)
		(layer "In2.Cu")
		(net "HDD_PRSNT13")
	)
	(segment
		(start 16.128746 -214.1347)
		(end 16.128746 -214.01151)
		(width 0.14605)
		(layer "In2.Cu")
		(net "HDD_PRSNT13")
	)
	(segment
		(start 18.938748 -259.189728)
		(end 18.938748 -302.473106)
		(width 0.14605)
		(layer "In2.Cu")
		(net "HDD_PRSNT13")
	)
	(segment
		(start 19.008344 -255.524)
		(end 17.7038 -256.828544)
		(width 0.14605)
		(layer "In2.Cu")
		(net "HDD_PRSNT13")
	)
	(segment
		(start 38.014148 -212.455252)
		(end 39.0906 -211.3788)
		(width 0.14605)
		(layer "In5.Cu")
		(net "HDD_PRSNT13")
	)
	(segment
		(start 22.987 -211.201)
		(end 24.241252 -212.455252)
		(width 0.14605)
		(layer "In5.Cu")
		(net "HDD_PRSNT13")
	)
	(segment
		(start 24.241252 -212.455252)
		(end 38.014148 -212.455252)
		(width 0.14605)
		(layer "In5.Cu")
		(net "HDD_PRSNT13")
	)
	(segment
		(start 22.34819 -178.445668)
		(end 22.34819 -178.731418)
		(width 0.09525)
		(layer "F.Cu")
		(net "SAS2X28_A_HDD13_TX_+")
	)
	(segment
		(start 8.840216 -354.57003)
		(end 6.99897 -356.411022)
		(width 0.09525)
		(layer "F.Cu")
		(net "SAS2X28_A_HDD13_TX_+")
	)
	(segment
		(start 21.75002 -143.929862)
		(end 23.049992 -143.929862)
		(width 0.09525)
		(layer "F.Cu")
		(net "SAS2X28_A_HDD13_TX_+")
	)
	(segment
		(start 23.172166 -143.807688)
		(end 23.172166 -143.55826)
		(width 0.09525)
		(layer "F.Cu")
		(net "SAS2X28_A_HDD13_TX_+")
	)
	(segment
		(start 11.857228 -270.260572)
		(end 10.153396 -271.964404)
		(width 0.09525)
		(layer "F.Cu")
		(net "SAS2X28_A_HDD13_TX_+")
	)
	(segment
		(start 22.5806 -157.439868)
		(end 22.5806 -167.788082)
		(width 0.09525)
		(layer "F.Cu")
		(net "SAS2X28_A_HDD13_TX_+")
	)
	(segment
		(start 22.5806 -183.89981)
		(end 22.5806 -185.739532)
		(width 0.09525)
		(layer "F.Cu")
		(net "SAS2X28_A_HDD13_TX_+")
	)
	(segment
		(start 22.5806 -177.695098)
		(end 22.5806 -177.980848)
		(width 0.09525)
		(layer "F.Cu")
		(net "SAS2X28_A_HDD13_TX_+")
	)
	(segment
		(start 22.34819 -183.14924)
		(end 22.34819 -183.43499)
		(width 0.09525)
		(layer "F.Cu")
		(net "SAS2X28_A_HDD13_TX_+")
	)
	(segment
		(start 9.067546 -274.5867)
		(end 9.067546 -354.156518)
		(width 0.09525)
		(layer "F.Cu")
		(net "SAS2X28_A_HDD13_TX_+")
	)
	(segment
		(start 22.5806 -179.196238)
		(end 22.5806 -179.481988)
		(width 0.09525)
		(layer "F.Cu")
		(net "SAS2X28_A_HDD13_TX_+")
	)
	(segment
		(start 28.770834 -253.346712)
		(end 11.857228 -270.260572)
		(width 0.09525)
		(layer "F.Cu")
		(net "SAS2X28_A_HDD13_TX_+")
	)
	(segment
		(start 8.93572 -354.474272)
		(end 8.840216 -354.569776)
		(width 0.09525)
		(layer "F.Cu")
		(net "SAS2X28_A_HDD13_TX_+")
	)
	(segment
		(start 8.840216 -354.569776)
		(end 8.840216 -354.57003)
		(width 0.09525)
		(layer "F.Cu")
		(net "SAS2X28_A_HDD13_TX_+")
	)
	(segment
		(start 22.5806 -170.504612)
		(end 22.5806 -170.790362)
		(width 0.09525)
		(layer "F.Cu")
		(net "SAS2X28_A_HDD13_TX_+")
	)
	(segment
		(start 22.5806 -180.697378)
		(end 22.5806 -182.68442)
		(width 0.09525)
		(layer "F.Cu")
		(net "SAS2X28_A_HDD13_TX_+")
	)
	(segment
		(start 3.19405 -357.500174)
		(end 3.192526 -357.49865)
		(width 0.09525)
		(layer "F.Cu")
		(net "SAS2X28_A_HDD13_TX_+")
	)
	(segment
		(start 23.273766 -143.45666)
		(end 24.516588 -143.45666)
		(width 0.09525)
		(layer "F.Cu")
		(net "SAS2X28_A_HDD13_TX_+")
	)
	(segment
		(start 22.34819 -171.255182)
		(end 22.34819 -171.540932)
		(width 0.09525)
		(layer "F.Cu")
		(net "SAS2X28_A_HDD13_TX_+")
	)
	(segment
		(start 5.01142 -357.500174)
		(end 3.19405 -357.500174)
		(width 0.09525)
		(layer "F.Cu")
		(net "SAS2X28_A_HDD13_TX_+")
	)
	(segment
		(start 29.5148 -194.777868)
		(end 29.5148 -251.550678)
		(width 0.09525)
		(layer "F.Cu")
		(net "SAS2X28_A_HDD13_TX_+")
	)
	(segment
		(start 6.730746 -356.8827)
		(end 6.730746 -357.095552)
		(width 0.09525)
		(layer "F.Cu")
		(net "SAS2X28_A_HDD13_TX_+")
	)
	(segment
		(start 24.1808 -154.7876)
		(end 23.324566 -155.64358)
		(width 0.09525)
		(layer "F.Cu")
		(net "SAS2X28_A_HDD13_TX_+")
	)
	(segment
		(start 24.7269 -154.2415)
		(end 24.1808 -154.7876)
		(width 0.09525)
		(layer "F.Cu")
		(net "SAS2X28_A_HDD13_TX_+")
	)
	(segment
		(start 22.34819 -169.754042)
		(end 22.34819 -170.039792)
		(width 0.09525)
		(layer "F.Cu")
		(net "SAS2X28_A_HDD13_TX_+")
	)
	(segment
		(start 23.324566 -187.535566)
		(end 28.770834 -192.981834)
		(width 0.09525)
		(layer "F.Cu")
		(net "SAS2X28_A_HDD13_TX_+")
	)
	(segment
		(start 22.34819 -179.946808)
		(end 22.34819 -180.232558)
		(width 0.09525)
		(layer "F.Cu")
		(net "SAS2X28_A_HDD13_TX_+")
	)
	(segment
		(start 22.34819 -176.944528)
		(end 22.34819 -177.230278)
		(width 0.09525)
		(layer "F.Cu")
		(net "SAS2X28_A_HDD13_TX_+")
	)
	(segment
		(start 6.149594 -357.6955)
		(end 5.801614 -357.6955)
		(width 0.09525)
		(layer "F.Cu")
		(net "SAS2X28_A_HDD13_TX_+")
	)
	(segment
		(start 5.371846 -357.771192)
		(end 5.207 -357.6066)
		(width 0.09525)
		(layer "F.Cu")
		(net "SAS2X28_A_HDD13_TX_+")
	)
	(segment
		(start 22.34819 -168.252902)
		(end 22.34819 -168.538652)
		(width 0.09525)
		(layer "F.Cu")
		(net "SAS2X28_A_HDD13_TX_+")
	)
	(segment
		(start 6.99897 -356.411022)
		(end 6.874764 -356.535482)
		(width 0.09525)
		(layer "F.Cu")
		(net "SAS2X28_A_HDD13_TX_+")
	)
	(segment
		(start 25.272746 -144.694148)
		(end 25.272746 -152.923494)
		(width 0.09525)
		(layer "F.Cu")
		(net "SAS2X28_A_HDD13_TX_+")
	)
	(segment
		(start 22.5806 -169.003472)
		(end 22.5806 -169.289222)
		(width 0.09525)
		(layer "F.Cu")
		(net "SAS2X28_A_HDD13_TX_+")
	)
	(segment
		(start 5.207 -357.6066)
		(end 5.163566 -357.563166)
		(width 0.09525)
		(layer "F.Cu")
		(net "SAS2X28_A_HDD13_TX_+")
	)
	(segment
		(start 22.5806 -172.005752)
		(end 22.5806 -176.479708)
		(width 0.09525)
		(layer "F.Cu")
		(net "SAS2X28_A_HDD13_TX_+")
	)
	(arc
		(start 22.464268 -178.963828)
		(mid 22.550667 -179.065902)
		(end 22.5806 -179.196238)
		(width 0.09525)
		(layer "F.Cu")
		(net "SAS2X28_A_HDD13_TX_+")
	)
	(arc
		(start 5.653278 -357.756968)
		(mid 5.580808 -357.805484)
		(end 5.49529 -357.8225)
		(width 0.09525)
		(layer "F.Cu")
		(net "SAS2X28_A_HDD13_TX_+")
	)
	(arc
		(start 6.874764 -356.535482)
		(mid 6.768237 -356.694772)
		(end 6.730746 -356.8827)
		(width 0.09525)
		(layer "F.Cu")
		(net "SAS2X28_A_HDD13_TX_+")
	)
	(arc
		(start 23.172166 -143.55826)
		(mid 23.190901 -143.499392)
		(end 23.240238 -143.462248)
		(width 0.09525)
		(layer "F.Cu")
		(net "SAS2X28_A_HDD13_TX_+")
	)
	(arc
		(start 10.153396 -271.964404)
		(mid 9.349692 -273.167554)
		(end 9.067546 -274.5867)
		(width 0.09525)
		(layer "F.Cu")
		(net "SAS2X28_A_HDD13_TX_+")
	)
	(arc
		(start 22.464268 -177.462688)
		(mid 22.550667 -177.564762)
		(end 22.5806 -177.695098)
		(width 0.09525)
		(layer "F.Cu")
		(net "SAS2X28_A_HDD13_TX_+")
	)
	(arc
		(start 24.516588 -143.45666)
		(mid 24.675679 -143.488341)
		(end 24.810466 -143.57858)
		(width 0.09525)
		(layer "F.Cu")
		(net "SAS2X28_A_HDD13_TX_+")
	)
	(arc
		(start 22.464268 -168.771062)
		(mid 22.550667 -168.873136)
		(end 22.5806 -169.003472)
		(width 0.09525)
		(layer "F.Cu")
		(net "SAS2X28_A_HDD13_TX_+")
	)
	(arc
		(start 22.5806 -169.289222)
		(mid 22.550664 -169.419557)
		(end 22.464268 -169.521632)
		(width 0.09525)
		(layer "F.Cu")
		(net "SAS2X28_A_HDD13_TX_+")
	)
	(arc
		(start 24.810466 -143.57858)
		(mid 25.152565 -144.090378)
		(end 25.272746 -144.694148)
		(width 0.09525)
		(layer "F.Cu")
		(net "SAS2X28_A_HDD13_TX_+")
	)
	(arc
		(start 22.464268 -168.020492)
		(mid 22.378037 -168.122609)
		(end 22.34819 -168.252902)
		(width 0.09525)
		(layer "F.Cu")
		(net "SAS2X28_A_HDD13_TX_+")
	)
	(arc
		(start 22.5806 -177.980848)
		(mid 22.550664 -178.111183)
		(end 22.464268 -178.213258)
		(width 0.09525)
		(layer "F.Cu")
		(net "SAS2X28_A_HDD13_TX_+")
	)
	(arc
		(start 23.240238 -143.462248)
		(mid 23.249528 -143.459517)
		(end 23.259034 -143.457676)
		(width 0.09525)
		(layer "F.Cu")
		(net "SAS2X28_A_HDD13_TX_+")
	)
	(arc
		(start 25.272746 -152.923494)
		(mid 25.130884 -153.636774)
		(end 24.7269 -154.2415)
		(width 0.09525)
		(layer "F.Cu")
		(net "SAS2X28_A_HDD13_TX_+")
	)
	(arc
		(start 23.136352 -143.894048)
		(mid 23.162881 -143.85444)
		(end 23.172166 -143.807688)
		(width 0.09525)
		(layer "F.Cu")
		(net "SAS2X28_A_HDD13_TX_+")
	)
	(arc
		(start 6.34492 -357.660702)
		(mid 6.24879 -357.686711)
		(end 6.149594 -357.6955)
		(width 0.09525)
		(layer "F.Cu")
		(net "SAS2X28_A_HDD13_TX_+")
	)
	(arc
		(start 22.5806 -182.68442)
		(mid 22.550664 -182.814755)
		(end 22.464268 -182.91683)
		(width 0.09525)
		(layer "F.Cu")
		(net "SAS2X28_A_HDD13_TX_+")
	)
	(arc
		(start 23.259034 -143.457676)
		(mid 23.266382 -143.456908)
		(end 23.273766 -143.45666)
		(width 0.09525)
		(layer "F.Cu")
		(net "SAS2X28_A_HDD13_TX_+")
	)
	(arc
		(start 22.34819 -180.232558)
		(mid 22.377987 -180.362876)
		(end 22.464268 -180.464968)
		(width 0.09525)
		(layer "F.Cu")
		(net "SAS2X28_A_HDD13_TX_+")
	)
	(arc
		(start 22.34819 -168.538652)
		(mid 22.377987 -168.66897)
		(end 22.464268 -168.771062)
		(width 0.09525)
		(layer "F.Cu")
		(net "SAS2X28_A_HDD13_TX_+")
	)
	(arc
		(start 22.464268 -178.213258)
		(mid 22.378037 -178.315375)
		(end 22.34819 -178.445668)
		(width 0.09525)
		(layer "F.Cu")
		(net "SAS2X28_A_HDD13_TX_+")
	)
	(arc
		(start 5.801614 -357.6955)
		(mid 5.721325 -357.71147)
		(end 5.653278 -357.756968)
		(width 0.09525)
		(layer "F.Cu")
		(net "SAS2X28_A_HDD13_TX_+")
	)
	(arc
		(start 22.34819 -178.731418)
		(mid 22.377987 -178.861736)
		(end 22.464268 -178.963828)
		(width 0.09525)
		(layer "F.Cu")
		(net "SAS2X28_A_HDD13_TX_+")
	)
	(arc
		(start 22.34819 -183.43499)
		(mid 22.377987 -183.565308)
		(end 22.464268 -183.6674)
		(width 0.09525)
		(layer "F.Cu")
		(net "SAS2X28_A_HDD13_TX_+")
	)
	(arc
		(start 9.067546 -354.156518)
		(mid 9.033226 -354.328497)
		(end 8.93572 -354.474272)
		(width 0.09525)
		(layer "F.Cu")
		(net "SAS2X28_A_HDD13_TX_+")
	)
	(arc
		(start 22.464268 -171.022772)
		(mid 22.378037 -171.124889)
		(end 22.34819 -171.255182)
		(width 0.09525)
		(layer "F.Cu")
		(net "SAS2X28_A_HDD13_TX_+")
	)
	(arc
		(start 22.5806 -167.788082)
		(mid 22.550664 -167.918417)
		(end 22.464268 -168.020492)
		(width 0.09525)
		(layer "F.Cu")
		(net "SAS2X28_A_HDD13_TX_+")
	)
	(arc
		(start 22.5806 -185.739532)
		(mid 22.773946 -186.711548)
		(end 23.324566 -187.535566)
		(width 0.09525)
		(layer "F.Cu")
		(net "SAS2X28_A_HDD13_TX_+")
	)
	(arc
		(start 6.551168 -357.52913)
		(mid 6.455223 -357.606174)
		(end 6.34492 -357.660702)
		(width 0.09525)
		(layer "F.Cu")
		(net "SAS2X28_A_HDD13_TX_+")
	)
	(arc
		(start 22.464268 -171.773342)
		(mid 22.550667 -171.875416)
		(end 22.5806 -172.005752)
		(width 0.09525)
		(layer "F.Cu")
		(net "SAS2X28_A_HDD13_TX_+")
	)
	(arc
		(start 22.5806 -176.479708)
		(mid 22.550664 -176.610043)
		(end 22.464268 -176.712118)
		(width 0.09525)
		(layer "F.Cu")
		(net "SAS2X28_A_HDD13_TX_+")
	)
	(arc
		(start 22.34819 -177.230278)
		(mid 22.377987 -177.360596)
		(end 22.464268 -177.462688)
		(width 0.09525)
		(layer "F.Cu")
		(net "SAS2X28_A_HDD13_TX_+")
	)
	(arc
		(start 22.464268 -169.521632)
		(mid 22.378037 -169.623749)
		(end 22.34819 -169.754042)
		(width 0.09525)
		(layer "F.Cu")
		(net "SAS2X28_A_HDD13_TX_+")
	)
	(arc
		(start 22.464268 -183.6674)
		(mid 22.550667 -183.769474)
		(end 22.5806 -183.89981)
		(width 0.09525)
		(layer "F.Cu")
		(net "SAS2X28_A_HDD13_TX_+")
	)
	(arc
		(start 23.324566 -155.64358)
		(mid 22.77392 -156.467725)
		(end 22.5806 -157.439868)
		(width 0.09525)
		(layer "F.Cu")
		(net "SAS2X28_A_HDD13_TX_+")
	)
	(arc
		(start 22.34819 -171.540932)
		(mid 22.377987 -171.67125)
		(end 22.464268 -171.773342)
		(width 0.09525)
		(layer "F.Cu")
		(net "SAS2X28_A_HDD13_TX_+")
	)
	(arc
		(start 22.34819 -170.039792)
		(mid 22.377987 -170.17011)
		(end 22.464268 -170.272202)
		(width 0.09525)
		(layer "F.Cu")
		(net "SAS2X28_A_HDD13_TX_+")
	)
	(arc
		(start 5.163566 -357.563166)
		(mid 5.093761 -357.516524)
		(end 5.01142 -357.500174)
		(width 0.09525)
		(layer "F.Cu")
		(net "SAS2X28_A_HDD13_TX_+")
	)
	(arc
		(start 5.49529 -357.8225)
		(mid 5.428469 -357.809115)
		(end 5.371846 -357.771192)
		(width 0.09525)
		(layer "F.Cu")
		(net "SAS2X28_A_HDD13_TX_+")
	)
	(arc
		(start 22.464268 -182.91683)
		(mid 22.378037 -183.018947)
		(end 22.34819 -183.14924)
		(width 0.09525)
		(layer "F.Cu")
		(net "SAS2X28_A_HDD13_TX_+")
	)
	(arc
		(start 23.049992 -143.929862)
		(mid 23.096732 -143.920547)
		(end 23.136352 -143.894048)
		(width 0.09525)
		(layer "F.Cu")
		(net "SAS2X28_A_HDD13_TX_+")
	)
	(arc
		(start 6.730746 -357.095552)
		(mid 6.684072 -357.330197)
		(end 6.551168 -357.52913)
		(width 0.09525)
		(layer "F.Cu")
		(net "SAS2X28_A_HDD13_TX_+")
	)
	(arc
		(start 22.5806 -170.790362)
		(mid 22.550664 -170.920697)
		(end 22.464268 -171.022772)
		(width 0.09525)
		(layer "F.Cu")
		(net "SAS2X28_A_HDD13_TX_+")
	)
	(arc
		(start 22.464268 -180.464968)
		(mid 22.550667 -180.567042)
		(end 22.5806 -180.697378)
		(width 0.09525)
		(layer "F.Cu")
		(net "SAS2X28_A_HDD13_TX_+")
	)
	(arc
		(start 22.464268 -179.714398)
		(mid 22.378037 -179.816515)
		(end 22.34819 -179.946808)
		(width 0.09525)
		(layer "F.Cu")
		(net "SAS2X28_A_HDD13_TX_+")
	)
	(arc
		(start 28.770834 -192.981834)
		(mid 29.321432 -193.805861)
		(end 29.5148 -194.777868)
		(width 0.09525)
		(layer "F.Cu")
		(net "SAS2X28_A_HDD13_TX_+")
	)
	(arc
		(start 22.464268 -170.272202)
		(mid 22.550667 -170.374276)
		(end 22.5806 -170.504612)
		(width 0.09525)
		(layer "F.Cu")
		(net "SAS2X28_A_HDD13_TX_+")
	)
	(arc
		(start 29.5148 -251.550678)
		(mid 29.321454 -252.522694)
		(end 28.770834 -253.346712)
		(width 0.09525)
		(layer "F.Cu")
		(net "SAS2X28_A_HDD13_TX_+")
	)
	(arc
		(start 22.464268 -176.712118)
		(mid 22.378037 -176.814235)
		(end 22.34819 -176.944528)
		(width 0.09525)
		(layer "F.Cu")
		(net "SAS2X28_A_HDD13_TX_+")
	)
	(arc
		(start 22.5806 -179.481988)
		(mid 22.550664 -179.612323)
		(end 22.464268 -179.714398)
		(width 0.09525)
		(layer "F.Cu")
		(net "SAS2X28_A_HDD13_TX_+")
	)
	(segment
		(start 10.89025 -136.160764)
		(end 10.6045 -136.160764)
		(width 0.09525)
		(layer "F.Cu")
		(net "SAS2X28_B_HDD13_TX_-")
	)
	(segment
		(start 15.239746 -136.5377)
		(end 15.239746 -136.339834)
		(width 0.09525)
		(layer "F.Cu")
		(net "SAS2X28_B_HDD13_TX_-")
	)
	(segment
		(start 20.488148 -135.210042)
		(end 20.49145 -135.20674)
		(width 0.09525)
		(layer "F.Cu")
		(net "SAS2X28_B_HDD13_TX_-")
	)
	(segment
		(start 4.861814 -136.500362)
		(end 4.86029 -136.498838)
		(width 0.09525)
		(layer "F.Cu")
		(net "SAS2X28_B_HDD13_TX_-")
	)
	(segment
		(start 10.13968 -136.393174)
		(end 9.85393 -136.393174)
		(width 0.09525)
		(layer "F.Cu")
		(net "SAS2X28_B_HDD13_TX_-")
	)
	(segment
		(start 21.006562 -135.4201)
		(end 21.342604 -135.4201)
		(width 0.09525)
		(layer "F.Cu")
		(net "SAS2X28_B_HDD13_TX_-")
	)
	(segment
		(start 19.600164 -135.210042)
		(end 20.488148 -135.210042)
		(width 0.09525)
		(layer "F.Cu")
		(net "SAS2X28_B_HDD13_TX_-")
	)
	(segment
		(start 15.011908 -136.148064)
		(end 15.011908 -136.14781)
		(width 0.09525)
		(layer "F.Cu")
		(net "SAS2X28_B_HDD13_TX_-")
	)
	(segment
		(start 8.63854 -136.393174)
		(end 8.35279 -136.393174)
		(width 0.09525)
		(layer "F.Cu")
		(net "SAS2X28_B_HDD13_TX_-")
	)
	(segment
		(start 13.14196 -136.393174)
		(end 12.85621 -136.393174)
		(width 0.09525)
		(layer "F.Cu")
		(net "SAS2X28_B_HDD13_TX_-")
	)
	(segment
		(start 4.86029 -136.498838)
		(end 3.192526 -136.498838)
		(width 0.09525)
		(layer "F.Cu")
		(net "SAS2X28_B_HDD13_TX_-")
	)
	(segment
		(start 11.64082 -136.393174)
		(end 11.35507 -136.393174)
		(width 0.09525)
		(layer "F.Cu")
		(net "SAS2X28_B_HDD13_TX_-")
	)
	(segment
		(start 14.863318 -136.160764)
		(end 13.60678 -136.160764)
		(width 0.09525)
		(layer "F.Cu")
		(net "SAS2X28_B_HDD13_TX_-")
	)
	(segment
		(start 7.88797 -136.160764)
		(end 5.681726 -136.160764)
		(width 0.09525)
		(layer "F.Cu")
		(net "SAS2X28_B_HDD13_TX_-")
	)
	(segment
		(start 9.38911 -136.160764)
		(end 9.10336 -136.160764)
		(width 0.09525)
		(layer "F.Cu")
		(net "SAS2X28_B_HDD13_TX_-")
	)
	(segment
		(start 12.39139 -136.160764)
		(end 12.10564 -136.160764)
		(width 0.09525)
		(layer "F.Cu")
		(net "SAS2X28_B_HDD13_TX_-")
	)
	(via
		(at 15.239746 -136.5377)
		(size 0.5588)
		(drill 0.3048)
		(layers "F.Cu" "B.Cu")
		(net "SAS2X28_B_HDD13_TX_-")
	)
	(via
		(at 21.894546 -135.1915)
		(size 0.5588)
		(drill 0.3048)
		(layers "F.Cu" "B.Cu")
		(net "SAS2X28_B_HDD13_TX_-")
	)
	(arc
		(start 20.49145 -135.20674)
		(mid 20.633462 -135.234988)
		(end 20.753832 -135.315452)
		(width 0.09525)
		(layer "F.Cu")
		(net "SAS2X28_B_HDD13_TX_-")
	)
	(arc
		(start 8.12038 -136.277096)
		(mid 8.018306 -136.190697)
		(end 7.88797 -136.160764)
		(width 0.09525)
		(layer "F.Cu")
		(net "SAS2X28_B_HDD13_TX_-")
	)
	(arc
		(start 10.37209 -136.277096)
		(mid 10.269973 -136.363327)
		(end 10.13968 -136.393174)
		(width 0.09525)
		(layer "F.Cu")
		(net "SAS2X28_B_HDD13_TX_-")
	)
	(arc
		(start 20.753832 -135.315452)
		(mid 20.869786 -135.39293)
		(end 21.006562 -135.4201)
		(width 0.09525)
		(layer "F.Cu")
		(net "SAS2X28_B_HDD13_TX_-")
	)
	(arc
		(start 8.87095 -136.277096)
		(mid 8.768833 -136.363327)
		(end 8.63854 -136.393174)
		(width 0.09525)
		(layer "F.Cu")
		(net "SAS2X28_B_HDD13_TX_-")
	)
	(arc
		(start 5.45719 -136.253728)
		(mid 5.184029 -136.436248)
		(end 4.861814 -136.500362)
		(width 0.09525)
		(layer "F.Cu")
		(net "SAS2X28_B_HDD13_TX_-")
	)
	(arc
		(start 9.10336 -136.160764)
		(mid 8.973025 -136.1907)
		(end 8.87095 -136.277096)
		(width 0.09525)
		(layer "F.Cu")
		(net "SAS2X28_B_HDD13_TX_-")
	)
	(arc
		(start 10.6045 -136.160764)
		(mid 10.474165 -136.1907)
		(end 10.37209 -136.277096)
		(width 0.09525)
		(layer "F.Cu")
		(net "SAS2X28_B_HDD13_TX_-")
	)
	(arc
		(start 8.35279 -136.393174)
		(mid 8.222472 -136.363377)
		(end 8.12038 -136.277096)
		(width 0.09525)
		(layer "F.Cu")
		(net "SAS2X28_B_HDD13_TX_-")
	)
	(arc
		(start 13.37437 -136.277096)
		(mid 13.272253 -136.363327)
		(end 13.14196 -136.393174)
		(width 0.09525)
		(layer "F.Cu")
		(net "SAS2X28_B_HDD13_TX_-")
	)
	(arc
		(start 12.10564 -136.160764)
		(mid 11.975305 -136.1907)
		(end 11.87323 -136.277096)
		(width 0.09525)
		(layer "F.Cu")
		(net "SAS2X28_B_HDD13_TX_-")
	)
	(arc
		(start 11.12266 -136.277096)
		(mid 11.020586 -136.190697)
		(end 10.89025 -136.160764)
		(width 0.09525)
		(layer "F.Cu")
		(net "SAS2X28_B_HDD13_TX_-")
	)
	(arc
		(start 15.239746 -136.339834)
		(mid 15.170449 -136.19096)
		(end 15.011908 -136.148064)
		(width 0.09525)
		(layer "F.Cu")
		(net "SAS2X28_B_HDD13_TX_-")
	)
	(arc
		(start 13.60678 -136.160764)
		(mid 13.476445 -136.1907)
		(end 13.37437 -136.277096)
		(width 0.09525)
		(layer "F.Cu")
		(net "SAS2X28_B_HDD13_TX_-")
	)
	(arc
		(start 9.85393 -136.393174)
		(mid 9.723612 -136.363377)
		(end 9.62152 -136.277096)
		(width 0.09525)
		(layer "F.Cu")
		(net "SAS2X28_B_HDD13_TX_-")
	)
	(arc
		(start 15.011908 -136.14781)
		(mid 14.937893 -136.157499)
		(end 14.863318 -136.160764)
		(width 0.09525)
		(layer "F.Cu")
		(net "SAS2X28_B_HDD13_TX_-")
	)
	(arc
		(start 5.681726 -136.160764)
		(mid 5.560224 -136.184932)
		(end 5.45719 -136.253728)
		(width 0.09525)
		(layer "F.Cu")
		(net "SAS2X28_B_HDD13_TX_-")
	)
	(arc
		(start 11.87323 -136.277096)
		(mid 11.771113 -136.363327)
		(end 11.64082 -136.393174)
		(width 0.09525)
		(layer "F.Cu")
		(net "SAS2X28_B_HDD13_TX_-")
	)
	(arc
		(start 12.6238 -136.277096)
		(mid 12.521726 -136.190697)
		(end 12.39139 -136.160764)
		(width 0.09525)
		(layer "F.Cu")
		(net "SAS2X28_B_HDD13_TX_-")
	)
	(arc
		(start 21.342604 -135.4201)
		(mid 21.641304 -135.360685)
		(end 21.894546 -135.1915)
		(width 0.09525)
		(layer "F.Cu")
		(net "SAS2X28_B_HDD13_TX_-")
	)
	(arc
		(start 9.62152 -136.277096)
		(mid 9.519446 -136.190697)
		(end 9.38911 -136.160764)
		(width 0.09525)
		(layer "F.Cu")
		(net "SAS2X28_B_HDD13_TX_-")
	)
	(arc
		(start 11.35507 -136.393174)
		(mid 11.224752 -136.363377)
		(end 11.12266 -136.277096)
		(width 0.09525)
		(layer "F.Cu")
		(net "SAS2X28_B_HDD13_TX_-")
	)
	(arc
		(start 12.85621 -136.393174)
		(mid 12.725892 -136.363377)
		(end 12.6238 -136.277096)
		(width 0.09525)
		(layer "F.Cu")
		(net "SAS2X28_B_HDD13_TX_-")
	)
	(segment
		(start 22.5552 -133.870446)
		(end 22.8346 -134.149846)
		(width 0.1143)
		(layer "In5.Cu")
		(net "SAS2X28_B_HDD13_TX_-")
	)
	(segment
		(start 22.730968 -135.5725)
		(end 22.103842 -135.5725)
		(width 0.1143)
		(layer "In5.Cu")
		(net "SAS2X28_B_HDD13_TX_-")
	)
	(segment
		(start 18.587974 -135.906764)
		(end 20.651978 -133.84276)
		(width 0.1143)
		(layer "In5.Cu")
		(net "SAS2X28_B_HDD13_TX_-")
	)
	(segment
		(start 22.898862 -135.457184)
		(end 22.82063 -135.535416)
		(width 0.1143)
		(layer "In5.Cu")
		(net "SAS2X28_B_HDD13_TX_-")
	)
	(segment
		(start 22.427692 -133.742684)
		(end 22.5552 -133.870446)
		(width 0.1143)
		(layer "In5.Cu")
		(net "SAS2X28_B_HDD13_TX_-")
	)
	(segment
		(start 15.773146 -136.241536)
		(end 17.779746 -136.241536)
		(width 0.1143)
		(layer "In5.Cu")
		(net "SAS2X28_B_HDD13_TX_-")
	)
	(segment
		(start 22.935946 -134.394448)
		(end 22.935946 -135.367522)
		(width 0.1143)
		(layer "In5.Cu")
		(net "SAS2X28_B_HDD13_TX_-")
	)
	(segment
		(start 15.239746 -136.5377)
		(end 15.368016 -136.409176)
		(width 0.1143)
		(layer "In5.Cu")
		(net "SAS2X28_B_HDD13_TX_-")
	)
	(segment
		(start 21.919946 -135.4963)
		(end 21.894546 -135.4709)
		(width 0.1143)
		(layer "In5.Cu")
		(net "SAS2X28_B_HDD13_TX_-")
	)
	(segment
		(start 21.197824 -133.6167)
		(end 22.123146 -133.6167)
		(width 0.1143)
		(layer "In5.Cu")
		(net "SAS2X28_B_HDD13_TX_-")
	)
	(arc
		(start 21.894546 -135.4709)
		(mid 21.83668 -135.3312)
		(end 21.894546 -135.1915)
		(width 0.1143)
		(layer "In5.Cu")
		(net "SAS2X28_B_HDD13_TX_-")
	)
	(arc
		(start 20.651978 -133.84276)
		(mid 20.902414 -133.675424)
		(end 21.197824 -133.6167)
		(width 0.1143)
		(layer "In5.Cu")
		(net "SAS2X28_B_HDD13_TX_-")
	)
	(arc
		(start 17.779746 -136.241536)
		(mid 18.217153 -136.15453)
		(end 18.587974 -135.906764)
		(width 0.1143)
		(layer "In5.Cu")
		(net "SAS2X28_B_HDD13_TX_-")
	)
	(arc
		(start 22.123146 -133.6167)
		(mid 22.287956 -133.649389)
		(end 22.427692 -133.742684)
		(width 0.1143)
		(layer "In5.Cu")
		(net "SAS2X28_B_HDD13_TX_-")
	)
	(arc
		(start 22.935946 -135.367522)
		(mid 22.926313 -135.41604)
		(end 22.898862 -135.457184)
		(width 0.1143)
		(layer "In5.Cu")
		(net "SAS2X28_B_HDD13_TX_-")
	)
	(arc
		(start 22.8346 -134.149846)
		(mid 22.909586 -134.26207)
		(end 22.935946 -134.394448)
		(width 0.1143)
		(layer "In5.Cu")
		(net "SAS2X28_B_HDD13_TX_-")
	)
	(arc
		(start 22.82063 -135.535416)
		(mid 22.779479 -135.562849)
		(end 22.730968 -135.5725)
		(width 0.1143)
		(layer "In5.Cu")
		(net "SAS2X28_B_HDD13_TX_-")
	)
	(arc
		(start 15.368016 -136.409176)
		(mid 15.553906 -136.285061)
		(end 15.773146 -136.241536)
		(width 0.1143)
		(layer "In5.Cu")
		(net "SAS2X28_B_HDD13_TX_-")
	)
	(arc
		(start 22.103842 -135.5725)
		(mid 22.004308 -135.552701)
		(end 21.919946 -135.4963)
		(width 0.1143)
		(layer "In5.Cu")
		(net "SAS2X28_B_HDD13_TX_-")
	)
	(segment
		(start 5.164074 -135.500364)
		(end 3.19405 -135.500364)
		(width 0.09525)
		(layer "F.Cu")
		(net "SAS2X28_B_HDD13_TX_+")
	)
	(segment
		(start 14.863064 -135.830564)
		(end 5.961126 -135.830564)
		(width 0.09525)
		(layer "F.Cu")
		(net "SAS2X28_B_HDD13_TX_+")
	)
	(segment
		(start 21.586444 -135.842248)
		(end 21.894546 -136.15035)
		(width 0.09525)
		(layer "F.Cu")
		(net "SAS2X28_B_HDD13_TX_+")
	)
	(segment
		(start 21.033486 -135.7503)
		(end 21.364194 -135.7503)
		(width 0.09525)
		(layer "F.Cu")
		(net "SAS2X28_B_HDD13_TX_+")
	)
	(segment
		(start 19.600164 -136.009888)
		(end 20.41144 -136.009888)
		(width 0.09525)
		(layer "F.Cu")
		(net "SAS2X28_B_HDD13_TX_+")
	)
	(segment
		(start 3.19405 -135.500364)
		(end 3.192526 -135.49884)
		(width 0.09525)
		(layer "F.Cu")
		(net "SAS2X28_B_HDD13_TX_+")
	)
	(segment
		(start 20.41144 -136.009888)
		(end 20.414742 -136.006586)
		(width 0.09525)
		(layer "F.Cu")
		(net "SAS2X28_B_HDD13_TX_+")
	)
	(via
		(at 21.894546 -136.15035)
		(size 0.5588)
		(drill 0.3048)
		(layers "F.Cu" "B.Cu")
		(net "SAS2X28_B_HDD13_TX_+")
	)
	(via
		(at 15.240762 -135.6741)
		(size 0.5588)
		(drill 0.3048)
		(layers "F.Cu" "B.Cu")
		(net "SAS2X28_B_HDD13_TX_+")
	)
	(arc
		(start 15.240762 -135.6741)
		(mid 15.067473 -135.789888)
		(end 14.863064 -135.830564)
		(width 0.09525)
		(layer "F.Cu")
		(net "SAS2X28_B_HDD13_TX_+")
	)
	(arc
		(start 5.961126 -135.830564)
		(mid 5.690322 -135.776698)
		(end 5.460746 -135.6233)
		(width 0.09525)
		(layer "F.Cu")
		(net "SAS2X28_B_HDD13_TX_+")
	)
	(arc
		(start 20.414742 -136.006586)
		(mid 20.593982 -135.970933)
		(end 20.745958 -135.869426)
		(width 0.09525)
		(layer "F.Cu")
		(net "SAS2X28_B_HDD13_TX_+")
	)
	(arc
		(start 20.745958 -135.869426)
		(mid 20.877877 -135.781281)
		(end 21.033486 -135.7503)
		(width 0.09525)
		(layer "F.Cu")
		(net "SAS2X28_B_HDD13_TX_+")
	)
	(arc
		(start 21.364194 -135.7503)
		(mid 21.484486 -135.774134)
		(end 21.586444 -135.842248)
		(width 0.09525)
		(layer "F.Cu")
		(net "SAS2X28_B_HDD13_TX_+")
	)
	(arc
		(start 5.460746 -135.6233)
		(mid 5.324632 -135.532351)
		(end 5.164074 -135.500364)
		(width 0.09525)
		(layer "F.Cu")
		(net "SAS2X28_B_HDD13_TX_+")
	)
	(segment
		(start 22.123146 -133.3119)
		(end 22.123146 -133.312154)
		(width 0.1143)
		(layer "In5.Cu")
		(net "SAS2X28_B_HDD13_TX_+")
	)
	(segment
		(start 15.240762 -135.6741)
		(end 15.258796 -135.692134)
		(width 0.1143)
		(layer "In5.Cu")
		(net "SAS2X28_B_HDD13_TX_+")
	)
	(segment
		(start 22.643592 -133.527038)
		(end 22.7711 -133.655054)
		(width 0.1143)
		(layer "In5.Cu")
		(net "SAS2X28_B_HDD13_TX_+")
	)
	(segment
		(start 23.240746 -134.394194)
		(end 23.240746 -135.367522)
		(width 0.1143)
		(layer "In5.Cu")
		(net "SAS2X28_B_HDD13_TX_+")
	)
	(segment
		(start 21.19757 -133.3119)
		(end 22.123146 -133.3119)
		(width 0.1143)
		(layer "In5.Cu")
		(net "SAS2X28_B_HDD13_TX_+")
	)
	(segment
		(start 15.849346 -135.936736)
		(end 17.791176 -135.936736)
		(width 0.1143)
		(layer "In5.Cu")
		(net "SAS2X28_B_HDD13_TX_+")
	)
	(segment
		(start 23.114762 -135.67283)
		(end 23.036276 -135.751316)
		(width 0.1143)
		(layer "In5.Cu")
		(net "SAS2X28_B_HDD13_TX_+")
	)
	(segment
		(start 18.363946 -135.6995)
		(end 20.436078 -133.627368)
		(width 0.1143)
		(layer "In5.Cu")
		(net "SAS2X28_B_HDD13_TX_+")
	)
	(segment
		(start 22.730968 -135.8773)
		(end 22.248876 -135.8773)
		(width 0.1143)
		(layer "In5.Cu")
		(net "SAS2X28_B_HDD13_TX_+")
	)
	(segment
		(start 22.109938 -135.934704)
		(end 21.894546 -136.15035)
		(width 0.1143)
		(layer "In5.Cu")
		(net "SAS2X28_B_HDD13_TX_+")
	)
	(segment
		(start 22.7711 -133.655054)
		(end 23.050246 -133.9342)
		(width 0.1143)
		(layer "In5.Cu")
		(net "SAS2X28_B_HDD13_TX_+")
	)
	(arc
		(start 23.036276 -135.751316)
		(mid 22.896141 -135.844639)
		(end 22.730968 -135.8773)
		(width 0.1143)
		(layer "In5.Cu")
		(net "SAS2X28_B_HDD13_TX_+")
	)
	(arc
		(start 22.123146 -133.312154)
		(mid 22.404774 -133.367781)
		(end 22.643592 -133.527038)
		(width 0.1143)
		(layer "In5.Cu")
		(net "SAS2X28_B_HDD13_TX_+")
	)
	(arc
		(start 23.240746 -135.367522)
		(mid 23.208112 -135.532706)
		(end 23.114762 -135.67283)
		(width 0.1143)
		(layer "In5.Cu")
		(net "SAS2X28_B_HDD13_TX_+")
	)
	(arc
		(start 15.258796 -135.692134)
		(mid 15.529743 -135.873175)
		(end 15.849346 -135.936736)
		(width 0.1143)
		(layer "In5.Cu")
		(net "SAS2X28_B_HDD13_TX_+")
	)
	(arc
		(start 17.791176 -135.936736)
		(mid 18.101152 -135.875078)
		(end 18.363946 -135.6995)
		(width 0.1143)
		(layer "In5.Cu")
		(net "SAS2X28_B_HDD13_TX_+")
	)
	(arc
		(start 22.248876 -135.8773)
		(mid 22.173685 -135.892163)
		(end 22.109938 -135.934704)
		(width 0.1143)
		(layer "In5.Cu")
		(net "SAS2X28_B_HDD13_TX_+")
	)
	(arc
		(start 23.050246 -133.9342)
		(mid 23.191209 -134.145261)
		(end 23.240746 -134.394194)
		(width 0.1143)
		(layer "In5.Cu")
		(net "SAS2X28_B_HDD13_TX_+")
	)
	(arc
		(start 20.436078 -133.627368)
		(mid 20.785439 -133.393869)
		(end 21.19757 -133.3119)
		(width 0.1143)
		(layer "In5.Cu")
		(net "SAS2X28_B_HDD13_TX_+")
	)
	(segment
		(start 43.814746 -125.0569)
		(end 43.814746 -124.727462)
		(width 0.111252)
		(layer "F.Cu")
		(net "SAS2X28_A_HDD13_FLT")
	)
	(segment
		(start 43.814746 -124.727462)
		(end 44.500546 -124.041662)
		(width 0.111252)
		(layer "F.Cu")
		(net "SAS2X28_A_HDD13_FLT")
	)
	(segment
		(start 44.500546 -124.041662)
		(end 44.957746 -124.041662)
		(width 0.111252)
		(layer "F.Cu")
		(net "SAS2X28_A_HDD13_FLT")
	)
	(segment
		(start 44.843446 -126.0856)
		(end 43.814746 -125.0569)
		(width 0.111252)
		(layer "F.Cu")
		(net "SAS2X28_A_HDD13_FLT")
	)
	(segment
		(start 46.202346 -126.0856)
		(end 44.843446 -126.0856)
		(width 0.111252)
		(layer "F.Cu")
		(net "SAS2X28_A_HDD13_FLT")
	)
	(via
		(at 90.043 -396.113)
		(size 0.5588)
		(drill 0.3048)
		(layers "F.Cu" "B.Cu")
		(net "SAS2X28_A_HDD13_FLT")
	)
	(via
		(at 43.814746 -124.727462)
		(size 0.5588)
		(drill 0.3048)
		(layers "F.Cu" "B.Cu")
		(net "SAS2X28_A_HDD13_FLT")
	)
	(via
		(at 20.827746 -391.5537)
		(size 0.7112)
		(drill 0.3556)
		(layers "F.Cu" "B.Cu")
		(net "SAS2X28_A_HDD13_FLT")
	)
	(via
		(at 25.374346 -391.1219)
		(size 0.5588)
		(drill 0.3048)
		(layers "F.Cu" "B.Cu")
		(net "SAS2X28_A_HDD13_FLT")
	)
	(segment
		(start 2.81305 -389.500364)
		(end 2.811526 -389.49884)
		(width 0.111252)
		(layer "B.Cu")
		(net "SAS2X28_A_HDD13_FLT")
	)
	(segment
		(start 10.355326 -391.467848)
		(end 10.345674 -391.4775)
		(width 0.111252)
		(layer "B.Cu")
		(net "SAS2X28_A_HDD13_FLT")
	)
	(segment
		(start 5.904992 -390.201912)
		(end 5.904992 -390.195054)
		(width 0.111252)
		(layer "B.Cu")
		(net "SAS2X28_A_HDD13_FLT")
	)
	(segment
		(start 5.904992 -390.195054)
		(end 5.210302 -389.500364)
		(width 0.111252)
		(layer "B.Cu")
		(net "SAS2X28_A_HDD13_FLT")
	)
	(segment
		(start 20.168616 -391.5537)
		(end 19.762216 -391.9601)
		(width 0.111252)
		(layer "B.Cu")
		(net "SAS2X28_A_HDD13_FLT")
	)
	(segment
		(start 15.437612 -391.467848)
		(end 10.355326 -391.467848)
		(width 0.111252)
		(layer "B.Cu")
		(net "SAS2X28_A_HDD13_FLT")
	)
	(segment
		(start 8.8011 -391.4775)
		(end 8.537448 -391.213848)
		(width 0.111252)
		(layer "B.Cu")
		(net "SAS2X28_A_HDD13_FLT")
	)
	(segment
		(start 20.827746 -391.5537)
		(end 20.168616 -391.5537)
		(width 0.111252)
		(layer "B.Cu")
		(net "SAS2X28_A_HDD13_FLT")
	)
	(segment
		(start 10.345674 -391.4775)
		(end 8.8011 -391.4775)
		(width 0.111252)
		(layer "B.Cu")
		(net "SAS2X28_A_HDD13_FLT")
	)
	(segment
		(start 24.942546 -391.5537)
		(end 20.827746 -391.5537)
		(width 0.111252)
		(layer "B.Cu")
		(net "SAS2X28_A_HDD13_FLT")
	)
	(segment
		(start 25.374346 -391.1219)
		(end 24.942546 -391.5537)
		(width 0.111252)
		(layer "B.Cu")
		(net "SAS2X28_A_HDD13_FLT")
	)
	(segment
		(start 6.425946 -390.716008)
		(end 6.419088 -390.716008)
		(width 0.111252)
		(layer "B.Cu")
		(net "SAS2X28_A_HDD13_FLT")
	)
	(segment
		(start 6.419088 -390.716008)
		(end 5.904992 -390.201912)
		(width 0.111252)
		(layer "B.Cu")
		(net "SAS2X28_A_HDD13_FLT")
	)
	(segment
		(start 6.923786 -391.213848)
		(end 6.425946 -390.716008)
		(width 0.111252)
		(layer "B.Cu")
		(net "SAS2X28_A_HDD13_FLT")
	)
	(segment
		(start 8.537448 -391.213848)
		(end 6.923786 -391.213848)
		(width 0.111252)
		(layer "B.Cu")
		(net "SAS2X28_A_HDD13_FLT")
	)
	(segment
		(start 5.210302 -389.500364)
		(end 2.81305 -389.500364)
		(width 0.111252)
		(layer "B.Cu")
		(net "SAS2X28_A_HDD13_FLT")
	)
	(segment
		(start 19.762216 -391.9601)
		(end 15.929864 -391.9601)
		(width 0.111252)
		(layer "B.Cu")
		(net "SAS2X28_A_HDD13_FLT")
	)
	(segment
		(start 15.929864 -391.9601)
		(end 15.437612 -391.467848)
		(width 0.111252)
		(layer "B.Cu")
		(net "SAS2X28_A_HDD13_FLT")
	)
	(segment
		(start 38.9001 -391.1219)
		(end 43.7642 -395.986)
		(width 0.14605)
		(layer "In2.Cu")
		(net "SAS2X28_A_HDD13_FLT")
	)
	(segment
		(start 89.916 -395.986)
		(end 90.043 -396.113)
		(width 0.14605)
		(layer "In2.Cu")
		(net "SAS2X28_A_HDD13_FLT")
	)
	(segment
		(start 25.374346 -391.1219)
		(end 38.9001 -391.1219)
		(width 0.14605)
		(layer "In2.Cu")
		(net "SAS2X28_A_HDD13_FLT")
	)
	(segment
		(start 43.7642 -395.986)
		(end 89.916 -395.986)
		(width 0.14605)
		(layer "In2.Cu")
		(net "SAS2X28_A_HDD13_FLT")
	)
	(segment
		(start 43.814746 -126.10338)
		(end 45.105066 -127.3937)
		(width 0.14605)
		(layer "In5.Cu")
		(net "SAS2X28_A_HDD13_FLT")
	)
	(segment
		(start 74.449432 -196.894704)
		(end 82.021934 -196.894704)
		(width 0.14605)
		(layer "In5.Cu")
		(net "SAS2X28_A_HDD13_FLT")
	)
	(segment
		(start 45.105066 -127.3937)
		(end 45.105066 -167.550338)
		(width 0.14605)
		(layer "In5.Cu")
		(net "SAS2X28_A_HDD13_FLT")
	)
	(segment
		(start 90.052398 -389.131048)
		(end 90.043 -389.140446)
		(width 0.14605)
		(layer "In5.Cu")
		(net "SAS2X28_A_HDD13_FLT")
	)
	(segment
		(start 90.052398 -204.925168)
		(end 90.052398 -389.131048)
		(width 0.14605)
		(layer "In5.Cu")
		(net "SAS2X28_A_HDD13_FLT")
	)
	(segment
		(start 90.043 -389.140446)
		(end 90.043 -396.113)
		(width 0.14605)
		(layer "In5.Cu")
		(net "SAS2X28_A_HDD13_FLT")
	)
	(segment
		(start 45.105066 -167.550338)
		(end 74.449432 -196.894704)
		(width 0.14605)
		(layer "In5.Cu")
		(net "SAS2X28_A_HDD13_FLT")
	)
	(segment
		(start 43.814746 -124.727462)
		(end 43.814746 -126.10338)
		(width 0.14605)
		(layer "In5.Cu")
		(net "SAS2X28_A_HDD13_FLT")
	)
	(segment
		(start 82.021934 -196.894704)
		(end 90.052398 -204.925168)
		(width 0.14605)
		(layer "In5.Cu")
		(net "SAS2X28_A_HDD13_FLT")
	)
	(segment
		(start 28.104846 -133.003798)
		(end 28.1051 -133.003798)
		(width 0.09525)
		(layer "F.Cu")
		(net "SAS2X28_B_HDD13_RX_-")
	)
	(segment
		(start 24.866854 -130.816858)
		(end 24.8666 -130.817112)
		(width 0.09525)
		(layer "F.Cu")
		(net "SAS2X28_B_HDD13_RX_-")
	)
	(segment
		(start 24.979376 -130.544824)
		(end 25.1206 -130.4036)
		(width 0.09525)
		(layer "F.Cu")
		(net "SAS2X28_B_HDD13_RX_-")
	)
	(segment
		(start 28.033472 -133.075426)
		(end 28.104846 -133.003798)
		(width 0.09525)
		(layer "F.Cu")
		(net "SAS2X28_B_HDD13_RX_-")
	)
	(segment
		(start 28.122372 -131.70662)
		(end 28.046172 -131.63042)
		(width 0.09525)
		(layer "F.Cu")
		(net "SAS2X28_B_HDD13_RX_-")
	)
	(segment
		(start 27.690572 -131.4831)
		(end 25.694894 -131.4831)
		(width 0.09525)
		(layer "F.Cu")
		(net "SAS2X28_B_HDD13_RX_-")
	)
	(segment
		(start 25.100026 -131.23672)
		(end 24.998172 -131.134866)
		(width 0.09525)
		(layer "F.Cu")
		(net "SAS2X28_B_HDD13_RX_-")
	)
	(segment
		(start 28.122372 -131.706874)
		(end 28.122372 -131.70662)
		(width 0.09525)
		(layer "F.Cu")
		(net "SAS2X28_B_HDD13_RX_-")
	)
	(segment
		(start 27.267154 -133.321552)
		(end 27.533346 -133.321552)
		(width 0.09525)
		(layer "F.Cu")
		(net "SAS2X28_B_HDD13_RX_-")
	)
	(segment
		(start 27.967432 -133.14172)
		(end 28.033472 -133.075426)
		(width 0.09525)
		(layer "F.Cu")
		(net "SAS2X28_B_HDD13_RX_-")
	)
	(segment
		(start 28.320746 -132.483098)
		(end 28.320746 -132.185918)
		(width 0.09525)
		(layer "F.Cu")
		(net "SAS2X28_B_HDD13_RX_-")
	)
	(via
		(at 25.1206 -130.4036)
		(size 0.5588)
		(drill 0.3048)
		(layers "F.Cu" "B.Cu")
		(net "SAS2X28_B_HDD13_RX_-")
	)
	(via
		(at 6.756146 -134.442708)
		(size 0.5588)
		(drill 0.3048)
		(layers "F.Cu" "B.Cu")
		(net "SAS2X28_B_HDD13_RX_-")
	)
	(arc
		(start 24.8666 -130.817112)
		(mid 24.895911 -130.669754)
		(end 24.979376 -130.544824)
		(width 0.09525)
		(layer "F.Cu")
		(net "SAS2X28_B_HDD13_RX_-")
	)
	(arc
		(start 28.320746 -132.185918)
		(mid 28.269249 -131.926642)
		(end 28.122372 -131.706874)
		(width 0.09525)
		(layer "F.Cu")
		(net "SAS2X28_B_HDD13_RX_-")
	)
	(arc
		(start 27.533346 -133.321552)
		(mid 27.734588 -133.287543)
		(end 27.913584 -133.189472)
		(width 0.09525)
		(layer "F.Cu")
		(net "SAS2X28_B_HDD13_RX_-")
	)
	(arc
		(start 25.694894 -131.4831)
		(mid 25.372962 -131.419064)
		(end 25.100026 -131.23672)
		(width 0.09525)
		(layer "F.Cu")
		(net "SAS2X28_B_HDD13_RX_-")
	)
	(arc
		(start 27.913584 -133.189472)
		(mid 27.941206 -133.166383)
		(end 27.967432 -133.14172)
		(width 0.09525)
		(layer "F.Cu")
		(net "SAS2X28_B_HDD13_RX_-")
	)
	(arc
		(start 24.998172 -131.134866)
		(mid 24.900926 -130.988905)
		(end 24.866854 -130.816858)
		(width 0.09525)
		(layer "F.Cu")
		(net "SAS2X28_B_HDD13_RX_-")
	)
	(arc
		(start 26.59253 -133.600952)
		(mid 26.90205 -133.394137)
		(end 27.267154 -133.321552)
		(width 0.09525)
		(layer "F.Cu")
		(net "SAS2X28_B_HDD13_RX_-")
	)
	(arc
		(start 28.1051 -133.003798)
		(mid 28.133526 -132.973712)
		(end 28.160218 -132.942076)
		(width 0.09525)
		(layer "F.Cu")
		(net "SAS2X28_B_HDD13_RX_-")
	)
	(arc
		(start 28.046172 -131.63042)
		(mid 27.883021 -131.521406)
		(end 27.690572 -131.4831)
		(width 0.09525)
		(layer "F.Cu")
		(net "SAS2X28_B_HDD13_RX_-")
	)
	(arc
		(start 28.160218 -132.942076)
		(mid 28.279433 -132.726218)
		(end 28.320746 -132.483098)
		(width 0.09525)
		(layer "F.Cu")
		(net "SAS2X28_B_HDD13_RX_-")
	)
	(segment
		(start 6.375146 -134.160768)
		(end 5.587746 -134.160768)
		(width 0.09525)
		(layer "B.Cu")
		(net "SAS2X28_B_HDD13_RX_-")
	)
	(segment
		(start 4.900676 -134.498842)
		(end 2.811526 -134.498842)
		(width 0.09525)
		(layer "B.Cu")
		(net "SAS2X28_B_HDD13_RX_-")
	)
	(segment
		(start 4.9022 -134.500366)
		(end 4.900676 -134.498842)
		(width 0.09525)
		(layer "B.Cu")
		(net "SAS2X28_B_HDD13_RX_-")
	)
	(segment
		(start 5.244592 -134.302754)
		(end 5.14985 -134.39775)
		(width 0.09525)
		(layer "B.Cu")
		(net "SAS2X28_B_HDD13_RX_-")
	)
	(segment
		(start 6.756146 -134.442708)
		(end 6.54431 -134.230872)
		(width 0.09525)
		(layer "B.Cu")
		(net "SAS2X28_B_HDD13_RX_-")
	)
	(arc
		(start 5.587746 -134.160768)
		(mid 5.402037 -134.197614)
		(end 5.244592 -134.302754)
		(width 0.09525)
		(layer "B.Cu")
		(net "SAS2X28_B_HDD13_RX_-")
	)
	(arc
		(start 6.54431 -134.230872)
		(mid 6.466697 -134.179013)
		(end 6.375146 -134.160768)
		(width 0.09525)
		(layer "B.Cu")
		(net "SAS2X28_B_HDD13_RX_-")
	)
	(arc
		(start 5.14985 -134.39775)
		(mid 5.036227 -134.47367)
		(end 4.9022 -134.500366)
		(width 0.09525)
		(layer "B.Cu")
		(net "SAS2X28_B_HDD13_RX_-")
	)
	(segment
		(start 24.650446 -131.762246)
		(end 24.650446 -131.7625)
		(width 0.1143)
		(layer "In2.Cu")
		(net "SAS2X28_B_HDD13_RX_-")
	)
	(segment
		(start 13.842746 -134.130796)
		(end 13.842746 -134.13105)
		(width 0.1143)
		(layer "In2.Cu")
		(net "SAS2X28_B_HDD13_RX_-")
	)
	(segment
		(start 24.159718 -131.9657)
		(end 18.661126 -131.9657)
		(width 0.1143)
		(layer "In2.Cu")
		(net "SAS2X28_B_HDD13_RX_-")
	)
	(segment
		(start 24.892 -130.955542)
		(end 24.892 -131.179824)
		(width 0.1143)
		(layer "In2.Cu")
		(net "SAS2X28_B_HDD13_RX_-")
	)
	(segment
		(start 15.074392 -133.451346)
		(end 14.784832 -133.74116)
		(width 0.1143)
		(layer "In2.Cu")
		(net "SAS2X28_B_HDD13_RX_-")
	)
	(segment
		(start 13.842746 -134.13105)
		(end 7.508494 -134.13105)
		(width 0.1143)
		(layer "In2.Cu")
		(net "SAS2X28_B_HDD13_RX_-")
	)
	(arc
		(start 7.508494 -134.13105)
		(mid 7.101317 -134.212043)
		(end 6.756146 -134.442708)
		(width 0.1143)
		(layer "In2.Cu")
		(net "SAS2X28_B_HDD13_RX_-")
	)
	(arc
		(start 24.650446 -131.7625)
		(mid 24.425284 -131.912885)
		(end 24.159718 -131.9657)
		(width 0.1143)
		(layer "In2.Cu")
		(net "SAS2X28_B_HDD13_RX_-")
	)
	(arc
		(start 18.661126 -131.9657)
		(mid 16.72001 -132.351812)
		(end 15.074392 -133.451346)
		(width 0.1143)
		(layer "In2.Cu")
		(net "SAS2X28_B_HDD13_RX_-")
	)
	(arc
		(start 25.1206 -130.4036)
		(mid 24.951395 -130.656833)
		(end 24.892 -130.955542)
		(width 0.1143)
		(layer "In2.Cu")
		(net "SAS2X28_B_HDD13_RX_-")
	)
	(arc
		(start 14.784832 -133.74116)
		(mid 14.35254 -134.029666)
		(end 13.842746 -134.130796)
		(width 0.1143)
		(layer "In2.Cu")
		(net "SAS2X28_B_HDD13_RX_-")
	)
	(arc
		(start 24.892 -131.179824)
		(mid 24.829128 -131.495053)
		(end 24.650446 -131.762246)
		(width 0.1143)
		(layer "In2.Cu")
		(net "SAS2X28_B_HDD13_RX_-")
	)
	(segment
		(start 27.990546 -132.483352)
		(end 27.990546 -132.185664)
		(width 0.09525)
		(layer "F.Cu")
		(net "SAS2X28_B_HDD13_RX_+")
	)
	(segment
		(start 27.734006 -132.908294)
		(end 27.733752 -132.90804)
		(width 0.09525)
		(layer "F.Cu")
		(net "SAS2X28_B_HDD13_RX_+")
	)
	(segment
		(start 24.441658 -130.588004)
		(end 24.257 -130.4036)
		(width 0.09525)
		(layer "F.Cu")
		(net "SAS2X28_B_HDD13_RX_+")
	)
	(segment
		(start 24.866346 -131.470146)
		(end 24.765 -131.3688)
		(width 0.09525)
		(layer "F.Cu")
		(net "SAS2X28_B_HDD13_RX_+")
	)
	(segment
		(start 27.812492 -131.863846)
		(end 27.812746 -131.863846)
		(width 0.09525)
		(layer "F.Cu")
		(net "SAS2X28_B_HDD13_RX_+")
	)
	(segment
		(start 27.888946 -131.9403)
		(end 27.812492 -131.863846)
		(width 0.09525)
		(layer "F.Cu")
		(net "SAS2X28_B_HDD13_RX_+")
	)
	(segment
		(start 27.733752 -132.90804)
		(end 27.871674 -132.770372)
		(width 0.09525)
		(layer "F.Cu")
		(net "SAS2X28_B_HDD13_RX_+")
	)
	(segment
		(start 27.267154 -132.991352)
		(end 27.533092 -132.991352)
		(width 0.09525)
		(layer "F.Cu")
		(net "SAS2X28_B_HDD13_RX_+")
	)
	(segment
		(start 27.690318 -131.8133)
		(end 25.694894 -131.8133)
		(width 0.09525)
		(layer "F.Cu")
		(net "SAS2X28_B_HDD13_RX_+")
	)
	(via
		(at 24.257 -130.4036)
		(size 0.5588)
		(drill 0.3048)
		(layers "F.Cu" "B.Cu")
		(net "SAS2X28_B_HDD13_RX_+")
	)
	(via
		(at 6.756146 -133.514592)
		(size 0.5588)
		(drill 0.3048)
		(layers "F.Cu" "B.Cu")
		(net "SAS2X28_B_HDD13_RX_+")
	)
	(arc
		(start 27.709114 -132.930138)
		(mid 27.721882 -132.919583)
		(end 27.734006 -132.908294)
		(width 0.09525)
		(layer "F.Cu")
		(net "SAS2X28_B_HDD13_RX_+")
	)
	(arc
		(start 27.533092 -132.991352)
		(mid 27.626274 -132.975613)
		(end 27.709114 -132.930138)
		(width 0.09525)
		(layer "F.Cu")
		(net "SAS2X28_B_HDD13_RX_+")
	)
	(arc
		(start 24.765 -131.3688)
		(mid 24.595844 -131.115684)
		(end 24.5364 -130.817112)
		(width 0.09525)
		(layer "F.Cu")
		(net "SAS2X28_B_HDD13_RX_+")
	)
	(arc
		(start 27.812746 -131.863846)
		(mid 27.756575 -131.826343)
		(end 27.690318 -131.8133)
		(width 0.09525)
		(layer "F.Cu")
		(net "SAS2X28_B_HDD13_RX_+")
	)
	(arc
		(start 26.59253 -132.711952)
		(mid 26.90205 -132.918767)
		(end 27.267154 -132.991352)
		(width 0.09525)
		(layer "F.Cu")
		(net "SAS2X28_B_HDD13_RX_+")
	)
	(arc
		(start 25.694894 -131.8133)
		(mid 25.246464 -131.724177)
		(end 24.866346 -131.470146)
		(width 0.09525)
		(layer "F.Cu")
		(net "SAS2X28_B_HDD13_RX_+")
	)
	(arc
		(start 24.5364 -130.817112)
		(mid 24.511831 -130.693126)
		(end 24.441658 -130.588004)
		(width 0.09525)
		(layer "F.Cu")
		(net "SAS2X28_B_HDD13_RX_+")
	)
	(arc
		(start 27.871674 -132.770372)
		(mid 27.887265 -132.753778)
		(end 27.9019 -132.736336)
		(width 0.09525)
		(layer "F.Cu")
		(net "SAS2X28_B_HDD13_RX_+")
	)
	(arc
		(start 27.990546 -132.185664)
		(mid 27.964135 -132.052887)
		(end 27.888946 -131.9403)
		(width 0.09525)
		(layer "F.Cu")
		(net "SAS2X28_B_HDD13_RX_+")
	)
	(arc
		(start 27.9019 -132.736336)
		(mid 27.967726 -132.617376)
		(end 27.990546 -132.483352)
		(width 0.09525)
		(layer "F.Cu")
		(net "SAS2X28_B_HDD13_RX_+")
	)
	(segment
		(start 4.966462 -133.498844)
		(end 2.811526 -133.498844)
		(width 0.09525)
		(layer "B.Cu")
		(net "SAS2X28_B_HDD13_RX_+")
	)
	(segment
		(start 4.967986 -133.500368)
		(end 4.966462 -133.498844)
		(width 0.09525)
		(layer "B.Cu")
		(net "SAS2X28_B_HDD13_RX_+")
	)
	(segment
		(start 6.197346 -133.830568)
		(end 5.765546 -133.830568)
		(width 0.09525)
		(layer "B.Cu")
		(net "SAS2X28_B_HDD13_RX_+")
	)
	(segment
		(start 6.756146 -133.514592)
		(end 6.611874 -133.658864)
		(width 0.09525)
		(layer "B.Cu")
		(net "SAS2X28_B_HDD13_RX_+")
	)
	(arc
		(start 5.765546 -133.830568)
		(mid 5.500521 -133.777945)
		(end 5.275834 -133.627876)
		(width 0.09525)
		(layer "B.Cu")
		(net "SAS2X28_B_HDD13_RX_+")
	)
	(arc
		(start 5.275834 -133.627876)
		(mid 5.134592 -133.533501)
		(end 4.967986 -133.500368)
		(width 0.09525)
		(layer "B.Cu")
		(net "SAS2X28_B_HDD13_RX_+")
	)
	(arc
		(start 6.611874 -133.658864)
		(mid 6.421687 -133.785943)
		(end 6.197346 -133.830568)
		(width 0.09525)
		(layer "B.Cu")
		(net "SAS2X28_B_HDD13_RX_+")
	)
	(segment
		(start 10.624566 -133.82625)
		(end 10.967466 -133.82625)
		(width 0.1143)
		(layer "In2.Cu")
		(net "SAS2X28_B_HDD13_RX_+")
	)
	(segment
		(start 13.499846 -133.82625)
		(end 13.842746 -133.82625)
		(width 0.1143)
		(layer "In2.Cu")
		(net "SAS2X28_B_HDD13_RX_+")
	)
	(segment
		(start 21.977858 -131.6609)
		(end 22.320758 -131.6609)
		(width 0.1143)
		(layer "In2.Cu")
		(net "SAS2X28_B_HDD13_RX_+")
	)
	(segment
		(start 18.66138 -131.6609)
		(end 19.445478 -131.6609)
		(width 0.1143)
		(layer "In2.Cu")
		(net "SAS2X28_B_HDD13_RX_+")
	)
	(segment
		(start 19.821398 -131.47294)
		(end 20.164298 -131.47294)
		(width 0.1143)
		(layer "In2.Cu")
		(net "SAS2X28_B_HDD13_RX_+")
	)
	(segment
		(start 22.696678 -131.47294)
		(end 23.039578 -131.47294)
		(width 0.1143)
		(layer "In2.Cu")
		(net "SAS2X28_B_HDD13_RX_+")
	)
	(segment
		(start 7.508748 -133.82625)
		(end 9.529826 -133.82625)
		(width 0.1143)
		(layer "In2.Cu")
		(net "SAS2X28_B_HDD13_RX_+")
	)
	(segment
		(start 12.781026 -133.63829)
		(end 13.123926 -133.63829)
		(width 0.1143)
		(layer "In2.Cu")
		(net "SAS2X28_B_HDD13_RX_+")
	)
	(segment
		(start 14.569186 -133.525514)
		(end 14.858746 -133.2357)
		(width 0.1143)
		(layer "In2.Cu")
		(net "SAS2X28_B_HDD13_RX_+")
	)
	(segment
		(start 21.259038 -131.47294)
		(end 21.601938 -131.47294)
		(width 0.1143)
		(layer "In2.Cu")
		(net "SAS2X28_B_HDD13_RX_+")
	)
	(segment
		(start 11.343386 -133.63829)
		(end 11.686286 -133.63829)
		(width 0.1143)
		(layer "In2.Cu")
		(net "SAS2X28_B_HDD13_RX_+")
	)
	(segment
		(start 9.905746 -133.63829)
		(end 10.248646 -133.63829)
		(width 0.1143)
		(layer "In2.Cu")
		(net "SAS2X28_B_HDD13_RX_+")
	)
	(segment
		(start 12.062206 -133.82625)
		(end 12.405106 -133.82625)
		(width 0.1143)
		(layer "In2.Cu")
		(net "SAS2X28_B_HDD13_RX_+")
	)
	(segment
		(start 6.756146 -133.514592)
		(end 6.756146 -133.570218)
		(width 0.1143)
		(layer "In2.Cu")
		(net "SAS2X28_B_HDD13_RX_+")
	)
	(segment
		(start 24.5872 -131.17957)
		(end 24.5872 -131.0386)
		(width 0.1143)
		(layer "In2.Cu")
		(net "SAS2X28_B_HDD13_RX_+")
	)
	(segment
		(start 20.540218 -131.6609)
		(end 20.883118 -131.6609)
		(width 0.1143)
		(layer "In2.Cu")
		(net "SAS2X28_B_HDD13_RX_+")
	)
	(segment
		(start 23.415498 -131.6609)
		(end 24.159718 -131.6609)
		(width 0.1143)
		(layer "In2.Cu")
		(net "SAS2X28_B_HDD13_RX_+")
	)
	(segment
		(start 24.371554 -130.518408)
		(end 24.257 -130.4036)
		(width 0.1143)
		(layer "In2.Cu")
		(net "SAS2X28_B_HDD13_RX_+")
	)
	(arc
		(start 11.874246 -133.73227)
		(mid 11.95734 -133.801006)
		(end 12.062206 -133.82625)
		(width 0.1143)
		(layer "In2.Cu")
		(net "SAS2X28_B_HDD13_RX_+")
	)
	(arc
		(start 24.159718 -131.6609)
		(mid 24.308728 -131.63126)
		(end 24.435054 -131.546854)
		(width 0.1143)
		(layer "In2.Cu")
		(net "SAS2X28_B_HDD13_RX_+")
	)
	(arc
		(start 10.967466 -133.82625)
		(mid 11.072376 -133.801095)
		(end 11.155426 -133.73227)
		(width 0.1143)
		(layer "In2.Cu")
		(net "SAS2X28_B_HDD13_RX_+")
	)
	(arc
		(start 10.248646 -133.63829)
		(mid 10.353556 -133.663445)
		(end 10.436606 -133.73227)
		(width 0.1143)
		(layer "In2.Cu")
		(net "SAS2X28_B_HDD13_RX_+")
	)
	(arc
		(start 7.152132 -133.873494)
		(mid 7.32888 -133.838086)
		(end 7.508748 -133.82625)
		(width 0.1143)
		(layer "In2.Cu")
		(net "SAS2X28_B_HDD13_RX_+")
	)
	(arc
		(start 20.352258 -131.56692)
		(mid 20.435352 -131.635656)
		(end 20.540218 -131.6609)
		(width 0.1143)
		(layer "In2.Cu")
		(net "SAS2X28_B_HDD13_RX_+")
	)
	(arc
		(start 21.789898 -131.56692)
		(mid 21.872992 -131.635656)
		(end 21.977858 -131.6609)
		(width 0.1143)
		(layer "In2.Cu")
		(net "SAS2X28_B_HDD13_RX_+")
	)
	(arc
		(start 13.311886 -133.73227)
		(mid 13.39498 -133.801006)
		(end 13.499846 -133.82625)
		(width 0.1143)
		(layer "In2.Cu")
		(net "SAS2X28_B_HDD13_RX_+")
	)
	(arc
		(start 12.593066 -133.73227)
		(mid 12.67616 -133.663534)
		(end 12.781026 -133.63829)
		(width 0.1143)
		(layer "In2.Cu")
		(net "SAS2X28_B_HDD13_RX_+")
	)
	(arc
		(start 24.5872 -131.0386)
		(mid 24.531105 -130.757061)
		(end 24.371554 -130.518408)
		(width 0.1143)
		(layer "In2.Cu")
		(net "SAS2X28_B_HDD13_RX_+")
	)
	(arc
		(start 24.435054 -131.546854)
		(mid 24.54765 -131.378343)
		(end 24.5872 -131.17957)
		(width 0.1143)
		(layer "In2.Cu")
		(net "SAS2X28_B_HDD13_RX_+")
	)
	(arc
		(start 11.155426 -133.73227)
		(mid 11.23852 -133.663534)
		(end 11.343386 -133.63829)
		(width 0.1143)
		(layer "In2.Cu")
		(net "SAS2X28_B_HDD13_RX_+")
	)
	(arc
		(start 21.601938 -131.47294)
		(mid 21.706778 -131.498184)
		(end 21.789898 -131.56692)
		(width 0.1143)
		(layer "In2.Cu")
		(net "SAS2X28_B_HDD13_RX_+")
	)
	(arc
		(start 12.405106 -133.82625)
		(mid 12.510016 -133.801095)
		(end 12.593066 -133.73227)
		(width 0.1143)
		(layer "In2.Cu")
		(net "SAS2X28_B_HDD13_RX_+")
	)
	(arc
		(start 9.717786 -133.73227)
		(mid 9.80088 -133.663534)
		(end 9.905746 -133.63829)
		(width 0.1143)
		(layer "In2.Cu")
		(net "SAS2X28_B_HDD13_RX_+")
	)
	(arc
		(start 6.756146 -133.570218)
		(mid 6.879274 -133.819642)
		(end 7.152132 -133.873494)
		(width 0.1143)
		(layer "In2.Cu")
		(net "SAS2X28_B_HDD13_RX_+")
	)
	(arc
		(start 22.508718 -131.56692)
		(mid 22.591812 -131.498184)
		(end 22.696678 -131.47294)
		(width 0.1143)
		(layer "In2.Cu")
		(net "SAS2X28_B_HDD13_RX_+")
	)
	(arc
		(start 10.436606 -133.73227)
		(mid 10.5197 -133.801006)
		(end 10.624566 -133.82625)
		(width 0.1143)
		(layer "In2.Cu")
		(net "SAS2X28_B_HDD13_RX_+")
	)
	(arc
		(start 9.529826 -133.82625)
		(mid 9.634736 -133.801095)
		(end 9.717786 -133.73227)
		(width 0.1143)
		(layer "In2.Cu")
		(net "SAS2X28_B_HDD13_RX_+")
	)
	(arc
		(start 23.039578 -131.47294)
		(mid 23.144488 -131.498095)
		(end 23.227538 -131.56692)
		(width 0.1143)
		(layer "In2.Cu")
		(net "SAS2X28_B_HDD13_RX_+")
	)
	(arc
		(start 13.123926 -133.63829)
		(mid 13.228836 -133.663445)
		(end 13.311886 -133.73227)
		(width 0.1143)
		(layer "In2.Cu")
		(net "SAS2X28_B_HDD13_RX_+")
	)
	(arc
		(start 14.858746 -133.2357)
		(mid 16.603425 -132.070065)
		(end 18.66138 -131.6609)
		(width 0.1143)
		(layer "In2.Cu")
		(net "SAS2X28_B_HDD13_RX_+")
	)
	(arc
		(start 13.842746 -133.82625)
		(mid 14.235883 -133.748144)
		(end 14.569186 -133.525514)
		(width 0.1143)
		(layer "In2.Cu")
		(net "SAS2X28_B_HDD13_RX_+")
	)
	(arc
		(start 21.071078 -131.56692)
		(mid 21.154172 -131.498184)
		(end 21.259038 -131.47294)
		(width 0.1143)
		(layer "In2.Cu")
		(net "SAS2X28_B_HDD13_RX_+")
	)
	(arc
		(start 11.686286 -133.63829)
		(mid 11.791196 -133.663445)
		(end 11.874246 -133.73227)
		(width 0.1143)
		(layer "In2.Cu")
		(net "SAS2X28_B_HDD13_RX_+")
	)
	(arc
		(start 19.633438 -131.56692)
		(mid 19.716532 -131.498184)
		(end 19.821398 -131.47294)
		(width 0.1143)
		(layer "In2.Cu")
		(net "SAS2X28_B_HDD13_RX_+")
	)
	(arc
		(start 19.445478 -131.6609)
		(mid 19.550318 -131.635656)
		(end 19.633438 -131.56692)
		(width 0.1143)
		(layer "In2.Cu")
		(net "SAS2X28_B_HDD13_RX_+")
	)
	(arc
		(start 22.320758 -131.6609)
		(mid 22.425668 -131.635745)
		(end 22.508718 -131.56692)
		(width 0.1143)
		(layer "In2.Cu")
		(net "SAS2X28_B_HDD13_RX_+")
	)
	(arc
		(start 23.227538 -131.56692)
		(mid 23.310632 -131.635656)
		(end 23.415498 -131.6609)
		(width 0.1143)
		(layer "In2.Cu")
		(net "SAS2X28_B_HDD13_RX_+")
	)
	(arc
		(start 20.883118 -131.6609)
		(mid 20.987958 -131.635656)
		(end 21.071078 -131.56692)
		(width 0.1143)
		(layer "In2.Cu")
		(net "SAS2X28_B_HDD13_RX_+")
	)
	(arc
		(start 20.164298 -131.47294)
		(mid 20.269138 -131.498184)
		(end 20.352258 -131.56692)
		(width 0.1143)
		(layer "In2.Cu")
		(net "SAS2X28_B_HDD13_RX_+")
	)
	(segment
		(start 228.229922 -142.368524)
		(end 228.462078 -142.136368)
		(width 0.111252)
		(layer "F.Cu")
		(net "FLT_NET_HDD3")
	)
	(segment
		(start 228.229922 -143.753332)
		(end 228.229922 -142.368524)
		(width 0.111252)
		(layer "F.Cu")
		(net "FLT_NET_HDD3")
	)
	(segment
		(start 229.084124 -142.136368)
		(end 228.51999 -142.136368)
		(width 0.111252)
		(layer "F.Cu")
		(net "FLT_NET_HDD3")
	)
	(segment
		(start 228.462078 -142.136368)
		(end 228.51999 -142.136368)
		(width 0.111252)
		(layer "F.Cu")
		(net "FLT_NET_HDD3")
	)
	(segment
		(start 229.919784 -142.972028)
		(end 229.084124 -142.136368)
		(width 0.111252)
		(layer "F.Cu")
		(net "FLT_NET_HDD3")
	)
	(segment
		(start 228.230176 -143.753586)
		(end 228.229922 -143.753332)
		(width 0.111252)
		(layer "F.Cu")
		(net "FLT_NET_HDD3")
	)
	(via
		(at 228.51999 -142.136368)
		(size 0.7112)
		(drill 0.3556)
		(layers "F.Cu" "B.Cu")
		(net "FLT_NET_HDD3")
	)
	(segment
		(start 15.515844 -165.5826)
		(end 15.366746 -165.731698)
		(width 0.111252)
		(layer "F.Cu")
		(net "DRIVE_ACT_13")
	)
	(segment
		(start 15.366746 -166.747698)
		(end 15.366746 -167.6527)
		(width 0.111252)
		(layer "F.Cu")
		(net "DRIVE_ACT_13")
	)
	(segment
		(start 15.366746 -167.6527)
		(end 15.747746 -168.0337)
		(width 0.111252)
		(layer "F.Cu")
		(net "DRIVE_ACT_13")
	)
	(segment
		(start 15.366746 -165.731698)
		(end 15.366746 -166.747698)
		(width 0.111252)
		(layer "F.Cu")
		(net "DRIVE_ACT_13")
	)
	(segment
		(start 16.903446 -165.5826)
		(end 15.515844 -165.5826)
		(width 0.111252)
		(layer "F.Cu")
		(net "DRIVE_ACT_13")
	)
	(via
		(at 15.747746 -168.0337)
		(size 0.7112)
		(drill 0.3556)
		(layers "F.Cu" "B.Cu")
		(net "DRIVE_ACT_13")
	)
	(segment
		(start 228.230176 -246.753634)
		(end 228.601016 -246.753634)
		(width 0.111252)
		(layer "F.Cu")
		(net "FLT_NET_HDD2")
	)
	(segment
		(start 228.601016 -246.753634)
		(end 229.891082 -245.463568)
		(width 0.111252)
		(layer "F.Cu")
		(net "FLT_NET_HDD2")
	)
	(segment
		(start 229.891082 -245.463568)
		(end 229.891082 -244.593364)
		(width 0.111252)
		(layer "F.Cu")
		(net "FLT_NET_HDD2")
	)
	(segment
		(start 229.891082 -244.593364)
		(end 230.123746 -244.3607)
		(width 0.111252)
		(layer "F.Cu")
		(net "FLT_NET_HDD2")
	)
	(via
		(at 230.123746 -244.3607)
		(size 0.7112)
		(drill 0.3556)
		(layers "F.Cu" "B.Cu")
		(net "FLT_NET_HDD2")
	)
	(segment
		(start 228.230176 -349.753682)
		(end 228.870764 -349.753682)
		(width 0.111252)
		(layer "F.Cu")
		(net "FLT_NET_HDD1")
	)
	(segment
		(start 229.107746 -349.5167)
		(end 229.107746 -348.159578)
		(width 0.111252)
		(layer "F.Cu")
		(net "FLT_NET_HDD1")
	)
	(segment
		(start 223.646746 -347.3577)
		(end 221.805246 -347.3577)
		(width 0.111252)
		(layer "F.Cu")
		(net "FLT_NET_HDD1")
	)
	(segment
		(start 228.870764 -349.753682)
		(end 229.107746 -349.5167)
		(width 0.111252)
		(layer "F.Cu")
		(net "FLT_NET_HDD1")
	)
	(segment
		(start 228.305868 -347.3577)
		(end 223.646746 -347.3577)
		(width 0.111252)
		(layer "F.Cu")
		(net "FLT_NET_HDD1")
	)
	(segment
		(start 229.107746 -348.159578)
		(end 228.305868 -347.3577)
		(width 0.111252)
		(layer "F.Cu")
		(net "FLT_NET_HDD1")
	)
	(via
		(at 223.646746 -347.3577)
		(size 0.7112)
		(drill 0.3556)
		(layers "F.Cu" "B.Cu")
		(net "FLT_NET_HDD1")
	)
	(segment
		(start 225.0948 -452.653146)
		(end 225.123756 -452.682102)
		(width 0.111252)
		(layer "F.Cu")
		(net "FLT_HDD0")
	)
	(segment
		(start 225.123756 -452.682102)
		(end 226.698302 -452.682102)
		(width 0.111252)
		(layer "F.Cu")
		(net "FLT_HDD0")
	)
	(segment
		(start 226.698302 -452.682102)
		(end 226.769676 -452.753476)
		(width 0.111252)
		(layer "F.Cu")
		(net "FLT_HDD0")
	)
	(segment
		(start 225.0948 -451.1548)
		(end 225.0948 -452.653146)
		(width 0.111252)
		(layer "F.Cu")
		(net "FLT_HDD0")
	)
	(via
		(at 225.0948 -451.1548)
		(size 0.7112)
		(drill 0.3556)
		(layers "F.Cu" "B.Cu")
		(net "FLT_HDD0")
	)
	(segment
		(start 42.290746 -236.346746)
		(end 43.434 -237.49)
		(width 0.111252)
		(layer "F.Cu")
		(net "HDD_PRSNT12")
	)
	(segment
		(start 43.434 -237.49)
		(end 43.4594 -237.49)
		(width 0.111252)
		(layer "F.Cu")
		(net "HDD_PRSNT12")
	)
	(segment
		(start 42.290746 -234.216702)
		(end 42.290746 -236.346746)
		(width 0.111252)
		(layer "F.Cu")
		(net "HDD_PRSNT12")
	)
	(via
		(at 17.652746 -214.1093)
		(size 0.5588)
		(drill 0.3048)
		(layers "F.Cu" "B.Cu")
		(net "HDD_PRSNT12")
	)
	(via
		(at 43.4594 -237.49)
		(size 0.5588)
		(drill 0.3048)
		(layers "F.Cu" "B.Cu")
		(net "HDD_PRSNT12")
	)
	(via
		(at 14.045946 -214.4649)
		(size 0.7112)
		(drill 0.3556)
		(layers "F.Cu" "B.Cu")
		(net "HDD_PRSNT12")
	)
	(via
		(at 12.091416 -449.32727)
		(size 0.5588)
		(drill 0.3048)
		(layers "F.Cu" "B.Cu")
		(net "HDD_PRSNT12")
	)
	(via
		(at 27.965146 -447.00825)
		(size 0.5588)
		(drill 0.3048)
		(layers "F.Cu" "B.Cu")
		(net "HDD_PRSNT12")
	)
	(segment
		(start 10.96391 -449.504562)
		(end 10.965434 -449.506086)
		(width 0.111252)
		(layer "B.Cu")
		(net "HDD_PRSNT12")
	)
	(segment
		(start 14.261846 -214.6808)
		(end 17.081246 -214.6808)
		(width 0.111252)
		(layer "B.Cu")
		(net "HDD_PRSNT12")
	)
	(segment
		(start 24.438356 -444.529972)
		(end 19.858228 -449.1101)
		(width 0.111252)
		(layer "B.Cu")
		(net "HDD_PRSNT12")
	)
	(segment
		(start 11.914124 -449.504562)
		(end 12.091416 -449.32727)
		(width 0.111252)
		(layer "B.Cu")
		(net "HDD_PRSNT12")
	)
	(segment
		(start 13.538454 -214.972392)
		(end 12.088368 -214.972392)
		(width 0.111252)
		(layer "B.Cu")
		(net "HDD_PRSNT12")
	)
	(segment
		(start 27.965146 -446.73139)
		(end 25.763728 -444.529972)
		(width 0.111252)
		(layer "B.Cu")
		(net "HDD_PRSNT12")
	)
	(segment
		(start 19.858228 -449.1101)
		(end 12.308586 -449.1101)
		(width 0.111252)
		(layer "B.Cu")
		(net "HDD_PRSNT12")
	)
	(segment
		(start 25.763728 -444.529972)
		(end 24.438356 -444.529972)
		(width 0.111252)
		(layer "B.Cu")
		(net "HDD_PRSNT12")
	)
	(segment
		(start 14.045946 -214.4649)
		(end 13.538454 -214.972392)
		(width 0.111252)
		(layer "B.Cu")
		(net "HDD_PRSNT12")
	)
	(segment
		(start 27.965146 -447.00825)
		(end 27.965146 -446.73139)
		(width 0.111252)
		(layer "B.Cu")
		(net "HDD_PRSNT12")
	)
	(segment
		(start 11.620754 -214.504778)
		(end 2.80924 -214.504778)
		(width 0.111252)
		(layer "B.Cu")
		(net "HDD_PRSNT12")
	)
	(segment
		(start 10.965434 -449.506086)
		(end 11.348466 -449.506086)
		(width 0.111252)
		(layer "B.Cu")
		(net "HDD_PRSNT12")
	)
	(segment
		(start 11.348466 -449.506086)
		(end 11.34999 -449.504562)
		(width 0.111252)
		(layer "B.Cu")
		(net "HDD_PRSNT12")
	)
	(segment
		(start 11.34999 -449.504562)
		(end 11.914124 -449.504562)
		(width 0.111252)
		(layer "B.Cu")
		(net "HDD_PRSNT12")
	)
	(segment
		(start 12.088368 -214.972392)
		(end 11.620754 -214.504778)
		(width 0.111252)
		(layer "B.Cu")
		(net "HDD_PRSNT12")
	)
	(segment
		(start 14.045946 -214.4649)
		(end 14.261846 -214.6808)
		(width 0.111252)
		(layer "B.Cu")
		(net "HDD_PRSNT12")
	)
	(segment
		(start 2.80924 -449.504562)
		(end 10.96391 -449.504562)
		(width 0.111252)
		(layer "B.Cu")
		(net "HDD_PRSNT12")
	)
	(segment
		(start 12.308586 -449.1101)
		(end 12.091416 -449.32727)
		(width 0.111252)
		(layer "B.Cu")
		(net "HDD_PRSNT12")
	)
	(segment
		(start 17.081246 -214.6808)
		(end 17.652746 -214.1093)
		(width 0.111252)
		(layer "B.Cu")
		(net "HDD_PRSNT12")
	)
	(segment
		(start 17.036288 -425.43603)
		(end 21.55825 -420.914068)
		(width 0.14605)
		(layer "In2.Cu")
		(net "HDD_PRSNT12")
	)
	(segment
		(start 20.519898 -255.800098)
		(end 20.329652 -255.609852)
		(width 0.14605)
		(layer "In2.Cu")
		(net "HDD_PRSNT12")
	)
	(segment
		(start 22.056852 -352.860864)
		(end 18.36928 -349.173292)
		(width 0.14605)
		(layer "In2.Cu")
		(net "HDD_PRSNT12")
	)
	(segment
		(start 21.55825 -419.742874)
		(end 21.606002 -419.503098)
		(width 0.14605)
		(layer "In2.Cu")
		(net "HDD_PRSNT12")
	)
	(segment
		(start 18.25625 -361.228132)
		(end 22.056852 -357.42753)
		(width 0.14605)
		(layer "In2.Cu")
		(net "HDD_PRSNT12")
	)
	(segment
		(start 20.661122 -257.433572)
		(end 20.661376 -257.433318)
		(width 0.14605)
		(layer "In2.Cu")
		(net "HDD_PRSNT12")
	)
	(segment
		(start 12.091416 -449.32727)
		(end 17.036288 -444.382398)
		(width 0.14605)
		(layer "In2.Cu")
		(net "HDD_PRSNT12")
	)
	(segment
		(start 18.36928 -319.992502)
		(end 21.155152 -317.20663)
		(width 0.14605)
		(layer "In2.Cu")
		(net "HDD_PRSNT12")
	)
	(segment
		(start 20.5994 -302.857916)
		(end 20.5994 -302.813212)
		(width 0.14605)
		(layer "In2.Cu")
		(net "HDD_PRSNT12")
	)
	(segment
		(start 22.056852 -357.42753)
		(end 22.056852 -352.860864)
		(width 0.14605)
		(layer "In2.Cu")
		(net "HDD_PRSNT12")
	)
	(segment
		(start 18.36928 -349.173292)
		(end 18.36928 -319.992502)
		(width 0.14605)
		(layer "In2.Cu")
		(net "HDD_PRSNT12")
	)
	(segment
		(start 17.217898 -397.774414)
		(end 17.217898 -395.93774)
		(width 0.14605)
		(layer "In2.Cu")
		(net "HDD_PRSNT12")
	)
	(segment
		(start 20.311364 -302.435514)
		(end 19.840448 -301.964598)
		(width 0.14605)
		(layer "In2.Cu")
		(net "HDD_PRSNT12")
	)
	(segment
		(start 20.661376 -257.433318)
		(end 20.661376 -257.059938)
		(width 0.14605)
		(layer "In2.Cu")
		(net "HDD_PRSNT12")
	)
	(segment
		(start 21.606002 -419.15715)
		(end 21.55825 -418.917374)
		(width 0.14605)
		(layer "In2.Cu")
		(net "HDD_PRSNT12")
	)
	(segment
		(start 20.661122 -260.045708)
		(end 20.661122 -257.433572)
		(width 0.14605)
		(layer "In2.Cu")
		(net "HDD_PRSNT12")
	)
	(segment
		(start 18.25625 -377.037092)
		(end 18.25625 -361.228132)
		(width 0.14605)
		(layer "In2.Cu")
		(net "HDD_PRSNT12")
	)
	(segment
		(start 20.462748 -302.661574)
		(end 20.311364 -302.435514)
		(width 0.14605)
		(layer "In2.Cu")
		(net "HDD_PRSNT12")
	)
	(segment
		(start 17.125696 -397.866616)
		(end 17.217898 -397.774414)
		(width 0.14605)
		(layer "In2.Cu")
		(net "HDD_PRSNT12")
	)
	(segment
		(start 21.55825 -420.914068)
		(end 21.55825 -419.742874)
		(width 0.14605)
		(layer "In2.Cu")
		(net "HDD_PRSNT12")
	)
	(segment
		(start 17.962372 -395.193266)
		(end 17.962372 -377.33097)
		(width 0.14605)
		(layer "In2.Cu")
		(net "HDD_PRSNT12")
	)
	(segment
		(start 20.661376 -257.059938)
		(end 20.519898 -256.91846)
		(width 0.14605)
		(layer "In2.Cu")
		(net "HDD_PRSNT12")
	)
	(segment
		(start 20.329652 -255.609852)
		(end 20.298918 -255.609852)
		(width 0.14605)
		(layer "In2.Cu")
		(net "HDD_PRSNT12")
	)
	(segment
		(start 17.962372 -377.33097)
		(end 18.25625 -377.037092)
		(width 0.14605)
		(layer "In2.Cu")
		(net "HDD_PRSNT12")
	)
	(segment
		(start 20.017994 -255.328928)
		(end 20.017994 -253.34341)
		(width 0.14605)
		(layer "In2.Cu")
		(net "HDD_PRSNT12")
	)
	(segment
		(start 20.5994 -302.813212)
		(end 20.473162 -302.686974)
		(width 0.14605)
		(layer "In2.Cu")
		(net "HDD_PRSNT12")
	)
	(segment
		(start 17.036288 -444.382398)
		(end 17.036288 -425.43603)
		(width 0.14605)
		(layer "In2.Cu")
		(net "HDD_PRSNT12")
	)
	(segment
		(start 21.55825 -418.917374)
		(end 21.55825 -417.758118)
		(width 0.14605)
		(layer "In2.Cu")
		(net "HDD_PRSNT12")
	)
	(segment
		(start 17.125696 -413.325564)
		(end 17.125696 -397.866616)
		(width 0.14605)
		(layer "In2.Cu")
		(net "HDD_PRSNT12")
	)
	(segment
		(start 20.298918 -255.609852)
		(end 20.017994 -255.328928)
		(width 0.14605)
		(layer "In2.Cu")
		(net "HDD_PRSNT12")
	)
	(segment
		(start 20.017994 -253.34341)
		(end 17.449546 -250.774962)
		(width 0.14605)
		(layer "In2.Cu")
		(net "HDD_PRSNT12")
	)
	(segment
		(start 17.217898 -395.93774)
		(end 17.962372 -395.193266)
		(width 0.14605)
		(layer "In2.Cu")
		(net "HDD_PRSNT12")
	)
	(segment
		(start 20.473162 -302.686974)
		(end 20.462748 -302.661574)
		(width 0.14605)
		(layer "In2.Cu")
		(net "HDD_PRSNT12")
	)
	(segment
		(start 20.622514 -302.881284)
		(end 20.5994 -302.857916)
		(width 0.14605)
		(layer "In2.Cu")
		(net "HDD_PRSNT12")
	)
	(segment
		(start 17.449546 -214.3125)
		(end 17.652746 -214.1093)
		(width 0.14605)
		(layer "In2.Cu")
		(net "HDD_PRSNT12")
	)
	(segment
		(start 20.519898 -256.91846)
		(end 20.519898 -255.800098)
		(width 0.14605)
		(layer "In2.Cu")
		(net "HDD_PRSNT12")
	)
	(segment
		(start 21.155152 -303.413922)
		(end 20.622514 -302.881284)
		(width 0.14605)
		(layer "In2.Cu")
		(net "HDD_PRSNT12")
	)
	(segment
		(start 19.840448 -301.964598)
		(end 19.840448 -260.866382)
		(width 0.14605)
		(layer "In2.Cu")
		(net "HDD_PRSNT12")
	)
	(segment
		(start 19.840448 -260.866382)
		(end 20.661122 -260.045708)
		(width 0.14605)
		(layer "In2.Cu")
		(net "HDD_PRSNT12")
	)
	(segment
		(start 21.155152 -317.20663)
		(end 21.155152 -303.413922)
		(width 0.14605)
		(layer "In2.Cu")
		(net "HDD_PRSNT12")
	)
	(segment
		(start 17.449546 -250.774962)
		(end 17.449546 -214.3125)
		(width 0.14605)
		(layer "In2.Cu")
		(net "HDD_PRSNT12")
	)
	(segment
		(start 21.606002 -419.503098)
		(end 21.606002 -419.15715)
		(width 0.14605)
		(layer "In2.Cu")
		(net "HDD_PRSNT12")
	)
	(segment
		(start 21.55825 -417.758118)
		(end 17.125696 -413.325564)
		(width 0.14605)
		(layer "In2.Cu")
		(net "HDD_PRSNT12")
	)
	(segment
		(start 85.178646 -377.696476)
		(end 85.178646 -409.12288)
		(width 0.14605)
		(layer "In5.Cu")
		(net "HDD_PRSNT12")
	)
	(segment
		(start 79.182976 -271.731486)
		(end 85.178646 -277.727156)
		(width 0.14605)
		(layer "In5.Cu")
		(net "HDD_PRSNT12")
	)
	(segment
		(start 84.114894 -327.610724)
		(end 84.440522 -327.936352)
		(width 0.14605)
		(layer "In5.Cu")
		(net "HDD_PRSNT12")
	)
	(segment
		(start 47.293276 -447.00825)
		(end 27.965146 -447.00825)
		(width 0.14605)
		(layer "In5.Cu")
		(net "HDD_PRSNT12")
	)
	(segment
		(start 85.178646 -327.102724)
		(end 84.90077 -326.824848)
		(width 0.14605)
		(layer "In5.Cu")
		(net "HDD_PRSNT12")
	)
	(segment
		(start 85.178646 -327.658476)
		(end 85.178646 -330.684124)
		(width 0.14605)
		(layer "In5.Cu")
		(net "HDD_PRSNT12")
	)
	(segment
		(start 84.440522 -326.824848)
		(end 84.114894 -327.150476)
		(width 0.14605)
		(layer "In5.Cu")
		(net "HDD_PRSNT12")
	)
	(segment
		(start 84.90077 -327.936352)
		(end 85.178646 -327.658476)
		(width 0.14605)
		(layer "In5.Cu")
		(net "HDD_PRSNT12")
	)
	(segment
		(start 78.517242 -271.06499)
		(end 79.182976 -271.731486)
		(width 0.14605)
		(layer "In5.Cu")
		(net "HDD_PRSNT12")
	)
	(segment
		(start 85.178646 -409.12288)
		(end 47.293276 -447.00825)
		(width 0.14605)
		(layer "In5.Cu")
		(net "HDD_PRSNT12")
	)
	(segment
		(start 84.114894 -376.632724)
		(end 85.178646 -377.696476)
		(width 0.14605)
		(layer "In5.Cu")
		(net "HDD_PRSNT12")
	)
	(segment
		(start 84.90077 -323.262752)
		(end 85.178646 -322.984876)
		(width 0.14605)
		(layer "In5.Cu")
		(net "HDD_PRSNT12")
	)
	(segment
		(start 84.90077 -326.824848)
		(end 84.440522 -326.824848)
		(width 0.14605)
		(layer "In5.Cu")
		(net "HDD_PRSNT12")
	)
	(segment
		(start 78.517242 -271.023842)
		(end 78.517242 -271.06499)
		(width 0.14605)
		(layer "In5.Cu")
		(net "HDD_PRSNT12")
	)
	(segment
		(start 85.178646 -321.873372)
		(end 84.90077 -322.151248)
		(width 0.14605)
		(layer "In5.Cu")
		(net "HDD_PRSNT12")
	)
	(segment
		(start 84.440522 -322.151248)
		(end 84.114894 -322.476876)
		(width 0.14605)
		(layer "In5.Cu")
		(net "HDD_PRSNT12")
	)
	(segment
		(start 84.114894 -331.747876)
		(end 84.114894 -376.632724)
		(width 0.14605)
		(layer "In5.Cu")
		(net "HDD_PRSNT12")
	)
	(segment
		(start 85.178646 -330.684124)
		(end 84.114894 -331.747876)
		(width 0.14605)
		(layer "In5.Cu")
		(net "HDD_PRSNT12")
	)
	(segment
		(start 84.114894 -327.150476)
		(end 84.114894 -327.610724)
		(width 0.14605)
		(layer "In5.Cu")
		(net "HDD_PRSNT12")
	)
	(segment
		(start 84.440522 -323.262752)
		(end 84.90077 -323.262752)
		(width 0.14605)
		(layer "In5.Cu")
		(net "HDD_PRSNT12")
	)
	(segment
		(start 84.114894 -322.476876)
		(end 84.114894 -322.937124)
		(width 0.14605)
		(layer "In5.Cu")
		(net "HDD_PRSNT12")
	)
	(segment
		(start 85.178646 -322.984876)
		(end 85.178646 -327.102724)
		(width 0.14605)
		(layer "In5.Cu")
		(net "HDD_PRSNT12")
	)
	(segment
		(start 85.178646 -277.727156)
		(end 85.178646 -321.873372)
		(width 0.14605)
		(layer "In5.Cu")
		(net "HDD_PRSNT12")
	)
	(segment
		(start 44.9834 -237.49)
		(end 78.517242 -271.023842)
		(width 0.14605)
		(layer "In5.Cu")
		(net "HDD_PRSNT12")
	)
	(segment
		(start 84.90077 -322.151248)
		(end 84.440522 -322.151248)
		(width 0.14605)
		(layer "In5.Cu")
		(net "HDD_PRSNT12")
	)
	(segment
		(start 84.114894 -322.937124)
		(end 84.440522 -323.262752)
		(width 0.14605)
		(layer "In5.Cu")
		(net "HDD_PRSNT12")
	)
	(segment
		(start 84.440522 -327.936352)
		(end 84.90077 -327.936352)
		(width 0.14605)
		(layer "In5.Cu")
		(net "HDD_PRSNT12")
	)
	(segment
		(start 43.4594 -237.49)
		(end 44.9834 -237.49)
		(width 0.14605)
		(layer "In5.Cu")
		(net "HDD_PRSNT12")
	)
	(segment
		(start 25.729946 -32.3215)
		(end 26.358596 -32.3215)
		(width 0.09525)
		(layer "F.Cu")
		(net "SAS2X28_DRIVE_RX_P_B14")
	)
	(segment
		(start 20.089876 -29.809948)
		(end 20.093178 -29.806646)
		(width 0.09525)
		(layer "F.Cu")
		(net "SAS2X28_DRIVE_RX_P_B14")
	)
	(segment
		(start 26.477722 -32.272224)
		(end 26.733246 -32.0167)
		(width 0.09525)
		(layer "F.Cu")
		(net "SAS2X28_DRIVE_RX_P_B14")
	)
	(segment
		(start 19.600164 -29.809948)
		(end 20.089876 -29.809948)
		(width 0.09525)
		(layer "F.Cu")
		(net "SAS2X28_DRIVE_RX_P_B14")
	)
	(segment
		(start 20.733766 -30.072076)
		(end 24.358346 -30.072076)
		(width 0.09525)
		(layer "F.Cu")
		(net "SAS2X28_DRIVE_RX_P_B14")
	)
	(segment
		(start 25.501346 -31.215076)
		(end 25.501346 -32.0929)
		(width 0.09525)
		(layer "F.Cu")
		(net "SAS2X28_DRIVE_RX_P_B14")
	)
	(arc
		(start 25.501346 -32.0929)
		(mid 25.568301 -32.254545)
		(end 25.729946 -32.3215)
		(width 0.09525)
		(layer "F.Cu")
		(net "SAS2X28_DRIVE_RX_P_B14")
	)
	(arc
		(start 20.522946 -29.9847)
		(mid 20.619671 -30.04933)
		(end 20.733766 -30.072076)
		(width 0.09525)
		(layer "F.Cu")
		(net "SAS2X28_DRIVE_RX_P_B14")
	)
	(arc
		(start 26.358596 -32.3215)
		(mid 26.423055 -32.308696)
		(end 26.477722 -32.272224)
		(width 0.09525)
		(layer "F.Cu")
		(net "SAS2X28_DRIVE_RX_P_B14")
	)
	(arc
		(start 24.358346 -30.072076)
		(mid 25.166569 -30.406853)
		(end 25.501346 -31.215076)
		(width 0.09525)
		(layer "F.Cu")
		(net "SAS2X28_DRIVE_RX_P_B14")
	)
	(arc
		(start 20.093178 -29.806646)
		(mid 20.325781 -29.852914)
		(end 20.522946 -29.9847)
		(width 0.09525)
		(layer "F.Cu")
		(net "SAS2X28_DRIVE_RX_P_B14")
	)
	(segment
		(start 27.62758 -235.858812)
		(end 27.711146 -235.7755)
		(width 0.09525)
		(layer "F.Cu")
		(net "SAS2X28_B_HDD12_RX_+")
	)
	(segment
		(start 26.23693 -235.709206)
		(end 26.246074 -235.718604)
		(width 0.09525)
		(layer "F.Cu")
		(net "SAS2X28_B_HDD12_RX_+")
	)
	(segment
		(start 26.898346 -235.988606)
		(end 27.314652 -235.988606)
		(width 0.09525)
		(layer "F.Cu")
		(net "SAS2X28_B_HDD12_RX_+")
	)
	(via
		(at 27.711146 -235.7755)
		(size 0.5588)
		(drill 0.3048)
		(layers "F.Cu" "B.Cu")
		(net "SAS2X28_B_HDD12_RX_+")
	)
	(arc
		(start 27.314652 -235.988606)
		(mid 27.484021 -235.954823)
		(end 27.62758 -235.858812)
		(width 0.09525)
		(layer "F.Cu")
		(net "SAS2X28_B_HDD12_RX_+")
	)
	(arc
		(start 26.805128 -235.98378)
		(mid 26.851676 -235.987373)
		(end 26.898346 -235.988606)
		(width 0.09525)
		(layer "F.Cu")
		(net "SAS2X28_B_HDD12_RX_+")
	)
	(arc
		(start 26.246074 -235.718604)
		(mid 26.502696 -235.899492)
		(end 26.805128 -235.98378)
		(width 0.09525)
		(layer "F.Cu")
		(net "SAS2X28_B_HDD12_RX_+")
	)
	(segment
		(start 26.961592 -190.8175)
		(end 26.961846 -190.817754)
		(width 0.09525)
		(layer "B.Cu")
		(net "SAS2X28_B_HDD12_RX_+")
	)
	(segment
		(start 26.961846 -190.817754)
		(end 26.961846 -232.20807)
		(width 0.09525)
		(layer "B.Cu")
		(net "SAS2X28_B_HDD12_RX_+")
	)
	(segment
		(start 26.961592 -189.594998)
		(end 26.961592 -190.8175)
		(width 0.09525)
		(layer "B.Cu")
		(net "SAS2X28_B_HDD12_RX_+")
	)
	(segment
		(start 4.867148 -167.498776)
		(end 4.868672 -167.5003)
		(width 0.09525)
		(layer "B.Cu")
		(net "SAS2X28_B_HDD12_RX_+")
	)
	(segment
		(start 5.665724 -167.8305)
		(end 10.210546 -167.8305)
		(width 0.09525)
		(layer "B.Cu")
		(net "SAS2X28_B_HDD12_RX_+")
	)
	(segment
		(start 2.811526 -167.498776)
		(end 4.867148 -167.498776)
		(width 0.09525)
		(layer "B.Cu")
		(net "SAS2X28_B_HDD12_RX_+")
	)
	(segment
		(start 11.683746 -169.3037)
		(end 11.683746 -172.327316)
		(width 0.09525)
		(layer "B.Cu")
		(net "SAS2X28_B_HDD12_RX_+")
	)
	(segment
		(start 12.509246 -174.3202)
		(end 26.380694 -188.191648)
		(width 0.09525)
		(layer "B.Cu")
		(net "SAS2X28_B_HDD12_RX_+")
	)
	(segment
		(start 27.194256 -232.67289)
		(end 27.194256 -232.95864)
		(width 0.09525)
		(layer "B.Cu")
		(net "SAS2X28_B_HDD12_RX_+")
	)
	(segment
		(start 26.961846 -233.42346)
		(end 26.961846 -235.78947)
		(width 0.09525)
		(layer "B.Cu")
		(net "SAS2X28_B_HDD12_RX_+")
	)
	(segment
		(start 27.173428 -236.0549)
		(end 27.279346 -236.0549)
		(width 0.09525)
		(layer "B.Cu")
		(net "SAS2X28_B_HDD12_RX_+")
	)
	(segment
		(start 26.380694 -188.191648)
		(end 26.38044 -188.191902)
		(width 0.09525)
		(layer "B.Cu")
		(net "SAS2X28_B_HDD12_RX_+")
	)
	(segment
		(start 27.539696 -235.947204)
		(end 27.711146 -235.7755)
		(width 0.09525)
		(layer "B.Cu")
		(net "SAS2X28_B_HDD12_RX_+")
	)
	(arc
		(start 26.961846 -235.78947)
		(mid 26.984951 -235.905626)
		(end 27.050746 -236.0041)
		(width 0.09525)
		(layer "B.Cu")
		(net "SAS2X28_B_HDD12_RX_+")
	)
	(arc
		(start 26.961846 -232.20807)
		(mid 26.991643 -232.338388)
		(end 27.077924 -232.44048)
		(width 0.09525)
		(layer "B.Cu")
		(net "SAS2X28_B_HDD12_RX_+")
	)
	(arc
		(start 27.050746 -236.0041)
		(mid 27.107033 -236.04171)
		(end 27.173428 -236.0549)
		(width 0.09525)
		(layer "B.Cu")
		(net "SAS2X28_B_HDD12_RX_+")
	)
	(arc
		(start 27.077924 -233.19105)
		(mid 26.991693 -233.293167)
		(end 26.961846 -233.42346)
		(width 0.09525)
		(layer "B.Cu")
		(net "SAS2X28_B_HDD12_RX_+")
	)
	(arc
		(start 10.210546 -167.8305)
		(mid 11.252256 -168.26199)
		(end 11.683746 -169.3037)
		(width 0.09525)
		(layer "B.Cu")
		(net "SAS2X28_B_HDD12_RX_+")
	)
	(arc
		(start 27.279346 -236.0549)
		(mid 27.420245 -236.026967)
		(end 27.539696 -235.947204)
		(width 0.09525)
		(layer "B.Cu")
		(net "SAS2X28_B_HDD12_RX_+")
	)
	(arc
		(start 27.194256 -232.95864)
		(mid 27.16432 -233.088975)
		(end 27.077924 -233.19105)
		(width 0.09525)
		(layer "B.Cu")
		(net "SAS2X28_B_HDD12_RX_+")
	)
	(arc
		(start 27.077924 -232.44048)
		(mid 27.164323 -232.542554)
		(end 27.194256 -232.67289)
		(width 0.09525)
		(layer "B.Cu")
		(net "SAS2X28_B_HDD12_RX_+")
	)
	(arc
		(start 11.683746 -172.327316)
		(mid 11.898283 -173.405865)
		(end 12.509246 -174.3202)
		(width 0.09525)
		(layer "B.Cu")
		(net "SAS2X28_B_HDD12_RX_+")
	)
	(arc
		(start 5.359146 -167.7035)
		(mid 5.499805 -167.797485)
		(end 5.665724 -167.8305)
		(width 0.09525)
		(layer "B.Cu")
		(net "SAS2X28_B_HDD12_RX_+")
	)
	(arc
		(start 26.38044 -188.191902)
		(mid 26.810548 -188.835649)
		(end 26.961592 -189.594998)
		(width 0.09525)
		(layer "B.Cu")
		(net "SAS2X28_B_HDD12_RX_+")
	)
	(arc
		(start 4.868672 -167.5003)
		(mid 5.13413 -167.553103)
		(end 5.359146 -167.7035)
		(width 0.09525)
		(layer "B.Cu")
		(net "SAS2X28_B_HDD12_RX_+")
	)
	(segment
		(start 21.080476 -238.4425)
		(end 21.486368 -238.4425)
		(width 0.09525)
		(layer "F.Cu")
		(net "SAS2X28_B_HDD12_TX_-")
	)
	(segment
		(start 19.600164 -238.21009)
		(end 20.508214 -238.21009)
		(width 0.09525)
		(layer "F.Cu")
		(net "SAS2X28_B_HDD12_TX_-")
	)
	(segment
		(start 6.349746 -170.160696)
		(end 5.610098 -170.160696)
		(width 0.09525)
		(layer "F.Cu")
		(net "SAS2X28_B_HDD12_TX_-")
	)
	(segment
		(start 20.508214 -238.21009)
		(end 20.511516 -238.206788)
		(width 0.09525)
		(layer "F.Cu")
		(net "SAS2X28_B_HDD12_TX_-")
	)
	(segment
		(start 7.032498 -170.459654)
		(end 7.005066 -170.431968)
		(width 0.09525)
		(layer "F.Cu")
		(net "SAS2X28_B_HDD12_TX_-")
	)
	(segment
		(start 4.951476 -170.49877)
		(end 3.192526 -170.49877)
		(width 0.09525)
		(layer "F.Cu")
		(net "SAS2X28_B_HDD12_TX_-")
	)
	(segment
		(start 21.792946 -238.3155)
		(end 21.83765 -238.270796)
		(width 0.09525)
		(layer "F.Cu")
		(net "SAS2X28_B_HDD12_TX_-")
	)
	(segment
		(start 5.26415 -170.303952)
		(end 5.148834 -170.419014)
		(width 0.09525)
		(layer "F.Cu")
		(net "SAS2X28_B_HDD12_TX_-")
	)
	(segment
		(start 4.953 -170.500294)
		(end 4.951476 -170.49877)
		(width 0.09525)
		(layer "F.Cu")
		(net "SAS2X28_B_HDD12_TX_-")
	)
	(via
		(at 21.945346 -238.0107)
		(size 0.5588)
		(drill 0.3048)
		(layers "F.Cu" "B.Cu")
		(net "SAS2X28_B_HDD12_TX_-")
	)
	(via
		(at 7.032498 -170.459654)
		(size 0.5588)
		(drill 0.3048)
		(layers "F.Cu" "B.Cu")
		(net "SAS2X28_B_HDD12_TX_-")
	)
	(arc
		(start 20.511516 -238.206788)
		(mid 20.703295 -238.244935)
		(end 20.865846 -238.3536)
		(width 0.09525)
		(layer "F.Cu")
		(net "SAS2X28_B_HDD12_TX_-")
	)
	(arc
		(start 21.83765 -238.270796)
		(mid 21.917332 -238.151449)
		(end 21.945346 -238.0107)
		(width 0.09525)
		(layer "F.Cu")
		(net "SAS2X28_B_HDD12_TX_-")
	)
	(arc
		(start 7.005066 -170.431968)
		(mid 6.704388 -170.231154)
		(end 6.349746 -170.160696)
		(width 0.09525)
		(layer "F.Cu")
		(net "SAS2X28_B_HDD12_TX_-")
	)
	(arc
		(start 5.148834 -170.419014)
		(mid 5.059 -170.479132)
		(end 4.953 -170.500294)
		(width 0.09525)
		(layer "F.Cu")
		(net "SAS2X28_B_HDD12_TX_-")
	)
	(arc
		(start 21.486368 -238.4425)
		(mid 21.652291 -238.409496)
		(end 21.792946 -238.3155)
		(width 0.09525)
		(layer "F.Cu")
		(net "SAS2X28_B_HDD12_TX_-")
	)
	(arc
		(start 5.610098 -170.160696)
		(mid 5.422888 -170.197934)
		(end 5.26415 -170.303952)
		(width 0.09525)
		(layer "F.Cu")
		(net "SAS2X28_B_HDD12_TX_-")
	)
	(arc
		(start 20.865846 -238.3536)
		(mid 20.964319 -238.419398)
		(end 21.080476 -238.4425)
		(width 0.09525)
		(layer "F.Cu")
		(net "SAS2X28_B_HDD12_TX_-")
	)
	(segment
		(start 25.691846 -230.429816)
		(end 25.691846 -230.715566)
		(width 0.09525)
		(layer "B.Cu")
		(net "SAS2X28_B_HDD12_TX_-")
	)
	(segment
		(start 25.374346 -236.0041)
		(end 23.177246 -238.2012)
		(width 0.09525)
		(layer "B.Cu")
		(net "SAS2X28_B_HDD12_TX_-")
	)
	(segment
		(start 10.794492 -177.177446)
		(end 25.069546 -191.4525)
		(width 0.09525)
		(layer "B.Cu")
		(net "SAS2X28_B_HDD12_TX_-")
	)
	(segment
		(start 9.702546 -171.0817)
		(end 9.702546 -174.54118)
		(width 0.09525)
		(layer "B.Cu")
		(net "SAS2X28_B_HDD12_TX_-")
	)
	(segment
		(start 25.691846 -231.930956)
		(end 25.691846 -232.216706)
		(width 0.09525)
		(layer "B.Cu")
		(net "SAS2X28_B_HDD12_TX_-")
	)
	(segment
		(start 25.459436 -229.679246)
		(end 25.459436 -229.964996)
		(width 0.09525)
		(layer "B.Cu")
		(net "SAS2X28_B_HDD12_TX_-")
	)
	(segment
		(start 10.794746 -177.177446)
		(end 10.794492 -177.177446)
		(width 0.09525)
		(layer "B.Cu")
		(net "SAS2X28_B_HDD12_TX_-")
	)
	(segment
		(start 22.672548 -238.410242)
		(end 22.112732 -238.410242)
		(width 0.09525)
		(layer "B.Cu")
		(net "SAS2X28_B_HDD12_TX_-")
	)
	(segment
		(start 25.459436 -232.681526)
		(end 25.459436 -232.967276)
		(width 0.09525)
		(layer "B.Cu")
		(net "SAS2X28_B_HDD12_TX_-")
	)
	(segment
		(start 25.691846 -233.432096)
		(end 25.691846 -235.237528)
		(width 0.09525)
		(layer "B.Cu")
		(net "SAS2X28_B_HDD12_TX_-")
	)
	(segment
		(start 25.691846 -192.95491)
		(end 25.691846 -204.384148)
		(width 0.09525)
		(layer "B.Cu")
		(net "SAS2X28_B_HDD12_TX_-")
	)
	(segment
		(start 7.493 -170.2689)
		(end 8.889746 -170.2689)
		(width 0.09525)
		(layer "B.Cu")
		(net "SAS2X28_B_HDD12_TX_-")
	)
	(segment
		(start 25.459436 -231.180386)
		(end 25.459436 -231.466136)
		(width 0.09525)
		(layer "B.Cu")
		(net "SAS2X28_B_HDD12_TX_-")
	)
	(segment
		(start 25.459436 -204.848968)
		(end 25.459436 -205.134718)
		(width 0.09525)
		(layer "B.Cu")
		(net "SAS2X28_B_HDD12_TX_-")
	)
	(segment
		(start 25.691846 -205.599538)
		(end 25.691846 -229.214426)
		(width 0.09525)
		(layer "B.Cu")
		(net "SAS2X28_B_HDD12_TX_-")
	)
	(arc
		(start 25.459436 -205.134718)
		(mid 25.489372 -205.265053)
		(end 25.575768 -205.367128)
		(width 0.09525)
		(layer "B.Cu")
		(net "SAS2X28_B_HDD12_TX_-")
	)
	(arc
		(start 7.032498 -170.459654)
		(mid 7.243778 -170.318481)
		(end 7.493 -170.2689)
		(width 0.09525)
		(layer "B.Cu")
		(net "SAS2X28_B_HDD12_TX_-")
	)
	(arc
		(start 21.945346 -238.3409)
		(mid 21.876959 -238.1758)
		(end 21.945346 -238.0107)
		(width 0.09525)
		(layer "B.Cu")
		(net "SAS2X28_B_HDD12_TX_-")
	)
	(arc
		(start 25.691846 -232.216706)
		(mid 25.662049 -232.347024)
		(end 25.575768 -232.449116)
		(width 0.09525)
		(layer "B.Cu")
		(net "SAS2X28_B_HDD12_TX_-")
	)
	(arc
		(start 25.575768 -232.449116)
		(mid 25.489369 -232.55119)
		(end 25.459436 -232.681526)
		(width 0.09525)
		(layer "B.Cu")
		(net "SAS2X28_B_HDD12_TX_-")
	)
	(arc
		(start 8.889746 -170.2689)
		(mid 9.464482 -170.506964)
		(end 9.702546 -171.0817)
		(width 0.09525)
		(layer "B.Cu")
		(net "SAS2X28_B_HDD12_TX_-")
	)
	(arc
		(start 10.285984 -176.543208)
		(mid 10.523023 -176.874238)
		(end 10.794746 -177.177446)
		(width 0.09525)
		(layer "B.Cu")
		(net "SAS2X28_B_HDD12_TX_-")
	)
	(arc
		(start 25.691846 -229.214426)
		(mid 25.662049 -229.344744)
		(end 25.575768 -229.446836)
		(width 0.09525)
		(layer "B.Cu")
		(net "SAS2X28_B_HDD12_TX_-")
	)
	(arc
		(start 22.112732 -238.410242)
		(mid 22.02214 -238.392222)
		(end 21.945346 -238.3409)
		(width 0.09525)
		(layer "B.Cu")
		(net "SAS2X28_B_HDD12_TX_-")
	)
	(arc
		(start 25.459436 -229.964996)
		(mid 25.489372 -230.095331)
		(end 25.575768 -230.197406)
		(width 0.09525)
		(layer "B.Cu")
		(net "SAS2X28_B_HDD12_TX_-")
	)
	(arc
		(start 9.702546 -174.54118)
		(mid 9.851435 -175.583822)
		(end 10.285984 -176.543208)
		(width 0.09525)
		(layer "B.Cu")
		(net "SAS2X28_B_HDD12_TX_-")
	)
	(arc
		(start 25.691846 -204.384148)
		(mid 25.662049 -204.514466)
		(end 25.575768 -204.616558)
		(width 0.09525)
		(layer "B.Cu")
		(net "SAS2X28_B_HDD12_TX_-")
	)
	(arc
		(start 23.177246 -238.2012)
		(mid 22.945689 -238.355922)
		(end 22.672548 -238.410242)
		(width 0.09525)
		(layer "B.Cu")
		(net "SAS2X28_B_HDD12_TX_-")
	)
	(arc
		(start 25.575768 -204.616558)
		(mid 25.489369 -204.718632)
		(end 25.459436 -204.848968)
		(width 0.09525)
		(layer "B.Cu")
		(net "SAS2X28_B_HDD12_TX_-")
	)
	(arc
		(start 25.691846 -235.237528)
		(mid 25.609326 -235.652384)
		(end 25.374346 -236.0041)
		(width 0.09525)
		(layer "B.Cu")
		(net "SAS2X28_B_HDD12_TX_-")
	)
	(arc
		(start 25.575768 -230.197406)
		(mid 25.661999 -230.299523)
		(end 25.691846 -230.429816)
		(width 0.09525)
		(layer "B.Cu")
		(net "SAS2X28_B_HDD12_TX_-")
	)
	(arc
		(start 25.575768 -231.698546)
		(mid 25.661999 -231.800663)
		(end 25.691846 -231.930956)
		(width 0.09525)
		(layer "B.Cu")
		(net "SAS2X28_B_HDD12_TX_-")
	)
	(arc
		(start 25.069546 -191.4525)
		(mid 25.530129 -192.141812)
		(end 25.691846 -192.95491)
		(width 0.09525)
		(layer "B.Cu")
		(net "SAS2X28_B_HDD12_TX_-")
	)
	(arc
		(start 25.459436 -232.967276)
		(mid 25.489372 -233.097611)
		(end 25.575768 -233.199686)
		(width 0.09525)
		(layer "B.Cu")
		(net "SAS2X28_B_HDD12_TX_-")
	)
	(arc
		(start 25.575768 -205.367128)
		(mid 25.661999 -205.469245)
		(end 25.691846 -205.599538)
		(width 0.09525)
		(layer "B.Cu")
		(net "SAS2X28_B_HDD12_TX_-")
	)
	(arc
		(start 25.691846 -230.715566)
		(mid 25.662049 -230.845884)
		(end 25.575768 -230.947976)
		(width 0.09525)
		(layer "B.Cu")
		(net "SAS2X28_B_HDD12_TX_-")
	)
	(arc
		(start 25.575768 -233.199686)
		(mid 25.661999 -233.301803)
		(end 25.691846 -233.432096)
		(width 0.09525)
		(layer "B.Cu")
		(net "SAS2X28_B_HDD12_TX_-")
	)
	(arc
		(start 25.575768 -230.947976)
		(mid 25.489369 -231.05005)
		(end 25.459436 -231.180386)
		(width 0.09525)
		(layer "B.Cu")
		(net "SAS2X28_B_HDD12_TX_-")
	)
	(arc
		(start 25.575768 -229.446836)
		(mid 25.489369 -229.54891)
		(end 25.459436 -229.679246)
		(width 0.09525)
		(layer "B.Cu")
		(net "SAS2X28_B_HDD12_TX_-")
	)
	(arc
		(start 25.459436 -231.466136)
		(mid 25.489372 -231.596471)
		(end 25.575768 -231.698546)
		(width 0.09525)
		(layer "B.Cu")
		(net "SAS2X28_B_HDD12_TX_-")
	)
	(segment
		(start 20.54987 -132.809996)
		(end 20.553172 -132.806694)
		(width 0.09525)
		(layer "F.Cu")
		(net "SAS2X28_DRIVE_RX_P_B13")
	)
	(segment
		(start 19.600164 -132.809996)
		(end 20.54987 -132.809996)
		(width 0.09525)
		(layer "F.Cu")
		(net "SAS2X28_DRIVE_RX_P_B13")
	)
	(segment
		(start 21.282406 -133.1087)
		(end 24.745696 -133.1087)
		(width 0.09525)
		(layer "F.Cu")
		(net "SAS2X28_DRIVE_RX_P_B13")
	)
	(arc
		(start 20.853146 -132.9309)
		(mid 21.013669 -133.045982)
		(end 21.20265 -133.103366)
		(width 0.09525)
		(layer "F.Cu")
		(net "SAS2X28_DRIVE_RX_P_B13")
	)
	(arc
		(start 24.745696 -133.1087)
		(mid 25.264072 -133.005589)
		(end 25.70353 -132.711952)
		(width 0.09525)
		(layer "F.Cu")
		(net "SAS2X28_DRIVE_RX_P_B13")
	)
	(arc
		(start 20.553172 -132.806694)
		(mid 20.715499 -132.838983)
		(end 20.853146 -132.9309)
		(width 0.09525)
		(layer "F.Cu")
		(net "SAS2X28_DRIVE_RX_P_B13")
	)
	(arc
		(start 21.20265 -133.103366)
		(mid 21.24244 -133.107345)
		(end 21.282406 -133.1087)
		(width 0.09525)
		(layer "F.Cu")
		(net "SAS2X28_DRIVE_RX_P_B13")
	)
	(segment
		(start 25.092406 -235.709206)
		(end 25.34793 -235.709206)
		(width 0.09525)
		(layer "F.Cu")
		(net "SAS2X28_DRIVE_RX_P_B12")
	)
	(segment
		(start 21.189188 -235.988606)
		(end 24.417782 -235.988606)
		(width 0.09525)
		(layer "F.Cu")
		(net "SAS2X28_DRIVE_RX_P_B12")
	)
	(segment
		(start 19.600164 -235.810044)
		(end 20.586192 -235.810044)
		(width 0.09525)
		(layer "F.Cu")
		(net "SAS2X28_DRIVE_RX_P_B12")
	)
	(arc
		(start 20.586192 -235.810044)
		(mid 20.755728 -235.834616)
		(end 20.911312 -235.90631)
		(width 0.09525)
		(layer "F.Cu")
		(net "SAS2X28_DRIVE_RX_P_B12")
	)
	(arc
		(start 24.417782 -235.988606)
		(mid 24.600327 -235.952296)
		(end 24.755094 -235.848906)
		(width 0.09525)
		(layer "F.Cu")
		(net "SAS2X28_DRIVE_RX_P_B12")
	)
	(arc
		(start 24.755094 -235.848906)
		(mid 24.909854 -235.745499)
		(end 25.092406 -235.709206)
		(width 0.09525)
		(layer "F.Cu")
		(net "SAS2X28_DRIVE_RX_P_B12")
	)
	(arc
		(start 20.911312 -235.90631)
		(mid 21.044287 -235.967605)
		(end 21.189188 -235.988606)
		(width 0.09525)
		(layer "F.Cu")
		(net "SAS2X28_DRIVE_RX_P_B12")
	)
	(segment
		(start 26.23693 -236.598206)
		(end 26.33599 -236.499146)
		(width 0.09525)
		(layer "F.Cu")
		(net "SAS2X28_B_HDD12_RX_-")
	)
	(segment
		(start 26.771346 -236.318806)
		(end 27.45994 -236.318806)
		(width 0.09525)
		(layer "F.Cu")
		(net "SAS2X28_B_HDD12_RX_-")
	)
	(segment
		(start 27.64663 -236.57179)
		(end 27.64663 -236.640878)
		(width 0.09525)
		(layer "F.Cu")
		(net "SAS2X28_B_HDD12_RX_-")
	)
	(via
		(at 27.64663 -236.640878)
		(size 0.5588)
		(drill 0.3048)
		(layers "F.Cu" "B.Cu")
		(net "SAS2X28_B_HDD12_RX_-")
	)
	(arc
		(start 26.33599 -236.499146)
		(mid 26.535733 -236.365682)
		(end 26.771346 -236.318806)
		(width 0.09525)
		(layer "F.Cu")
		(net "SAS2X28_B_HDD12_RX_-")
	)
	(arc
		(start 27.558746 -236.3597)
		(mid 27.623765 -236.457008)
		(end 27.64663 -236.57179)
		(width 0.09525)
		(layer "F.Cu")
		(net "SAS2X28_B_HDD12_RX_-")
	)
	(arc
		(start 27.45994 -236.318806)
		(mid 27.513401 -236.32944)
		(end 27.558746 -236.3597)
		(width 0.09525)
		(layer "F.Cu")
		(net "SAS2X28_B_HDD12_RX_-")
	)
	(segment
		(start 2.81305 -168.500298)
		(end 2.811526 -168.498774)
		(width 0.09525)
		(layer "B.Cu")
		(net "SAS2X28_B_HDD12_RX_-")
	)
	(segment
		(start 11.353546 -172.32757)
		(end 11.353546 -169.3037)
		(width 0.09525)
		(layer "B.Cu")
		(net "SAS2X28_B_HDD12_RX_-")
	)
	(segment
		(start 27.279346 -236.3851)
		(end 27.173682 -236.3851)
		(width 0.09525)
		(layer "B.Cu")
		(net "SAS2X28_B_HDD12_RX_-")
	)
	(segment
		(start 12.275566 -174.55388)
		(end 12.27582 -174.553626)
		(width 0.09525)
		(layer "B.Cu")
		(net "SAS2X28_B_HDD12_RX_-")
	)
	(segment
		(start 5.512054 -168.252648)
		(end 5.420106 -168.34485)
		(width 0.09525)
		(layer "B.Cu")
		(net "SAS2X28_B_HDD12_RX_-")
	)
	(segment
		(start 26.631392 -190.954406)
		(end 26.631392 -189.594744)
		(width 0.09525)
		(layer "B.Cu")
		(net "SAS2X28_B_HDD12_RX_-")
	)
	(segment
		(start 26.631646 -190.95466)
		(end 26.631392 -190.954406)
		(width 0.09525)
		(layer "B.Cu")
		(net "SAS2X28_B_HDD12_RX_-")
	)
	(segment
		(start 10.210546 -168.1607)
		(end 5.734558 -168.1607)
		(width 0.09525)
		(layer "B.Cu")
		(net "SAS2X28_B_HDD12_RX_-")
	)
	(segment
		(start 5.044948 -168.500298)
		(end 2.81305 -168.500298)
		(width 0.09525)
		(layer "B.Cu")
		(net "SAS2X28_B_HDD12_RX_-")
	)
	(segment
		(start 26.631646 -235.78947)
		(end 26.631646 -190.95466)
		(width 0.09525)
		(layer "B.Cu")
		(net "SAS2X28_B_HDD12_RX_-")
	)
	(segment
		(start 26.147014 -188.425328)
		(end 12.275566 -174.55388)
		(width 0.09525)
		(layer "B.Cu")
		(net "SAS2X28_B_HDD12_RX_-")
	)
	(segment
		(start 27.64663 -236.640878)
		(end 27.469846 -236.46384)
		(width 0.09525)
		(layer "B.Cu")
		(net "SAS2X28_B_HDD12_RX_-")
	)
	(arc
		(start 26.631392 -189.594744)
		(mid 26.505504 -188.961864)
		(end 26.147014 -188.425328)
		(width 0.09525)
		(layer "B.Cu")
		(net "SAS2X28_B_HDD12_RX_-")
	)
	(arc
		(start 12.27582 -174.553626)
		(mid 11.593281 -173.532319)
		(end 11.353546 -172.32757)
		(width 0.09525)
		(layer "B.Cu")
		(net "SAS2X28_B_HDD12_RX_-")
	)
	(arc
		(start 27.173682 -236.3851)
		(mid 26.980727 -236.346906)
		(end 26.817066 -236.23778)
		(width 0.09525)
		(layer "B.Cu")
		(net "SAS2X28_B_HDD12_RX_-")
	)
	(arc
		(start 27.469846 -236.46384)
		(mid 27.382429 -236.405523)
		(end 27.279346 -236.3851)
		(width 0.09525)
		(layer "B.Cu")
		(net "SAS2X28_B_HDD12_RX_-")
	)
	(arc
		(start 5.734558 -168.1607)
		(mid 5.614169 -168.184553)
		(end 5.512054 -168.252648)
		(width 0.09525)
		(layer "B.Cu")
		(net "SAS2X28_B_HDD12_RX_-")
	)
	(arc
		(start 26.817066 -236.23778)
		(mid 26.679767 -236.032064)
		(end 26.631646 -235.78947)
		(width 0.09525)
		(layer "B.Cu")
		(net "SAS2X28_B_HDD12_RX_-")
	)
	(arc
		(start 11.353546 -169.3037)
		(mid 11.018769 -168.495477)
		(end 10.210546 -168.1607)
		(width 0.09525)
		(layer "B.Cu")
		(net "SAS2X28_B_HDD12_RX_-")
	)
	(arc
		(start 5.420106 -168.34485)
		(mid 5.247982 -168.45986)
		(end 5.044948 -168.500298)
		(width 0.09525)
		(layer "B.Cu")
		(net "SAS2X28_B_HDD12_RX_-")
	)
	(segment
		(start 6.349746 -169.830496)
		(end 5.540502 -169.830496)
		(width 0.09525)
		(layer "F.Cu")
		(net "SAS2X28_B_HDD12_TX_+")
	)
	(segment
		(start 7.032498 -169.531538)
		(end 7.005066 -169.559224)
		(width 0.09525)
		(layer "F.Cu")
		(net "SAS2X28_B_HDD12_TX_+")
	)
	(segment
		(start 20.853146 -238.8743)
		(end 20.865084 -238.862616)
		(width 0.09525)
		(layer "F.Cu")
		(net "SAS2X28_B_HDD12_TX_+")
	)
	(segment
		(start 19.600164 -239.009936)
		(end 20.530312 -239.009936)
		(width 0.09525)
		(layer "F.Cu")
		(net "SAS2X28_B_HDD12_TX_+")
	)
	(segment
		(start 20.530312 -239.009936)
		(end 20.533614 -239.006634)
		(width 0.09525)
		(layer "F.Cu")
		(net "SAS2X28_B_HDD12_TX_+")
	)
	(segment
		(start 5.341112 -169.794936)
		(end 5.340096 -169.794682)
		(width 0.09525)
		(layer "F.Cu")
		(net "SAS2X28_B_HDD12_TX_+")
	)
	(segment
		(start 4.741926 -169.498772)
		(end 3.192526 -169.498772)
		(width 0.09525)
		(layer "F.Cu")
		(net "SAS2X28_B_HDD12_TX_+")
	)
	(segment
		(start 4.74345 -169.500296)
		(end 4.741926 -169.498772)
		(width 0.09525)
		(layer "F.Cu")
		(net "SAS2X28_B_HDD12_TX_+")
	)
	(segment
		(start 21.041106 -238.789718)
		(end 21.652484 -238.789718)
		(width 0.09525)
		(layer "F.Cu")
		(net "SAS2X28_B_HDD12_TX_+")
	)
	(via
		(at 21.843746 -238.868966)
		(size 0.5588)
		(drill 0.3048)
		(layers "F.Cu" "B.Cu")
		(net "SAS2X28_B_HDD12_TX_+")
	)
	(via
		(at 7.032498 -169.531538)
		(size 0.5588)
		(drill 0.3048)
		(layers "F.Cu" "B.Cu")
		(net "SAS2X28_B_HDD12_TX_+")
	)
	(arc
		(start 20.533614 -239.006634)
		(mid 20.706536 -238.972238)
		(end 20.853146 -238.8743)
		(width 0.09525)
		(layer "F.Cu")
		(net "SAS2X28_B_HDD12_TX_+")
	)
	(arc
		(start 20.865084 -238.862616)
		(mid 20.945844 -238.808654)
		(end 21.041106 -238.789718)
		(width 0.09525)
		(layer "F.Cu")
		(net "SAS2X28_B_HDD12_TX_+")
	)
	(arc
		(start 5.340096 -169.794682)
		(mid 5.227633 -169.738933)
		(end 5.129784 -169.660316)
		(width 0.09525)
		(layer "F.Cu")
		(net "SAS2X28_B_HDD12_TX_+")
	)
	(arc
		(start 7.005066 -169.559224)
		(mid 6.704388 -169.760038)
		(end 6.349746 -169.830496)
		(width 0.09525)
		(layer "F.Cu")
		(net "SAS2X28_B_HDD12_TX_+")
	)
	(arc
		(start 5.540502 -169.830496)
		(mid 5.439236 -169.82152)
		(end 5.341112 -169.794936)
		(width 0.09525)
		(layer "F.Cu")
		(net "SAS2X28_B_HDD12_TX_+")
	)
	(arc
		(start 21.652484 -238.789718)
		(mid 21.756004 -238.810309)
		(end 21.843746 -238.868966)
		(width 0.09525)
		(layer "F.Cu")
		(net "SAS2X28_B_HDD12_TX_+")
	)
	(arc
		(start 5.129784 -169.660316)
		(mid 4.952532 -169.54188)
		(end 4.74345 -169.500296)
		(width 0.09525)
		(layer "F.Cu")
		(net "SAS2X28_B_HDD12_TX_+")
	)
	(segment
		(start 26.022046 -192.95491)
		(end 26.022046 -235.237528)
		(width 0.09525)
		(layer "B.Cu")
		(net "SAS2X28_B_HDD12_TX_+")
	)
	(segment
		(start 22.672548 -238.740442)
		(end 22.154134 -238.740442)
		(width 0.09525)
		(layer "B.Cu")
		(net "SAS2X28_B_HDD12_TX_+")
	)
	(segment
		(start 7.365746 -169.9387)
		(end 8.889746 -169.9387)
		(width 0.09525)
		(layer "B.Cu")
		(net "SAS2X28_B_HDD12_TX_+")
	)
	(segment
		(start 11.028172 -176.94402)
		(end 25.302972 -191.21882)
		(width 0.09525)
		(layer "B.Cu")
		(net "SAS2X28_B_HDD12_TX_+")
	)
	(segment
		(start 10.032746 -171.0817)
		(end 10.032746 -174.540926)
		(width 0.09525)
		(layer "B.Cu")
		(net "SAS2X28_B_HDD12_TX_+")
	)
	(segment
		(start 7.032498 -169.531538)
		(end 7.032498 -169.605452)
		(width 0.09525)
		(layer "B.Cu")
		(net "SAS2X28_B_HDD12_TX_+")
	)
	(segment
		(start 25.607772 -236.23778)
		(end 23.410926 -238.434626)
		(width 0.09525)
		(layer "B.Cu")
		(net "SAS2X28_B_HDD12_TX_+")
	)
	(arc
		(start 7.032498 -169.605452)
		(mid 7.130104 -169.841094)
		(end 7.365746 -169.9387)
		(width 0.09525)
		(layer "B.Cu")
		(net "SAS2X28_B_HDD12_TX_+")
	)
	(arc
		(start 22.154134 -238.740442)
		(mid 21.98617 -238.773852)
		(end 21.843746 -238.868966)
		(width 0.09525)
		(layer "B.Cu")
		(net "SAS2X28_B_HDD12_TX_+")
	)
	(arc
		(start 25.302972 -191.21882)
		(mid 25.835164 -192.015346)
		(end 26.022046 -192.95491)
		(width 0.09525)
		(layer "B.Cu")
		(net "SAS2X28_B_HDD12_TX_+")
	)
	(arc
		(start 26.022046 -235.237528)
		(mid 25.91444 -235.778883)
		(end 25.607772 -236.23778)
		(width 0.09525)
		(layer "B.Cu")
		(net "SAS2X28_B_HDD12_TX_+")
	)
	(arc
		(start 10.564368 -176.365916)
		(mid 10.780465 -176.667648)
		(end 11.028172 -176.94402)
		(width 0.09525)
		(layer "B.Cu")
		(net "SAS2X28_B_HDD12_TX_+")
	)
	(arc
		(start 23.410926 -238.434626)
		(mid 23.072155 -238.660956)
		(end 22.672548 -238.740442)
		(width 0.09525)
		(layer "B.Cu")
		(net "SAS2X28_B_HDD12_TX_+")
	)
	(arc
		(start 8.889746 -169.9387)
		(mid 9.697969 -170.273477)
		(end 10.032746 -171.0817)
		(width 0.09525)
		(layer "B.Cu")
		(net "SAS2X28_B_HDD12_TX_+")
	)
	(arc
		(start 10.032746 -174.540926)
		(mid 10.168349 -175.491353)
		(end 10.564368 -176.365916)
		(width 0.09525)
		(layer "B.Cu")
		(net "SAS2X28_B_HDD12_TX_+")
	)
	(segment
		(start 20.917662 -339.0265)
		(end 24.917146 -339.0265)
		(width 0.09525)
		(layer "F.Cu")
		(net "SAS2X28_DRIVE_RX_P_B11")
	)
	(segment
		(start 25.42921 -338.81441)
		(end 25.546812 -338.696808)
		(width 0.09525)
		(layer "F.Cu")
		(net "SAS2X28_DRIVE_RX_P_B11")
	)
	(segment
		(start 19.600164 -338.810092)
		(end 20.383754 -338.810092)
		(width 0.09525)
		(layer "F.Cu")
		(net "SAS2X28_DRIVE_RX_P_B11")
	)
	(segment
		(start 20.383754 -338.810092)
		(end 20.387056 -338.80679)
		(width 0.09525)
		(layer "F.Cu")
		(net "SAS2X28_DRIVE_RX_P_B11")
	)
	(arc
		(start 24.917146 -339.0265)
		(mid 25.194268 -338.971377)
		(end 25.42921 -338.81441)
		(width 0.09525)
		(layer "F.Cu")
		(net "SAS2X28_DRIVE_RX_P_B11")
	)
	(arc
		(start 20.387056 -338.80679)
		(mid 20.591179 -338.847393)
		(end 20.764246 -338.963)
		(width 0.09525)
		(layer "F.Cu")
		(net "SAS2X28_DRIVE_RX_P_B11")
	)
	(arc
		(start 20.764246 -338.963)
		(mid 20.834634 -339.010032)
		(end 20.917662 -339.0265)
		(width 0.09525)
		(layer "F.Cu")
		(net "SAS2X28_DRIVE_RX_P_B11")
	)
	(segment
		(start 221.558612 -469.346788)
		(end 219.832682 -469.346788)
		(width 0.09525)
		(layer "F.Cu")
		(net "SAS2X28_DRIVE_RX_N_A0")
	)
	(segment
		(start 221.7166 -469.093296)
		(end 221.7166 -469.1888)
		(width 0.09525)
		(layer "F.Cu")
		(net "SAS2X28_DRIVE_RX_N_A0")
	)
	(segment
		(start 223.249998 -468.88019)
		(end 221.863412 -468.88019)
		(width 0.09525)
		(layer "F.Cu")
		(net "SAS2X28_DRIVE_RX_N_A0")
	)
	(arc
		(start 221.7928 -468.9094)
		(mid 221.736424 -468.993772)
		(end 221.7166 -469.093296)
		(width 0.09525)
		(layer "F.Cu")
		(net "SAS2X28_DRIVE_RX_N_A0")
	)
	(arc
		(start 221.7166 -469.1888)
		(mid 221.670326 -469.300514)
		(end 221.558612 -469.346788)
		(width 0.09525)
		(layer "F.Cu")
		(net "SAS2X28_DRIVE_RX_N_A0")
	)
	(arc
		(start 221.863412 -468.88019)
		(mid 221.825212 -468.887788)
		(end 221.7928 -468.9094)
		(width 0.09525)
		(layer "F.Cu")
		(net "SAS2X28_DRIVE_RX_N_A0")
	)
	(arc
		(start 219.832682 -469.346788)
		(mid 219.431434 -469.266975)
		(end 219.091256 -469.039702)
		(width 0.09525)
		(layer "F.Cu")
		(net "SAS2X28_DRIVE_RX_N_A0")
	)
	(via
		(at 38.0238 -119.7864)
		(size 0.7112)
		(drill 0.4064)
		(layers "F.Cu" "B.Cu")
		(net "P12V_HDD13")
	)
	(via
		(at 52.610512 -111.866934)
		(size 0.7112)
		(drill 0.3556)
		(layers "F.Cu" "B.Cu")
		(net "P12V_HDD13")
	)
	(via
		(at 41.8084 -121.0818)
		(size 0.7112)
		(drill 0.4064)
		(layers "F.Cu" "B.Cu")
		(net "P12V_HDD13")
	)
	(via
		(at 24.815546 -114.2619)
		(size 0.7112)
		(drill 0.4064)
		(layers "F.Cu" "B.Cu")
		(net "P12V_HDD13")
	)
	(via
		(at 23.749 -113.1062)
		(size 0.7112)
		(drill 0.4064)
		(layers "F.Cu" "B.Cu")
		(net "P12V_HDD13")
	)
	(via
		(at 24.891746 -113.1697)
		(size 0.7112)
		(drill 0.4064)
		(layers "F.Cu" "B.Cu")
		(net "P12V_HDD13")
	)
	(via
		(at 43.5102 -121.0818)
		(size 0.7112)
		(drill 0.4064)
		(layers "F.Cu" "B.Cu")
		(net "P12V_HDD13")
	)
	(via
		(at 23.672546 -114.2619)
		(size 0.7112)
		(drill 0.4064)
		(layers "F.Cu" "B.Cu")
		(net "P12V_HDD13")
	)
	(via
		(at 42.799 -119.888)
		(size 0.7112)
		(drill 0.3556)
		(layers "F.Cu" "B.Cu")
		(net "P12V_HDD13")
	)
	(via
		(at 39.1414 -121.031)
		(size 0.7112)
		(drill 0.4064)
		(layers "F.Cu" "B.Cu")
		(net "P12V_HDD13")
	)
	(segment
		(start 8.156702 -351.832672)
		(end 8.156194 -351.833688)
		(width 0.09525)
		(layer "F.Cu")
		(net "SAS2X28_A_HDD12_RX_+")
	)
	(segment
		(start 27.805888 -253.433072)
		(end 9.099042 -272.139918)
		(width 0.09525)
		(layer "F.Cu")
		(net "SAS2X28_A_HDD12_RX_+")
	)
	(segment
		(start 8.15721 -351.832164)
		(end 8.156702 -351.832672)
		(width 0.09525)
		(layer "F.Cu")
		(net "SAS2X28_A_HDD12_RX_+")
	)
	(segment
		(start 7.855712 -352.282252)
		(end 7.855712 -352.4377)
		(width 0.09525)
		(layer "F.Cu")
		(net "SAS2X28_A_HDD12_RX_+")
	)
	(segment
		(start 8.156194 -351.833688)
		(end 7.953756 -352.03638)
		(width 0.09525)
		(layer "F.Cu")
		(net "SAS2X28_A_HDD12_RX_+")
	)
	(segment
		(start 7.932674 -352.62312)
		(end 8.212582 -352.903282)
		(width 0.09525)
		(layer "F.Cu")
		(net "SAS2X28_A_HDD12_RX_+")
	)
	(segment
		(start 8.451596 -273.702272)
		(end 8.451596 -351.121472)
		(width 0.09525)
		(layer "F.Cu")
		(net "SAS2X28_A_HDD12_RX_+")
	)
	(segment
		(start 28.8544 -243.519452)
		(end 28.8544 -250.900946)
		(width 0.09525)
		(layer "F.Cu")
		(net "SAS2X28_A_HDD12_RX_+")
	)
	(via
		(at 8.212582 -352.903282)
		(size 0.5588)
		(drill 0.3048)
		(layers "F.Cu" "B.Cu")
		(net "SAS2X28_A_HDD12_RX_+")
	)
	(arc
		(start 26.99893 -242.059206)
		(mid 27.300735 -242.262698)
		(end 27.65679 -242.338352)
		(width 0.09525)
		(layer "F.Cu")
		(net "SAS2X28_A_HDD12_RX_+")
	)
	(arc
		(start 7.855712 -352.4377)
		(mid 7.875768 -352.538056)
		(end 7.932674 -352.62312)
		(width 0.09525)
		(layer "F.Cu")
		(net "SAS2X28_A_HDD12_RX_+")
	)
	(arc
		(start 27.65679 -242.338352)
		(mid 27.665172 -242.338325)
		(end 27.673554 -242.338352)
		(width 0.09525)
		(layer "F.Cu")
		(net "SAS2X28_A_HDD12_RX_+")
	)
	(arc
		(start 7.953756 -352.03638)
		(mid 7.881139 -352.149905)
		(end 7.855712 -352.282252)
		(width 0.09525)
		(layer "F.Cu")
		(net "SAS2X28_A_HDD12_RX_+")
	)
	(arc
		(start 8.451596 -351.121472)
		(mid 8.375089 -351.506099)
		(end 8.15721 -351.832164)
		(width 0.09525)
		(layer "F.Cu")
		(net "SAS2X28_A_HDD12_RX_+")
	)
	(arc
		(start 28.8544 -250.900946)
		(mid 28.581991 -252.27129)
		(end 27.805888 -253.433072)
		(width 0.09525)
		(layer "F.Cu")
		(net "SAS2X28_A_HDD12_RX_+")
	)
	(arc
		(start 9.099042 -272.139918)
		(mid 8.619945 -272.856703)
		(end 8.451596 -273.702272)
		(width 0.09525)
		(layer "F.Cu")
		(net "SAS2X28_A_HDD12_RX_+")
	)
	(arc
		(start 27.673554 -242.338352)
		(mid 28.508628 -242.684304)
		(end 28.8544 -243.519452)
		(width 0.09525)
		(layer "F.Cu")
		(net "SAS2X28_A_HDD12_RX_+")
	)
	(segment
		(start 7.445248 -350.144842)
		(end 7.547864 -350.247458)
		(width 0.09525)
		(layer "B.Cu")
		(net "SAS2X28_A_HDD12_RX_+")
	)
	(segment
		(start 2.811526 -349.498412)
		(end 4.703826 -349.498412)
		(width 0.09525)
		(layer "B.Cu")
		(net "SAS2X28_A_HDD12_RX_+")
	)
	(segment
		(start 4.703826 -349.498412)
		(end 4.70535 -349.499936)
		(width 0.09525)
		(layer "B.Cu")
		(net "SAS2X28_A_HDD12_RX_+")
	)
	(segment
		(start 5.576824 -349.86087)
		(end 6.75894 -349.86087)
		(width 0.09525)
		(layer "B.Cu")
		(net "SAS2X28_A_HDD12_RX_+")
	)
	(segment
		(start 7.913116 -352.603816)
		(end 8.212582 -352.903282)
		(width 0.09525)
		(layer "B.Cu")
		(net "SAS2X28_A_HDD12_RX_+")
	)
	(segment
		(start 7.822946 -350.912176)
		(end 7.822946 -352.386138)
		(width 0.09525)
		(layer "B.Cu")
		(net "SAS2X28_A_HDD12_RX_+")
	)
	(arc
		(start 5.510784 -349.853504)
		(mid 5.543604 -349.858986)
		(end 5.576824 -349.86087)
		(width 0.09525)
		(layer "B.Cu")
		(net "SAS2X28_A_HDD12_RX_+")
	)
	(arc
		(start 6.75894 -349.86087)
		(mid 7.130318 -349.93463)
		(end 7.445248 -350.144842)
		(width 0.09525)
		(layer "B.Cu")
		(net "SAS2X28_A_HDD12_RX_+")
	)
	(arc
		(start 7.547864 -350.247458)
		(mid 7.751559 -350.552448)
		(end 7.822946 -350.912176)
		(width 0.09525)
		(layer "B.Cu")
		(net "SAS2X28_A_HDD12_RX_+")
	)
	(arc
		(start 5.501386 -349.851218)
		(mid 5.506076 -349.852398)
		(end 5.510784 -349.853504)
		(width 0.09525)
		(layer "B.Cu")
		(net "SAS2X28_A_HDD12_RX_+")
	)
	(arc
		(start 5.359146 -349.7707)
		(mid 5.424831 -349.820554)
		(end 5.501386 -349.851218)
		(width 0.09525)
		(layer "B.Cu")
		(net "SAS2X28_A_HDD12_RX_+")
	)
	(arc
		(start 7.822946 -352.386138)
		(mid 7.84638 -352.503946)
		(end 7.913116 -352.603816)
		(width 0.09525)
		(layer "B.Cu")
		(net "SAS2X28_A_HDD12_RX_+")
	)
	(arc
		(start 4.70535 -349.499936)
		(mid 5.059164 -349.570314)
		(end 5.359146 -349.7707)
		(width 0.09525)
		(layer "B.Cu")
		(net "SAS2X28_A_HDD12_RX_+")
	)
	(segment
		(start 21.044662 -442.0997)
		(end 25.23109 -442.0997)
		(width 0.09525)
		(layer "F.Cu")
		(net "SAS2X28_DRIVE_RX_P_B10")
	)
	(segment
		(start 19.600164 -441.81014)
		(end 20.495768 -441.81014)
		(width 0.09525)
		(layer "F.Cu")
		(net "SAS2X28_DRIVE_RX_P_B10")
	)
	(segment
		(start 20.495768 -441.81014)
		(end 20.49907 -441.806838)
		(width 0.09525)
		(layer "F.Cu")
		(net "SAS2X28_DRIVE_RX_P_B10")
	)
	(segment
		(start 20.776946 -441.9219)
		(end 20.891246 -442.0362)
		(width 0.09525)
		(layer "F.Cu")
		(net "SAS2X28_DRIVE_RX_P_B10")
	)
	(arc
		(start 25.23109 -442.0997)
		(mid 25.562936 -442.033692)
		(end 25.844246 -441.8457)
		(width 0.09525)
		(layer "F.Cu")
		(net "SAS2X28_DRIVE_RX_P_B10")
	)
	(arc
		(start 20.49907 -441.806838)
		(mid 20.649441 -441.836749)
		(end 20.776946 -441.9219)
		(width 0.09525)
		(layer "F.Cu")
		(net "SAS2X28_DRIVE_RX_P_B10")
	)
	(arc
		(start 20.891246 -442.0362)
		(mid 20.961634 -442.083232)
		(end 21.044662 -442.0997)
		(width 0.09525)
		(layer "F.Cu")
		(net "SAS2X28_DRIVE_RX_P_B10")
	)
	(segment
		(start 7.884668 -351.638108)
		(end 7.717536 -351.805494)
		(width 0.09525)
		(layer "F.Cu")
		(net "SAS2X28_A_HDD12_RX_-")
	)
	(segment
		(start 28.5242 -250.041664)
		(end 28.5242 -250.9012)
		(width 0.09525)
		(layer "F.Cu")
		(net "SAS2X28_A_HDD12_RX_-")
	)
	(segment
		(start 7.92353 -351.598484)
		(end 7.885176 -351.636838)
		(width 0.09525)
		(layer "F.Cu")
		(net "SAS2X28_A_HDD12_RX_-")
	)
	(segment
		(start 8.121396 -273.702272)
		(end 8.121396 -351.121218)
		(width 0.09525)
		(layer "F.Cu")
		(net "SAS2X28_A_HDD12_RX_-")
	)
	(segment
		(start 28.29179 -249.291094)
		(end 28.29179 -249.576844)
		(width 0.09525)
		(layer "F.Cu")
		(net "SAS2X28_A_HDD12_RX_-")
	)
	(segment
		(start 28.5242 -248.540524)
		(end 28.5242 -248.826274)
		(width 0.09525)
		(layer "F.Cu")
		(net "SAS2X28_A_HDD12_RX_-")
	)
	(segment
		(start 7.395972 -353.169474)
		(end 7.238746 -353.3267)
		(width 0.09525)
		(layer "F.Cu")
		(net "SAS2X28_A_HDD12_RX_-")
	)
	(segment
		(start 27.572208 -253.199392)
		(end 8.865362 -271.906238)
		(width 0.09525)
		(layer "F.Cu")
		(net "SAS2X28_A_HDD12_RX_-")
	)
	(segment
		(start 28.5242 -243.519452)
		(end 28.5242 -247.325134)
		(width 0.09525)
		(layer "F.Cu")
		(net "SAS2X28_A_HDD12_RX_-")
	)
	(segment
		(start 7.885176 -351.636838)
		(end 7.884668 -351.638108)
		(width 0.09525)
		(layer "F.Cu")
		(net "SAS2X28_A_HDD12_RX_-")
	)
	(segment
		(start 7.525512 -352.281998)
		(end 7.525512 -352.8568)
		(width 0.09525)
		(layer "F.Cu")
		(net "SAS2X28_A_HDD12_RX_-")
	)
	(segment
		(start 28.29179 -247.789954)
		(end 28.29179 -248.075704)
		(width 0.09525)
		(layer "F.Cu")
		(net "SAS2X28_A_HDD12_RX_-")
	)
	(via
		(at 7.238746 -353.3267)
		(size 0.5588)
		(drill 0.3048)
		(layers "F.Cu" "B.Cu")
		(net "SAS2X28_A_HDD12_RX_-")
	)
	(arc
		(start 26.99893 -242.948206)
		(mid 27.30845 -242.741391)
		(end 27.673554 -242.668806)
		(width 0.09525)
		(layer "F.Cu")
		(net "SAS2X28_A_HDD12_RX_-")
	)
	(arc
		(start 27.673554 -242.668806)
		(mid 28.275052 -242.917954)
		(end 28.5242 -243.519452)
		(width 0.09525)
		(layer "F.Cu")
		(net "SAS2X28_A_HDD12_RX_-")
	)
	(arc
		(start 28.5242 -248.826274)
		(mid 28.494264 -248.956609)
		(end 28.407868 -249.058684)
		(width 0.09525)
		(layer "F.Cu")
		(net "SAS2X28_A_HDD12_RX_-")
	)
	(arc
		(start 7.717536 -351.805494)
		(mid 7.575312 -352.025131)
		(end 7.525512 -352.281998)
		(width 0.09525)
		(layer "F.Cu")
		(net "SAS2X28_A_HDD12_RX_-")
	)
	(arc
		(start 28.5242 -247.325134)
		(mid 28.494264 -247.455469)
		(end 28.407868 -247.557544)
		(width 0.09525)
		(layer "F.Cu")
		(net "SAS2X28_A_HDD12_RX_-")
	)
	(arc
		(start 8.865362 -271.906238)
		(mid 8.314764 -272.730265)
		(end 8.121396 -273.702272)
		(width 0.09525)
		(layer "F.Cu")
		(net "SAS2X28_A_HDD12_RX_-")
	)
	(arc
		(start 7.525512 -352.8568)
		(mid 7.49185 -353.026028)
		(end 7.395972 -353.169474)
		(width 0.09525)
		(layer "F.Cu")
		(net "SAS2X28_A_HDD12_RX_-")
	)
	(arc
		(start 28.407868 -249.809254)
		(mid 28.494267 -249.911328)
		(end 28.5242 -250.041664)
		(width 0.09525)
		(layer "F.Cu")
		(net "SAS2X28_A_HDD12_RX_-")
	)
	(arc
		(start 28.5242 -250.9012)
		(mid 28.276779 -252.144977)
		(end 27.572208 -253.199392)
		(width 0.09525)
		(layer "F.Cu")
		(net "SAS2X28_A_HDD12_RX_-")
	)
	(arc
		(start 8.121396 -351.121218)
		(mid 8.069975 -351.379551)
		(end 7.92353 -351.598484)
		(width 0.09525)
		(layer "F.Cu")
		(net "SAS2X28_A_HDD12_RX_-")
	)
	(arc
		(start 28.29179 -249.576844)
		(mid 28.321587 -249.707162)
		(end 28.407868 -249.809254)
		(width 0.09525)
		(layer "F.Cu")
		(net "SAS2X28_A_HDD12_RX_-")
	)
	(arc
		(start 28.407868 -247.557544)
		(mid 28.321637 -247.659661)
		(end 28.29179 -247.789954)
		(width 0.09525)
		(layer "F.Cu")
		(net "SAS2X28_A_HDD12_RX_-")
	)
	(arc
		(start 28.29179 -248.075704)
		(mid 28.321587 -248.206022)
		(end 28.407868 -248.308114)
		(width 0.09525)
		(layer "F.Cu")
		(net "SAS2X28_A_HDD12_RX_-")
	)
	(arc
		(start 28.407868 -248.308114)
		(mid 28.494267 -248.410188)
		(end 28.5242 -248.540524)
		(width 0.09525)
		(layer "F.Cu")
		(net "SAS2X28_A_HDD12_RX_-")
	)
	(arc
		(start 28.407868 -249.058684)
		(mid 28.321637 -249.160801)
		(end 28.29179 -249.291094)
		(width 0.09525)
		(layer "F.Cu")
		(net "SAS2X28_A_HDD12_RX_-")
	)
	(segment
		(start 2.811526 -350.49841)
		(end 2.81305 -350.499934)
		(width 0.09525)
		(layer "B.Cu")
		(net "SAS2X28_A_HDD12_RX_-")
	)
	(segment
		(start 2.81305 -350.499934)
		(end 5.068062 -350.499934)
		(width 0.09525)
		(layer "B.Cu")
		(net "SAS2X28_A_HDD12_RX_-")
	)
	(segment
		(start 7.211568 -350.378522)
		(end 7.314184 -350.481138)
		(width 0.09525)
		(layer "B.Cu")
		(net "SAS2X28_A_HDD12_RX_-")
	)
	(segment
		(start 7.492746 -350.912176)
		(end 7.492746 -352.933)
		(width 0.09525)
		(layer "B.Cu")
		(net "SAS2X28_A_HDD12_RX_-")
	)
	(segment
		(start 7.39394 -353.171506)
		(end 7.238746 -353.3267)
		(width 0.09525)
		(layer "B.Cu")
		(net "SAS2X28_A_HDD12_RX_-")
	)
	(segment
		(start 5.370322 -350.374712)
		(end 5.404358 -350.340676)
		(width 0.09525)
		(layer "B.Cu")
		(net "SAS2X28_A_HDD12_RX_-")
	)
	(segment
		(start 5.765546 -350.19107)
		(end 6.75894 -350.19107)
		(width 0.09525)
		(layer "B.Cu")
		(net "SAS2X28_A_HDD12_RX_-")
	)
	(arc
		(start 6.75894 -350.19107)
		(mid 7.003888 -350.239793)
		(end 7.211568 -350.378522)
		(width 0.09525)
		(layer "B.Cu")
		(net "SAS2X28_A_HDD12_RX_-")
	)
	(arc
		(start 7.314184 -350.481138)
		(mid 7.446324 -350.6789)
		(end 7.492746 -350.912176)
		(width 0.09525)
		(layer "B.Cu")
		(net "SAS2X28_A_HDD12_RX_-")
	)
	(arc
		(start 5.068062 -350.499934)
		(mid 5.231652 -350.467394)
		(end 5.370322 -350.374712)
		(width 0.09525)
		(layer "B.Cu")
		(net "SAS2X28_A_HDD12_RX_-")
	)
	(arc
		(start 5.404358 -350.340676)
		(mid 5.570072 -350.229949)
		(end 5.765546 -350.19107)
		(width 0.09525)
		(layer "B.Cu")
		(net "SAS2X28_A_HDD12_RX_-")
	)
	(arc
		(start 7.492746 -352.933)
		(mid 7.46707 -353.062084)
		(end 7.39394 -353.171506)
		(width 0.09525)
		(layer "B.Cu")
		(net "SAS2X28_A_HDD12_RX_-")
	)
	(via
		(at 24.815546 -121.1707)
		(size 0.7112)
		(drill 0.4064)
		(layers "F.Cu" "B.Cu")
		(net "P5V_HDD13")
	)
	(via
		(at 40.004746 -127.6477)
		(size 0.7112)
		(drill 0.3556)
		(layers "F.Cu" "B.Cu")
		(net "P5V_HDD13")
	)
	(via
		(at 35.686746 -126.7587)
		(size 0.7112)
		(drill 0.4064)
		(layers "F.Cu" "B.Cu")
		(net "P5V_HDD13")
	)
	(via
		(at 42.747946 -127.8001)
		(size 0.7112)
		(drill 0.3556)
		(layers "F.Cu" "B.Cu")
		(net "P5V_HDD13")
	)
	(via
		(at 23.748746 -121.1707)
		(size 0.7112)
		(drill 0.4064)
		(layers "F.Cu" "B.Cu")
		(net "P5V_HDD13")
	)
	(via
		(at 34.619946 -126.7587)
		(size 0.7112)
		(drill 0.4064)
		(layers "F.Cu" "B.Cu")
		(net "P5V_HDD13")
	)
	(via
		(at 24.815546 -122.3137)
		(size 0.7112)
		(drill 0.4064)
		(layers "F.Cu" "B.Cu")
		(net "P5V_HDD13")
	)
	(via
		(at 38.988746 -127.6477)
		(size 0.7112)
		(drill 0.4064)
		(layers "F.Cu" "B.Cu")
		(net "P5V_HDD13")
	)
	(via
		(at 23.748746 -122.3137)
		(size 0.7112)
		(drill 0.4064)
		(layers "F.Cu" "B.Cu")
		(net "P5V_HDD13")
	)
	(via
		(at 37.845746 -127.6477)
		(size 0.7112)
		(drill 0.4064)
		(layers "F.Cu" "B.Cu")
		(net "P5V_HDD13")
	)
	(segment
		(start 38.988746 -127.6477)
		(end 40.004746 -127.6477)
		(width 0.508)
		(layer "B.Cu")
		(net "P5V_HDD13")
	)
	(segment
		(start 33.464246 -64.024764)
		(end 33.464246 -64.1477)
		(width 0.09525)
		(layer "F.Cu")
		(net "SAS2X28_DRIVE_RX_P_B9")
	)
	(segment
		(start 38.796976 -63.873126)
		(end 33.615884 -63.873126)
		(width 0.09525)
		(layer "F.Cu")
		(net "SAS2X28_DRIVE_RX_P_B9")
	)
	(segment
		(start 40.39997 -64.189864)
		(end 39.423848 -64.189864)
		(width 0.09525)
		(layer "F.Cu")
		(net "SAS2X28_DRIVE_RX_P_B9")
	)
	(segment
		(start 39.423848 -64.189864)
		(end 39.420546 -64.186562)
		(width 0.09525)
		(layer "F.Cu")
		(net "SAS2X28_DRIVE_RX_P_B9")
	)
	(segment
		(start 39.167054 -64.081406)
		(end 39.14902 -64.063626)
		(width 0.09525)
		(layer "F.Cu")
		(net "SAS2X28_DRIVE_RX_P_B9")
	)
	(segment
		(start 39.14902 -64.063626)
		(end 39.07282 -63.987426)
		(width 0.09525)
		(layer "F.Cu")
		(net "SAS2X28_DRIVE_RX_P_B9")
	)
	(arc
		(start 33.508696 -63.917576)
		(mid 33.475782 -63.96674)
		(end 33.464246 -64.024764)
		(width 0.09525)
		(layer "F.Cu")
		(net "SAS2X28_DRIVE_RX_P_B9")
	)
	(arc
		(start 39.07282 -63.987426)
		(mid 39.039719 -63.957892)
		(end 39.003478 -63.932308)
		(width 0.09525)
		(layer "F.Cu")
		(net "SAS2X28_DRIVE_RX_P_B9")
	)
	(arc
		(start 33.615884 -63.873126)
		(mid 33.557869 -63.884684)
		(end 33.508696 -63.917576)
		(width 0.09525)
		(layer "F.Cu")
		(net "SAS2X28_DRIVE_RX_P_B9")
	)
	(arc
		(start 39.420546 -64.186562)
		(mid 39.283351 -64.159179)
		(end 39.167054 -64.081406)
		(width 0.09525)
		(layer "F.Cu")
		(net "SAS2X28_DRIVE_RX_P_B9")
	)
	(arc
		(start 39.003478 -63.932308)
		(mid 38.904378 -63.888245)
		(end 38.796976 -63.873126)
		(width 0.09525)
		(layer "F.Cu")
		(net "SAS2X28_DRIVE_RX_P_B9")
	)
	(segment
		(start 5.809488 -352.160078)
		(end 5.454904 -352.160078)
		(width 0.09525)
		(layer "F.Cu")
		(net "SAS2X28_A_HDD12_TX_-")
	)
	(segment
		(start 23.172166 -245.791736)
		(end 23.172166 -246.024908)
		(width 0.09525)
		(layer "F.Cu")
		(net "SAS2X28_A_HDD12_TX_-")
	)
	(segment
		(start 24.840946 -247.149112)
		(end 24.840946 -253.811786)
		(width 0.09525)
		(layer "F.Cu")
		(net "SAS2X28_A_HDD12_TX_-")
	)
	(segment
		(start 7.190486 -351.30867)
		(end 6.776974 -351.722182)
		(width 0.09525)
		(layer "F.Cu")
		(net "SAS2X28_A_HDD12_TX_-")
	)
	(segment
		(start 6.776974 -351.722182)
		(end 6.728206 -351.770696)
		(width 0.09525)
		(layer "F.Cu")
		(net "SAS2X28_A_HDD12_TX_-")
	)
	(segment
		(start 4.632706 -352.498406)
		(end 3.192526 -352.498406)
		(width 0.09525)
		(layer "F.Cu")
		(net "SAS2X28_A_HDD12_TX_-")
	)
	(segment
		(start 23.273766 -246.126508)
		(end 24.08809 -246.126508)
		(width 0.09525)
		(layer "F.Cu")
		(net "SAS2X28_A_HDD12_TX_-")
	)
	(segment
		(start 21.75002 -245.65991)
		(end 23.01367 -245.65991)
		(width 0.09525)
		(layer "F.Cu")
		(net "SAS2X28_A_HDD12_TX_-")
	)
	(segment
		(start 24.00046 -255.8415)
		(end 8.159242 -271.682718)
		(width 0.09525)
		(layer "F.Cu")
		(net "SAS2X28_A_HDD12_TX_-")
	)
	(segment
		(start 4.63423 -352.49993)
		(end 4.632706 -352.498406)
		(width 0.09525)
		(layer "F.Cu")
		(net "SAS2X28_A_HDD12_TX_-")
	)
	(segment
		(start 23.124414 -245.704868)
		(end 23.143464 -245.723664)
		(width 0.09525)
		(layer "F.Cu")
		(net "SAS2X28_A_HDD12_TX_-")
	)
	(segment
		(start 7.511796 -273.245072)
		(end 7.511796 -350.5327)
		(width 0.09525)
		(layer "F.Cu")
		(net "SAS2X28_A_HDD12_TX_-")
	)
	(arc
		(start 23.25116 -246.123714)
		(mid 23.262385 -246.125744)
		(end 23.273766 -246.126508)
		(width 0.09525)
		(layer "F.Cu")
		(net "SAS2X28_A_HDD12_TX_-")
	)
	(arc
		(start 24.08809 -246.126508)
		(mid 24.303129 -246.169393)
		(end 24.485346 -246.291354)
		(width 0.09525)
		(layer "F.Cu")
		(net "SAS2X28_A_HDD12_TX_-")
	)
	(arc
		(start 24.485346 -246.291354)
		(mid 24.748391 -246.684894)
		(end 24.840946 -247.149112)
		(width 0.09525)
		(layer "F.Cu")
		(net "SAS2X28_A_HDD12_TX_-")
	)
	(arc
		(start 5.454904 -352.160078)
		(mid 5.323779 -352.18616)
		(end 5.212588 -352.260408)
		(width 0.09525)
		(layer "F.Cu")
		(net "SAS2X28_A_HDD12_TX_-")
	)
	(arc
		(start 7.511796 -350.5327)
		(mid 7.428286 -350.952625)
		(end 7.190486 -351.30867)
		(width 0.09525)
		(layer "F.Cu")
		(net "SAS2X28_A_HDD12_TX_-")
	)
	(arc
		(start 6.728206 -351.770696)
		(mid 6.30844 -352.058827)
		(end 5.809488 -352.160078)
		(width 0.09525)
		(layer "F.Cu")
		(net "SAS2X28_A_HDD12_TX_-")
	)
	(arc
		(start 23.01367 -245.65991)
		(mid 23.073463 -245.671518)
		(end 23.124414 -245.704868)
		(width 0.09525)
		(layer "F.Cu")
		(net "SAS2X28_A_HDD12_TX_-")
	)
	(arc
		(start 23.143464 -245.723664)
		(mid 23.164714 -245.754794)
		(end 23.172166 -245.791736)
		(width 0.09525)
		(layer "F.Cu")
		(net "SAS2X28_A_HDD12_TX_-")
	)
	(arc
		(start 8.159242 -271.682718)
		(mid 7.680145 -272.399503)
		(end 7.511796 -273.245072)
		(width 0.09525)
		(layer "F.Cu")
		(net "SAS2X28_A_HDD12_TX_-")
	)
	(arc
		(start 5.212588 -352.260408)
		(mid 4.947235 -352.437711)
		(end 4.63423 -352.49993)
		(width 0.09525)
		(layer "F.Cu")
		(net "SAS2X28_A_HDD12_TX_-")
	)
	(arc
		(start 23.172166 -246.024908)
		(mid 23.194337 -246.088172)
		(end 23.25116 -246.123714)
		(width 0.09525)
		(layer "F.Cu")
		(net "SAS2X28_A_HDD12_TX_-")
	)
	(arc
		(start 24.840946 -253.811786)
		(mid 24.622548 -254.910218)
		(end 24.00046 -255.8415)
		(width 0.09525)
		(layer "F.Cu")
		(net "SAS2X28_A_HDD12_TX_-")
	)
	(segment
		(start 40.39997 -167.189912)
		(end 39.338758 -167.189912)
		(width 0.09525)
		(layer "F.Cu")
		(net "SAS2X28_DRIVE_RX_P_B8")
	)
	(segment
		(start 39.115746 -166.9669)
		(end 34.776156 -166.9669)
		(width 0.09525)
		(layer "F.Cu")
		(net "SAS2X28_DRIVE_RX_P_B8")
	)
	(segment
		(start 39.338758 -167.189912)
		(end 39.335456 -167.18661)
		(width 0.09525)
		(layer "F.Cu")
		(net "SAS2X28_DRIVE_RX_P_B8")
	)
	(arc
		(start 34.776156 -166.9669)
		(mid 34.538887 -167.014096)
		(end 34.337752 -167.14851)
		(width 0.09525)
		(layer "F.Cu")
		(net "SAS2X28_DRIVE_RX_P_B8")
	)
	(arc
		(start 39.335456 -167.18661)
		(mid 39.25194 -167.152016)
		(end 39.217346 -167.0685)
		(width 0.09525)
		(layer "F.Cu")
		(net "SAS2X28_DRIVE_RX_P_B8")
	)
	(arc
		(start 39.138098 -166.969186)
		(mid 39.126985 -166.967436)
		(end 39.115746 -166.9669)
		(width 0.09525)
		(layer "F.Cu")
		(net "SAS2X28_DRIVE_RX_P_B8")
	)
	(arc
		(start 39.217346 -167.0685)
		(mid 39.195106 -167.004972)
		(end 39.138098 -166.969186)
		(width 0.09525)
		(layer "F.Cu")
		(net "SAS2X28_DRIVE_RX_P_B8")
	)
	(segment
		(start 82.931 -393.7508)
		(end 83.248246 -394.068046)
		(width 0.111252)
		(layer "F.Cu")
		(net "SAS_EXP_B_PWR6")
	)
	(segment
		(start 83.009486 -394.84046)
		(end 81.216246 -394.84046)
		(width 0.111252)
		(layer "F.Cu")
		(net "SAS_EXP_B_PWR6")
	)
	(segment
		(start 13.734796 -207.2005)
		(end 10.557002 -207.2005)
		(width 0.111252)
		(layer "F.Cu")
		(net "SAS_EXP_B_PWR6")
	)
	(segment
		(start 83.248246 -394.6017)
		(end 83.009486 -394.84046)
		(width 0.111252)
		(layer "F.Cu")
		(net "SAS_EXP_B_PWR6")
	)
	(segment
		(start 9.252966 -208.504536)
		(end 3.19024 -208.504536)
		(width 0.111252)
		(layer "F.Cu")
		(net "SAS_EXP_B_PWR6")
	)
	(segment
		(start 10.557002 -207.2005)
		(end 9.252966 -208.504536)
		(width 0.111252)
		(layer "F.Cu")
		(net "SAS_EXP_B_PWR6")
	)
	(segment
		(start 83.248246 -394.068046)
		(end 83.248246 -394.6017)
		(width 0.111252)
		(layer "F.Cu")
		(net "SAS_EXP_B_PWR6")
	)
	(via
		(at 82.931 -393.7508)
		(size 0.5588)
		(drill 0.3048)
		(layers "F.Cu" "B.Cu")
		(net "SAS_EXP_B_PWR6")
	)
	(via
		(at 13.734796 -207.2005)
		(size 0.5588)
		(drill 0.3048)
		(layers "F.Cu" "B.Cu")
		(net "SAS_EXP_B_PWR6")
	)
	(via
		(at 13.716 -208.2546)
		(size 0.7112)
		(drill 0.3556)
		(layers "F.Cu" "B.Cu")
		(net "SAS_EXP_B_PWR6")
	)
	(segment
		(start 13.716 -208.2546)
		(end 13.716 -207.219296)
		(width 0.111252)
		(layer "B.Cu")
		(net "SAS_EXP_B_PWR6")
	)
	(segment
		(start 13.716 -207.219296)
		(end 13.734796 -207.2005)
		(width 0.111252)
		(layer "B.Cu")
		(net "SAS_EXP_B_PWR6")
	)
	(segment
		(start 82.931 -331.482954)
		(end 82.931 -393.7508)
		(width 0.14605)
		(layer "In5.Cu")
		(net "SAS_EXP_B_PWR6")
	)
	(segment
		(start 49.434496 -279.456642)
		(end 49.434496 -297.98645)
		(width 0.14605)
		(layer "In5.Cu")
		(net "SAS_EXP_B_PWR6")
	)
	(segment
		(start 15.417546 -263.75868)
		(end 26.972514 -275.313648)
		(width 0.14605)
		(layer "In5.Cu")
		(net "SAS_EXP_B_PWR6")
	)
	(segment
		(start 49.3649 -279.288494)
		(end 49.434496 -279.456642)
		(width 0.14605)
		(layer "In5.Cu")
		(net "SAS_EXP_B_PWR6")
	)
	(segment
		(start 33.05175 -275.457158)
		(end 33.05175 -271.324578)
		(width 0.14605)
		(layer "In5.Cu")
		(net "SAS_EXP_B_PWR6")
	)
	(segment
		(start 26.972514 -275.313648)
		(end 27.122374 -275.313648)
		(width 0.14605)
		(layer "In5.Cu")
		(net "SAS_EXP_B_PWR6")
	)
	(segment
		(start 33.05175 -271.324578)
		(end 33.605978 -270.77035)
		(width 0.14605)
		(layer "In5.Cu")
		(net "SAS_EXP_B_PWR6")
	)
	(segment
		(start 32.264858 -276.24405)
		(end 33.05175 -275.457158)
		(width 0.14605)
		(layer "In5.Cu")
		(net "SAS_EXP_B_PWR6")
	)
	(segment
		(start 33.605978 -270.77035)
		(end 40.846756 -270.77035)
		(width 0.14605)
		(layer "In5.Cu")
		(net "SAS_EXP_B_PWR6")
	)
	(segment
		(start 49.434496 -297.98645)
		(end 82.931 -331.482954)
		(width 0.14605)
		(layer "In5.Cu")
		(net "SAS_EXP_B_PWR6")
	)
	(segment
		(start 13.734796 -207.2005)
		(end 15.417546 -208.88325)
		(width 0.14605)
		(layer "In5.Cu")
		(net "SAS_EXP_B_PWR6")
	)
	(segment
		(start 40.846756 -270.77035)
		(end 49.3649 -279.288494)
		(width 0.14605)
		(layer "In5.Cu")
		(net "SAS_EXP_B_PWR6")
	)
	(segment
		(start 15.417546 -208.88325)
		(end 15.417546 -263.75868)
		(width 0.14605)
		(layer "In5.Cu")
		(net "SAS_EXP_B_PWR6")
	)
	(segment
		(start 27.122374 -275.313648)
		(end 28.052776 -276.24405)
		(width 0.14605)
		(layer "In5.Cu")
		(net "SAS_EXP_B_PWR6")
	)
	(segment
		(start 28.052776 -276.24405)
		(end 32.264858 -276.24405)
		(width 0.14605)
		(layer "In5.Cu")
		(net "SAS_EXP_B_PWR6")
	)
	(segment
		(start 7.181596 -312.440066)
		(end 7.181596 -328.389742)
		(width 0.09525)
		(layer "F.Cu")
		(net "SAS2X28_A_HDD12_TX_+")
	)
	(segment
		(start 6.480048 -351.551748)
		(end 6.47954 -351.55251)
		(width 0.09525)
		(layer "F.Cu")
		(net "SAS2X28_A_HDD12_TX_+")
	)
	(segment
		(start 7.181596 -340.403942)
		(end 7.181596 -350.532954)
		(width 0.09525)
		(layer "F.Cu")
		(net "SAS2X28_A_HDD12_TX_+")
	)
	(segment
		(start 5.809488 -351.829878)
		(end 5.511546 -351.829878)
		(width 0.09525)
		(layer "F.Cu")
		(net "SAS2X28_A_HDD12_TX_+")
	)
	(segment
		(start 7.181596 -310.938926)
		(end 7.181596 -311.224676)
		(width 0.09525)
		(layer "F.Cu")
		(net "SAS2X28_A_HDD12_TX_+")
	)
	(segment
		(start 7.181596 -350.532954)
		(end 7.181342 -350.5327)
		(width 0.09525)
		(layer "F.Cu")
		(net "SAS2X28_A_HDD12_TX_+")
	)
	(segment
		(start 24.510746 -247.149366)
		(end 24.510746 -253.811786)
		(width 0.09525)
		(layer "F.Cu")
		(net "SAS2X28_A_HDD12_TX_+")
	)
	(segment
		(start 4.833112 -351.498408)
		(end 3.192526 -351.498408)
		(width 0.09525)
		(layer "F.Cu")
		(net "SAS2X28_A_HDD12_TX_+")
	)
	(segment
		(start 7.181596 -338.902802)
		(end 7.181596 -339.188552)
		(width 0.09525)
		(layer "F.Cu")
		(net "SAS2X28_A_HDD12_TX_+")
	)
	(segment
		(start 6.949186 -310.188356)
		(end 6.949186 -310.474106)
		(width 0.09525)
		(layer "F.Cu")
		(net "SAS2X28_A_HDD12_TX_+")
	)
	(segment
		(start 6.949186 -339.653372)
		(end 6.949186 -339.939122)
		(width 0.09525)
		(layer "F.Cu")
		(net "SAS2X28_A_HDD12_TX_+")
	)
	(segment
		(start 23.172166 -246.744236)
		(end 23.172166 -246.558308)
		(width 0.09525)
		(layer "F.Cu")
		(net "SAS2X28_A_HDD12_TX_+")
	)
	(segment
		(start 6.949186 -330.355702)
		(end 6.949186 -330.641452)
		(width 0.09525)
		(layer "F.Cu")
		(net "SAS2X28_A_HDD12_TX_+")
	)
	(segment
		(start 21.75002 -246.92991)
		(end 22.986492 -246.92991)
		(width 0.09525)
		(layer "F.Cu")
		(net "SAS2X28_A_HDD12_TX_+")
	)
	(segment
		(start 6.949186 -311.689496)
		(end 6.949186 -311.975246)
		(width 0.09525)
		(layer "F.Cu")
		(net "SAS2X28_A_HDD12_TX_+")
	)
	(segment
		(start 6.949186 -338.152232)
		(end 6.949186 -338.437982)
		(width 0.09525)
		(layer "F.Cu")
		(net "SAS2X28_A_HDD12_TX_+")
	)
	(segment
		(start 23.76678 -255.60782)
		(end 7.925562 -271.449038)
		(width 0.09525)
		(layer "F.Cu")
		(net "SAS2X28_A_HDD12_TX_+")
	)
	(segment
		(start 7.181596 -337.401662)
		(end 7.181596 -337.687412)
		(width 0.09525)
		(layer "F.Cu")
		(net "SAS2X28_A_HDD12_TX_+")
	)
	(segment
		(start 7.181596 -331.106272)
		(end 7.181596 -336.186272)
		(width 0.09525)
		(layer "F.Cu")
		(net "SAS2X28_A_HDD12_TX_+")
	)
	(segment
		(start 23.273766 -246.456708)
		(end 24.087836 -246.456708)
		(width 0.09525)
		(layer "F.Cu")
		(net "SAS2X28_A_HDD12_TX_+")
	)
	(segment
		(start 5.347208 -351.761806)
		(end 5.262626 -351.677224)
		(width 0.09525)
		(layer "F.Cu")
		(net "SAS2X28_A_HDD12_TX_+")
	)
	(segment
		(start 6.949186 -328.854562)
		(end 6.949186 -329.140312)
		(width 0.09525)
		(layer "F.Cu")
		(net "SAS2X28_A_HDD12_TX_+")
	)
	(segment
		(start 6.956806 -351.07499)
		(end 6.480048 -351.551748)
		(width 0.09525)
		(layer "F.Cu")
		(net "SAS2X28_A_HDD12_TX_+")
	)
	(segment
		(start 7.181596 -273.245072)
		(end 7.181596 -309.723536)
		(width 0.09525)
		(layer "F.Cu")
		(net "SAS2X28_A_HDD12_TX_+")
	)
	(segment
		(start 6.949186 -336.651092)
		(end 6.949186 -336.936842)
		(width 0.09525)
		(layer "F.Cu")
		(net "SAS2X28_A_HDD12_TX_+")
	)
	(segment
		(start 7.181596 -329.605132)
		(end 7.181596 -329.890882)
		(width 0.09525)
		(layer "F.Cu")
		(net "SAS2X28_A_HDD12_TX_+")
	)
	(segment
		(start 4.834636 -351.499932)
		(end 4.833112 -351.498408)
		(width 0.09525)
		(layer "F.Cu")
		(net "SAS2X28_A_HDD12_TX_+")
	)
	(arc
		(start 7.065518 -329.372722)
		(mid 7.151749 -329.474839)
		(end 7.181596 -329.605132)
		(width 0.09525)
		(layer "F.Cu")
		(net "SAS2X28_A_HDD12_TX_+")
	)
	(arc
		(start 7.065518 -340.171532)
		(mid 7.151749 -340.273649)
		(end 7.181596 -340.403942)
		(width 0.09525)
		(layer "F.Cu")
		(net "SAS2X28_A_HDD12_TX_+")
	)
	(arc
		(start 6.949186 -339.939122)
		(mid 6.979122 -340.069457)
		(end 7.065518 -340.171532)
		(width 0.09525)
		(layer "F.Cu")
		(net "SAS2X28_A_HDD12_TX_+")
	)
	(arc
		(start 6.949186 -336.936842)
		(mid 6.979122 -337.067177)
		(end 7.065518 -337.169252)
		(width 0.09525)
		(layer "F.Cu")
		(net "SAS2X28_A_HDD12_TX_+")
	)
	(arc
		(start 7.181596 -329.890882)
		(mid 7.151799 -330.0212)
		(end 7.065518 -330.123292)
		(width 0.09525)
		(layer "F.Cu")
		(net "SAS2X28_A_HDD12_TX_+")
	)
	(arc
		(start 6.949186 -310.474106)
		(mid 6.979122 -310.604441)
		(end 7.065518 -310.706516)
		(width 0.09525)
		(layer "F.Cu")
		(net "SAS2X28_A_HDD12_TX_+")
	)
	(arc
		(start 7.065518 -328.622152)
		(mid 6.979119 -328.724226)
		(end 6.949186 -328.854562)
		(width 0.09525)
		(layer "F.Cu")
		(net "SAS2X28_A_HDD12_TX_+")
	)
	(arc
		(start 7.181596 -328.389742)
		(mid 7.151799 -328.52006)
		(end 7.065518 -328.622152)
		(width 0.09525)
		(layer "F.Cu")
		(net "SAS2X28_A_HDD12_TX_+")
	)
	(arc
		(start 7.065518 -336.418682)
		(mid 6.979119 -336.520756)
		(end 6.949186 -336.651092)
		(width 0.09525)
		(layer "F.Cu")
		(net "SAS2X28_A_HDD12_TX_+")
	)
	(arc
		(start 23.242778 -246.46128)
		(mid 23.246443 -246.460197)
		(end 23.250144 -246.459248)
		(width 0.09525)
		(layer "F.Cu")
		(net "SAS2X28_A_HDD12_TX_+")
	)
	(arc
		(start 7.065518 -311.457086)
		(mid 6.979119 -311.55916)
		(end 6.949186 -311.689496)
		(width 0.09525)
		(layer "F.Cu")
		(net "SAS2X28_A_HDD12_TX_+")
	)
	(arc
		(start 6.949186 -311.975246)
		(mid 6.979122 -312.105581)
		(end 7.065518 -312.207656)
		(width 0.09525)
		(layer "F.Cu")
		(net "SAS2X28_A_HDD12_TX_+")
	)
	(arc
		(start 23.250144 -246.459248)
		(mid 23.26188 -246.457284)
		(end 23.273766 -246.456708)
		(width 0.09525)
		(layer "F.Cu")
		(net "SAS2X28_A_HDD12_TX_+")
	)
	(arc
		(start 24.087836 -246.456708)
		(mid 24.176499 -246.474474)
		(end 24.251666 -246.52478)
		(width 0.09525)
		(layer "F.Cu")
		(net "SAS2X28_A_HDD12_TX_+")
	)
	(arc
		(start 7.065518 -337.169252)
		(mid 7.151749 -337.271369)
		(end 7.181596 -337.401662)
		(width 0.09525)
		(layer "F.Cu")
		(net "SAS2X28_A_HDD12_TX_+")
	)
	(arc
		(start 7.065518 -310.706516)
		(mid 7.151749 -310.808633)
		(end 7.181596 -310.938926)
		(width 0.09525)
		(layer "F.Cu")
		(net "SAS2X28_A_HDD12_TX_+")
	)
	(arc
		(start 7.065518 -337.919822)
		(mid 6.979119 -338.021896)
		(end 6.949186 -338.152232)
		(width 0.09525)
		(layer "F.Cu")
		(net "SAS2X28_A_HDD12_TX_+")
	)
	(arc
		(start 24.510746 -253.811786)
		(mid 24.3174 -254.783802)
		(end 23.76678 -255.60782)
		(width 0.09525)
		(layer "F.Cu")
		(net "SAS2X28_A_HDD12_TX_+")
	)
	(arc
		(start 6.949186 -329.140312)
		(mid 6.979122 -329.270647)
		(end 7.065518 -329.372722)
		(width 0.09525)
		(layer "F.Cu")
		(net "SAS2X28_A_HDD12_TX_+")
	)
	(arc
		(start 6.47954 -351.55251)
		(mid 6.172102 -351.75784)
		(end 5.809488 -351.829878)
		(width 0.09525)
		(layer "F.Cu")
		(net "SAS2X28_A_HDD12_TX_+")
	)
	(arc
		(start 5.262626 -351.677224)
		(mid 5.066263 -351.546018)
		(end 4.834636 -351.499932)
		(width 0.09525)
		(layer "F.Cu")
		(net "SAS2X28_A_HDD12_TX_+")
	)
	(arc
		(start 5.511546 -351.829878)
		(mid 5.422607 -351.812187)
		(end 5.347208 -351.761806)
		(width 0.09525)
		(layer "F.Cu")
		(net "SAS2X28_A_HDD12_TX_+")
	)
	(arc
		(start 7.065518 -309.955946)
		(mid 6.979119 -310.05802)
		(end 6.949186 -310.188356)
		(width 0.09525)
		(layer "F.Cu")
		(net "SAS2X28_A_HDD12_TX_+")
	)
	(arc
		(start 7.181596 -309.723536)
		(mid 7.151799 -309.853854)
		(end 7.065518 -309.955946)
		(width 0.09525)
		(layer "F.Cu")
		(net "SAS2X28_A_HDD12_TX_+")
	)
	(arc
		(start 24.251666 -246.52478)
		(mid 24.443307 -246.811312)
		(end 24.510746 -247.149366)
		(width 0.09525)
		(layer "F.Cu")
		(net "SAS2X28_A_HDD12_TX_+")
	)
	(arc
		(start 7.065518 -330.873862)
		(mid 7.151749 -330.975979)
		(end 7.181596 -331.106272)
		(width 0.09525)
		(layer "F.Cu")
		(net "SAS2X28_A_HDD12_TX_+")
	)
	(arc
		(start 23.172166 -246.558308)
		(mid 23.191698 -246.49833)
		(end 23.242778 -246.46128)
		(width 0.09525)
		(layer "F.Cu")
		(net "SAS2X28_A_HDD12_TX_+")
	)
	(arc
		(start 6.949186 -338.437982)
		(mid 6.979122 -338.568317)
		(end 7.065518 -338.670392)
		(width 0.09525)
		(layer "F.Cu")
		(net "SAS2X28_A_HDD12_TX_+")
	)
	(arc
		(start 7.181596 -339.188552)
		(mid 7.151799 -339.31887)
		(end 7.065518 -339.420962)
		(width 0.09525)
		(layer "F.Cu")
		(net "SAS2X28_A_HDD12_TX_+")
	)
	(arc
		(start 7.065518 -338.670392)
		(mid 7.151749 -338.772509)
		(end 7.181596 -338.902802)
		(width 0.09525)
		(layer "F.Cu")
		(net "SAS2X28_A_HDD12_TX_+")
	)
	(arc
		(start 7.181596 -311.224676)
		(mid 7.151799 -311.354994)
		(end 7.065518 -311.457086)
		(width 0.09525)
		(layer "F.Cu")
		(net "SAS2X28_A_HDD12_TX_+")
	)
	(arc
		(start 7.065518 -330.123292)
		(mid 6.979119 -330.225366)
		(end 6.949186 -330.355702)
		(width 0.09525)
		(layer "F.Cu")
		(net "SAS2X28_A_HDD12_TX_+")
	)
	(arc
		(start 7.181342 -350.5327)
		(mid 7.122986 -350.826166)
		(end 6.956806 -351.07499)
		(width 0.09525)
		(layer "F.Cu")
		(net "SAS2X28_A_HDD12_TX_+")
	)
	(arc
		(start 7.065518 -312.207656)
		(mid 7.151749 -312.309773)
		(end 7.181596 -312.440066)
		(width 0.09525)
		(layer "F.Cu")
		(net "SAS2X28_A_HDD12_TX_+")
	)
	(arc
		(start 7.181596 -337.687412)
		(mid 7.151799 -337.81773)
		(end 7.065518 -337.919822)
		(width 0.09525)
		(layer "F.Cu")
		(net "SAS2X28_A_HDD12_TX_+")
	)
	(arc
		(start 7.181596 -336.186272)
		(mid 7.151799 -336.31659)
		(end 7.065518 -336.418682)
		(width 0.09525)
		(layer "F.Cu")
		(net "SAS2X28_A_HDD12_TX_+")
	)
	(arc
		(start 22.986492 -246.92991)
		(mid 23.117783 -246.875527)
		(end 23.172166 -246.744236)
		(width 0.09525)
		(layer "F.Cu")
		(net "SAS2X28_A_HDD12_TX_+")
	)
	(arc
		(start 7.065518 -339.420962)
		(mid 6.979119 -339.523036)
		(end 6.949186 -339.653372)
		(width 0.09525)
		(layer "F.Cu")
		(net "SAS2X28_A_HDD12_TX_+")
	)
	(arc
		(start 6.949186 -330.641452)
		(mid 6.979122 -330.771787)
		(end 7.065518 -330.873862)
		(width 0.09525)
		(layer "F.Cu")
		(net "SAS2X28_A_HDD12_TX_+")
	)
	(arc
		(start 7.925562 -271.449038)
		(mid 7.374964 -272.273065)
		(end 7.181596 -273.245072)
		(width 0.09525)
		(layer "F.Cu")
		(net "SAS2X28_A_HDD12_TX_+")
	)
	(segment
		(start 38.893496 -269.935706)
		(end 34.215578 -269.935706)
		(width 0.09525)
		(layer "F.Cu")
		(net "SAS2X28_DRIVE_RX_P_B7")
	)
	(segment
		(start 39.377112 -270.18996)
		(end 39.37381 -270.186658)
		(width 0.09525)
		(layer "F.Cu")
		(net "SAS2X28_DRIVE_RX_P_B7")
	)
	(segment
		(start 40.39997 -270.18996)
		(end 39.377112 -270.18996)
		(width 0.09525)
		(layer "F.Cu")
		(net "SAS2X28_DRIVE_RX_P_B7")
	)
	(segment
		(start 39.177468 -270.105378)
		(end 39.088568 -270.016478)
		(width 0.09525)
		(layer "F.Cu")
		(net "SAS2X28_DRIVE_RX_P_B7")
	)
	(arc
		(start 39.37381 -270.186658)
		(mid 39.267569 -270.165525)
		(end 39.177468 -270.105378)
		(width 0.09525)
		(layer "F.Cu")
		(net "SAS2X28_DRIVE_RX_P_B7")
	)
	(arc
		(start 34.215578 -269.935706)
		(mid 33.946427 -269.989244)
		(end 33.718246 -270.1417)
		(width 0.09525)
		(layer "F.Cu")
		(net "SAS2X28_DRIVE_RX_P_B7")
	)
	(arc
		(start 39.088568 -270.016478)
		(mid 38.999068 -269.956676)
		(end 38.893496 -269.935706)
		(width 0.09525)
		(layer "F.Cu")
		(net "SAS2X28_DRIVE_RX_P_B7")
	)
	(segment
		(start 52.323746 -226.5172)
		(end 52.323746 -228.158802)
		(width 0.111252)
		(layer "F.Cu")
		(net "SAS2X28_A_HDD12_FLT")
	)
	(segment
		(start 51.8922 -228.158802)
		(end 51.469798 -227.7364)
		(width 0.111252)
		(layer "F.Cu")
		(net "SAS2X28_A_HDD12_FLT")
	)
	(segment
		(start 51.469798 -227.7364)
		(end 51.002946 -227.7364)
		(width 0.111252)
		(layer "F.Cu")
		(net "SAS2X28_A_HDD12_FLT")
	)
	(segment
		(start 52.323746 -228.158802)
		(end 51.8922 -228.158802)
		(width 0.111252)
		(layer "F.Cu")
		(net "SAS2X28_A_HDD12_FLT")
	)
	(via
		(at 51.002946 -227.7364)
		(size 0.5588)
		(drill 0.3048)
		(layers "F.Cu" "B.Cu")
		(net "SAS2X28_A_HDD12_FLT")
	)
	(via
		(at 9.779 -389.7884)
		(size 0.5588)
		(drill 0.3048)
		(layers "F.Cu" "B.Cu")
		(net "SAS2X28_A_HDD12_FLT")
	)
	(via
		(at 51.993546 -227.73894)
		(size 0.7112)
		(drill 0.3556)
		(layers "F.Cu" "B.Cu")
		(net "SAS2X28_A_HDD12_FLT")
	)
	(segment
		(start 6.156452 -388.934452)
		(end 4.722368 -387.500368)
		(width 0.111252)
		(layer "B.Cu")
		(net "SAS2X28_A_HDD12_FLT")
	)
	(segment
		(start 8.417052 -388.934452)
		(end 6.156452 -388.934452)
		(width 0.111252)
		(layer "B.Cu")
		(net "SAS2X28_A_HDD12_FLT")
	)
	(segment
		(start 4.722368 -387.500368)
		(end 2.81305 -387.500368)
		(width 0.111252)
		(layer "B.Cu")
		(net "SAS2X28_A_HDD12_FLT")
	)
	(segment
		(start 2.81305 -387.500368)
		(end 2.811526 -387.498844)
		(width 0.111252)
		(layer "B.Cu")
		(net "SAS2X28_A_HDD12_FLT")
	)
	(segment
		(start 51.005486 -227.73894)
		(end 51.993546 -227.73894)
		(width 0.111252)
		(layer "B.Cu")
		(net "SAS2X28_A_HDD12_FLT")
	)
	(segment
		(start 9.779 -389.7884)
		(end 9.271 -389.7884)
		(width 0.111252)
		(layer "B.Cu")
		(net "SAS2X28_A_HDD12_FLT")
	)
	(segment
		(start 51.002946 -227.7364)
		(end 51.005486 -227.73894)
		(width 0.111252)
		(layer "B.Cu")
		(net "SAS2X28_A_HDD12_FLT")
	)
	(segment
		(start 9.271 -389.7884)
		(end 8.417052 -388.934452)
		(width 0.111252)
		(layer "B.Cu")
		(net "SAS2X28_A_HDD12_FLT")
	)
	(segment
		(start 13.057378 -443.258194)
		(end 11.99642 -443.258194)
		(width 0.14605)
		(layer "In5.Cu")
		(net "SAS2X28_A_HDD12_FLT")
	)
	(segment
		(start 10.615422 -442.512196)
		(end 9.331198 -441.227972)
		(width 0.14605)
		(layer "In5.Cu")
		(net "SAS2X28_A_HDD12_FLT")
	)
	(segment
		(start 14.63929 -431.516536)
		(end 14.63929 -401.99183)
		(width 0.14605)
		(layer "In5.Cu")
		(net "SAS2X28_A_HDD12_FLT")
	)
	(segment
		(start 51.002946 -229.56139)
		(end 78.968092 -257.526536)
		(width 0.14605)
		(layer "In5.Cu")
		(net "SAS2X28_A_HDD12_FLT")
	)
	(segment
		(start 9.331198 -436.824628)
		(end 14.63929 -431.516536)
		(width 0.14605)
		(layer "In5.Cu")
		(net "SAS2X28_A_HDD12_FLT")
	)
	(segment
		(start 14.894052 -396.735554)
		(end 10.826496 -392.667998)
		(width 0.14605)
		(layer "In5.Cu")
		(net "SAS2X28_A_HDD12_FLT")
	)
	(segment
		(start 85.629496 -277.539958)
		(end 85.629496 -409.309824)
		(width 0.14605)
		(layer "In5.Cu")
		(net "SAS2X28_A_HDD12_FLT")
	)
	(segment
		(start 79.502 -271.412462)
		(end 85.629496 -277.539958)
		(width 0.14605)
		(layer "In5.Cu")
		(net "SAS2X28_A_HDD12_FLT")
	)
	(segment
		(start 10.826496 -390.835896)
		(end 9.779 -389.7884)
		(width 0.14605)
		(layer "In5.Cu")
		(net "SAS2X28_A_HDD12_FLT")
	)
	(segment
		(start 11.99642 -443.258194)
		(end 11.250422 -442.512196)
		(width 0.14605)
		(layer "In5.Cu")
		(net "SAS2X28_A_HDD12_FLT")
	)
	(segment
		(start 47.24527 -447.69405)
		(end 35.2552 -447.69405)
		(width 0.14605)
		(layer "In5.Cu")
		(net "SAS2X28_A_HDD12_FLT")
	)
	(segment
		(start 78.968092 -257.526536)
		(end 78.968092 -270.8783)
		(width 0.14605)
		(layer "In5.Cu")
		(net "SAS2X28_A_HDD12_FLT")
	)
	(segment
		(start 78.968092 -270.8783)
		(end 79.502 -271.412462)
		(width 0.14605)
		(layer "In5.Cu")
		(net "SAS2X28_A_HDD12_FLT")
	)
	(segment
		(start 51.002946 -227.7364)
		(end 51.002946 -229.56139)
		(width 0.14605)
		(layer "In5.Cu")
		(net "SAS2X28_A_HDD12_FLT")
	)
	(segment
		(start 10.826496 -392.667998)
		(end 10.826496 -390.835896)
		(width 0.14605)
		(layer "In5.Cu")
		(net "SAS2X28_A_HDD12_FLT")
	)
	(segment
		(start 9.331198 -441.227972)
		(end 9.331198 -436.824628)
		(width 0.14605)
		(layer "In5.Cu")
		(net "SAS2X28_A_HDD12_FLT")
	)
	(segment
		(start 35.2552 -447.69405)
		(end 34.947352 -448.001898)
		(width 0.14605)
		(layer "In5.Cu")
		(net "SAS2X28_A_HDD12_FLT")
	)
	(segment
		(start 11.250422 -442.512196)
		(end 10.615422 -442.512196)
		(width 0.14605)
		(layer "In5.Cu")
		(net "SAS2X28_A_HDD12_FLT")
	)
	(segment
		(start 14.894052 -401.737068)
		(end 14.894052 -396.735554)
		(width 0.14605)
		(layer "In5.Cu")
		(net "SAS2X28_A_HDD12_FLT")
	)
	(segment
		(start 14.63929 -401.99183)
		(end 14.894052 -401.737068)
		(width 0.14605)
		(layer "In5.Cu")
		(net "SAS2X28_A_HDD12_FLT")
	)
	(segment
		(start 85.629496 -409.309824)
		(end 47.24527 -447.69405)
		(width 0.14605)
		(layer "In5.Cu")
		(net "SAS2X28_A_HDD12_FLT")
	)
	(segment
		(start 34.947352 -448.001898)
		(end 17.801082 -448.001898)
		(width 0.14605)
		(layer "In5.Cu")
		(net "SAS2X28_A_HDD12_FLT")
	)
	(segment
		(start 17.801082 -448.001898)
		(end 13.057378 -443.258194)
		(width 0.14605)
		(layer "In5.Cu")
		(net "SAS2X28_A_HDD12_FLT")
	)
	(segment
		(start 40.39997 -373.190008)
		(end 39.306754 -373.190008)
		(width 0.09525)
		(layer "F.Cu")
		(net "SAS2X28_DRIVE_RX_P_B6")
	)
	(segment
		(start 38.736778 -372.95201)
		(end 33.877504 -372.95201)
		(width 0.09525)
		(layer "F.Cu")
		(net "SAS2X28_DRIVE_RX_P_B6")
	)
	(segment
		(start 39.306754 -373.190008)
		(end 39.303452 -373.186706)
		(width 0.09525)
		(layer "F.Cu")
		(net "SAS2X28_DRIVE_RX_P_B6")
	)
	(arc
		(start 39.303452 -373.186706)
		(mid 39.174368 -373.16103)
		(end 39.064946 -373.0879)
		(width 0.09525)
		(layer "F.Cu")
		(net "SAS2X28_DRIVE_RX_P_B6")
	)
	(arc
		(start 39.064946 -373.0879)
		(mid 38.914381 -372.987296)
		(end 38.736778 -372.95201)
		(width 0.09525)
		(layer "F.Cu")
		(net "SAS2X28_DRIVE_RX_P_B6")
	)
	(arc
		(start 33.877504 -372.95201)
		(mid 33.570153 -373.013146)
		(end 33.30956 -373.187214)
		(width 0.09525)
		(layer "F.Cu")
		(net "SAS2X28_DRIVE_RX_P_B6")
	)
	(segment
		(start 53.7845 -227.2284)
		(end 53.0733 -226.5172)
		(width 0.111252)
		(layer "F.Cu")
		(net "SAS2X28_B_HDD12_FLT")
	)
	(segment
		(start 53.7845 -227.714048)
		(end 53.7845 -227.2284)
		(width 0.111252)
		(layer "F.Cu")
		(net "SAS2X28_B_HDD12_FLT")
	)
	(segment
		(start 3.19405 -147.50034)
		(end 3.192526 -147.498816)
		(width 0.111252)
		(layer "F.Cu")
		(net "SAS2X28_B_HDD12_FLT")
	)
	(segment
		(start 7.112 -146.939)
		(end 6.55066 -147.50034)
		(width 0.111252)
		(layer "F.Cu")
		(net "SAS2X28_B_HDD12_FLT")
	)
	(segment
		(start 6.55066 -147.50034)
		(end 3.19405 -147.50034)
		(width 0.111252)
		(layer "F.Cu")
		(net "SAS2X28_B_HDD12_FLT")
	)
	(segment
		(start 53.339746 -228.158802)
		(end 53.7845 -227.714048)
		(width 0.111252)
		(layer "F.Cu")
		(net "SAS2X28_B_HDD12_FLT")
	)
	(segment
		(start 53.0733 -226.5172)
		(end 52.973986 -226.5172)
		(width 0.111252)
		(layer "F.Cu")
		(net "SAS2X28_B_HDD12_FLT")
	)
	(via
		(at 94.361 -223.6724)
		(size 0.5588)
		(drill 0.3048)
		(layers "F.Cu" "B.Cu")
		(net "SAS2X28_B_HDD12_FLT")
	)
	(via
		(at 54.737 -226.97694)
		(size 0.7112)
		(drill 0.3556)
		(layers "F.Cu" "B.Cu")
		(net "SAS2X28_B_HDD12_FLT")
	)
	(via
		(at 53.7845 -227.2284)
		(size 0.5588)
		(drill 0.3048)
		(layers "F.Cu" "B.Cu")
		(net "SAS2X28_B_HDD12_FLT")
	)
	(via
		(at 7.112 -146.939)
		(size 0.5588)
		(drill 0.3048)
		(layers "F.Cu" "B.Cu")
		(net "SAS2X28_B_HDD12_FLT")
	)
	(segment
		(start 53.7845 -227.2284)
		(end 54.03596 -226.97694)
		(width 0.111252)
		(layer "B.Cu")
		(net "SAS2X28_B_HDD12_FLT")
	)
	(segment
		(start 54.03596 -226.97694)
		(end 54.737 -226.97694)
		(width 0.111252)
		(layer "B.Cu")
		(net "SAS2X28_B_HDD12_FLT")
	)
	(segment
		(start 54.3179 -226.695)
		(end 93.345 -226.695)
		(width 0.14605)
		(layer "In2.Cu")
		(net "SAS2X28_B_HDD12_FLT")
	)
	(segment
		(start 94.361 -225.679)
		(end 94.361 -223.6724)
		(width 0.14605)
		(layer "In2.Cu")
		(net "SAS2X28_B_HDD12_FLT")
	)
	(segment
		(start 53.7845 -227.2284)
		(end 54.3179 -226.695)
		(width 0.14605)
		(layer "In2.Cu")
		(net "SAS2X28_B_HDD12_FLT")
	)
	(segment
		(start 93.345 -226.695)
		(end 94.361 -225.679)
		(width 0.14605)
		(layer "In2.Cu")
		(net "SAS2X28_B_HDD12_FLT")
	)
	(segment
		(start 94.967298 -223.066102)
		(end 94.967298 -106.799634)
		(width 0.14605)
		(layer "In5.Cu")
		(net "SAS2X28_B_HDD12_FLT")
	)
	(segment
		(start 10.687304 -138.829034)
		(end 10.408666 -139.107672)
		(width 0.14605)
		(layer "In5.Cu")
		(net "SAS2X28_B_HDD12_FLT")
	)
	(segment
		(start 12.036552 -129.838196)
		(end 12.036552 -133.458204)
		(width 0.14605)
		(layer "In5.Cu")
		(net "SAS2X28_B_HDD12_FLT")
	)
	(segment
		(start 21.52142 -99.488498)
		(end 11.598148 -109.41177)
		(width 0.14605)
		(layer "In5.Cu")
		(net "SAS2X28_B_HDD12_FLT")
	)
	(segment
		(start 94.361 -223.6724)
		(end 94.967298 -223.066102)
		(width 0.14605)
		(layer "In5.Cu")
		(net "SAS2X28_B_HDD12_FLT")
	)
	(segment
		(start 10.44067 -139.536932)
		(end 10.44067 -141.946376)
		(width 0.14605)
		(layer "In5.Cu")
		(net "SAS2X28_B_HDD12_FLT")
	)
	(segment
		(start 8.610346 -145.1737)
		(end 7.112 -146.671792)
		(width 0.14605)
		(layer "In5.Cu")
		(net "SAS2X28_B_HDD12_FLT")
	)
	(segment
		(start 87.656162 -99.488498)
		(end 21.52142 -99.488498)
		(width 0.14605)
		(layer "In5.Cu")
		(net "SAS2X28_B_HDD12_FLT")
	)
	(segment
		(start 10.408666 -139.107672)
		(end 10.408666 -139.504928)
		(width 0.14605)
		(layer "In5.Cu")
		(net "SAS2X28_B_HDD12_FLT")
	)
	(segment
		(start 10.44067 -141.946376)
		(end 8.610346 -143.7767)
		(width 0.14605)
		(layer "In5.Cu")
		(net "SAS2X28_B_HDD12_FLT")
	)
	(segment
		(start 8.610346 -143.7767)
		(end 8.610346 -145.1737)
		(width 0.14605)
		(layer "In5.Cu")
		(net "SAS2X28_B_HDD12_FLT")
	)
	(segment
		(start 94.967298 -106.799634)
		(end 87.656162 -99.488498)
		(width 0.14605)
		(layer "In5.Cu")
		(net "SAS2X28_B_HDD12_FLT")
	)
	(segment
		(start 11.598148 -109.41177)
		(end 11.598148 -129.399792)
		(width 0.14605)
		(layer "In5.Cu")
		(net "SAS2X28_B_HDD12_FLT")
	)
	(segment
		(start 10.408666 -139.504928)
		(end 10.44067 -139.536932)
		(width 0.14605)
		(layer "In5.Cu")
		(net "SAS2X28_B_HDD12_FLT")
	)
	(segment
		(start 10.687304 -134.807452)
		(end 10.687304 -138.829034)
		(width 0.14605)
		(layer "In5.Cu")
		(net "SAS2X28_B_HDD12_FLT")
	)
	(segment
		(start 11.598148 -129.399792)
		(end 12.036552 -129.838196)
		(width 0.14605)
		(layer "In5.Cu")
		(net "SAS2X28_B_HDD12_FLT")
	)
	(segment
		(start 7.112 -146.671792)
		(end 7.112 -146.939)
		(width 0.14605)
		(layer "In5.Cu")
		(net "SAS2X28_B_HDD12_FLT")
	)
	(segment
		(start 12.036552 -133.458204)
		(end 10.687304 -134.807452)
		(width 0.14605)
		(layer "In5.Cu")
		(net "SAS2X28_B_HDD12_FLT")
	)
	(segment
		(start 38.951662 -475.951804)
		(end 33.75025 -475.951804)
		(width 0.09525)
		(layer "F.Cu")
		(net "SAS2X28_DRIVE_RX_P_B5")
	)
	(segment
		(start 39.219886 -476.107506)
		(end 39.143686 -476.031306)
		(width 0.09525)
		(layer "F.Cu")
		(net "SAS2X28_DRIVE_RX_P_B5")
	)
	(segment
		(start 40.39997 -476.190056)
		(end 39.41445 -476.190056)
		(width 0.09525)
		(layer "F.Cu")
		(net "SAS2X28_DRIVE_RX_P_B5")
	)
	(segment
		(start 39.41445 -476.190056)
		(end 39.411148 -476.186754)
		(width 0.09525)
		(layer "F.Cu")
		(net "SAS2X28_DRIVE_RX_P_B5")
	)
	(arc
		(start 33.75025 -475.951804)
		(mid 33.608238 -475.980052)
		(end 33.487868 -476.060516)
		(width 0.09525)
		(layer "F.Cu")
		(net "SAS2X28_DRIVE_RX_P_B5")
	)
	(arc
		(start 39.143686 -476.031306)
		(mid 39.055585 -475.972439)
		(end 38.951662 -475.951804)
		(width 0.09525)
		(layer "F.Cu")
		(net "SAS2X28_DRIVE_RX_P_B5")
	)
	(arc
		(start 39.411148 -476.186754)
		(mid 39.307628 -476.166163)
		(end 39.219886 -476.107506)
		(width 0.09525)
		(layer "F.Cu")
		(net "SAS2X28_DRIVE_RX_P_B5")
	)
	(segment
		(start 7.933944 -268.2367)
		(end 7.200646 -268.2367)
		(width 0.111252)
		(layer "F.Cu")
		(net "DRIVE_ACT_12")
	)
	(segment
		(start 14.271244 -259.3467)
		(end 14.271244 -259.56514)
		(width 0.111252)
		(layer "F.Cu")
		(net "DRIVE_ACT_12")
	)
	(segment
		(start 14.287246 -258.3307)
		(end 13.398246 -257.4417)
		(width 0.111252)
		(layer "F.Cu")
		(net "DRIVE_ACT_12")
	)
	(segment
		(start 13.716 -262.454644)
		(end 7.933944 -268.2367)
		(width 0.111252)
		(layer "F.Cu")
		(net "DRIVE_ACT_12")
	)
	(segment
		(start 14.271244 -258.346702)
		(end 14.287246 -258.3307)
		(width 0.111252)
		(layer "F.Cu")
		(net "DRIVE_ACT_12")
	)
	(segment
		(start 14.271244 -259.3467)
		(end 14.271244 -258.346702)
		(width 0.111252)
		(layer "F.Cu")
		(net "DRIVE_ACT_12")
	)
	(segment
		(start 14.271244 -259.56514)
		(end 13.716 -260.120384)
		(width 0.111252)
		(layer "F.Cu")
		(net "DRIVE_ACT_12")
	)
	(segment
		(start 13.716 -260.120384)
		(end 13.716 -262.454644)
		(width 0.111252)
		(layer "F.Cu")
		(net "DRIVE_ACT_12")
	)
	(segment
		(start 13.398246 -257.4417)
		(end 13.334746 -257.4417)
		(width 0.111252)
		(layer "F.Cu")
		(net "DRIVE_ACT_12")
	)
	(via
		(at 13.334746 -257.4417)
		(size 0.7112)
		(drill 0.3556)
		(layers "F.Cu" "B.Cu")
		(net "DRIVE_ACT_12")
	)
	(segment
		(start 224.203006 -64.090804)
		(end 224.155254 -64.043052)
		(width 0.09525)
		(layer "F.Cu")
		(net "SAS2X28_DRIVE_RX_P_B4")
	)
	(segment
		(start 223.900746 -63.937642)
		(end 218.947746 -63.937642)
		(width 0.09525)
		(layer "F.Cu")
		(net "SAS2X28_DRIVE_RX_P_B4")
	)
	(segment
		(start 218.267026 -64.219582)
		(end 218.243912 -64.242696)
		(width 0.09525)
		(layer "F.Cu")
		(net "SAS2X28_DRIVE_RX_P_B4")
	)
	(segment
		(start 224.437448 -64.189864)
		(end 224.434146 -64.186562)
		(width 0.09525)
		(layer "F.Cu")
		(net "SAS2X28_DRIVE_RX_P_B4")
	)
	(segment
		(start 225.399854 -64.189864)
		(end 224.437448 -64.189864)
		(width 0.09525)
		(layer "F.Cu")
		(net "SAS2X28_DRIVE_RX_P_B4")
	)
	(arc
		(start 224.155254 -64.043052)
		(mid 224.038485 -63.965029)
		(end 223.900746 -63.937642)
		(width 0.09525)
		(layer "F.Cu")
		(net "SAS2X28_DRIVE_RX_P_B4")
	)
	(arc
		(start 218.9099 -63.93815)
		(mid 218.561898 -64.018195)
		(end 218.267026 -64.219582)
		(width 0.09525)
		(layer "F.Cu")
		(net "SAS2X28_DRIVE_RX_P_B4")
	)
	(arc
		(start 224.434146 -64.186562)
		(mid 224.309048 -64.161678)
		(end 224.203006 -64.090804)
		(width 0.09525)
		(layer "F.Cu")
		(net "SAS2X28_DRIVE_RX_P_B4")
	)
	(arc
		(start 218.947746 -63.937642)
		(mid 218.92882 -63.937708)
		(end 218.9099 -63.93815)
		(width 0.09525)
		(layer "F.Cu")
		(net "SAS2X28_DRIVE_RX_P_B4")
	)
	(segment
		(start 224.57791 -167.189912)
		(end 224.574608 -167.18661)
		(width 0.09525)
		(layer "F.Cu")
		(net "SAS2X28_DRIVE_RX_P_B3")
	)
	(segment
		(start 224.080324 -166.9669)
		(end 218.922346 -166.9669)
		(width 0.09525)
		(layer "F.Cu")
		(net "SAS2X28_DRIVE_RX_P_B3")
	)
	(segment
		(start 225.399854 -167.189912)
		(end 224.57791 -167.189912)
		(width 0.09525)
		(layer "F.Cu")
		(net "SAS2X28_DRIVE_RX_P_B3")
	)
	(segment
		(start 218.306142 -167.22217)
		(end 218.299284 -167.229028)
		(width 0.09525)
		(layer "F.Cu")
		(net "SAS2X28_DRIVE_RX_P_B3")
	)
	(arc
		(start 224.25152 -167.052752)
		(mid 224.2368 -167.039551)
		(end 224.222564 -167.025828)
		(width 0.09525)
		(layer "F.Cu")
		(net "SAS2X28_DRIVE_RX_P_B3")
	)
	(arc
		(start 224.222564 -167.025828)
		(mid 224.194928 -167.002749)
		(end 224.163636 -166.984934)
		(width 0.09525)
		(layer "F.Cu")
		(net "SAS2X28_DRIVE_RX_P_B3")
	)
	(arc
		(start 224.163636 -166.984934)
		(mid 224.122947 -166.971441)
		(end 224.080324 -166.9669)
		(width 0.09525)
		(layer "F.Cu")
		(net "SAS2X28_DRIVE_RX_P_B3")
	)
	(arc
		(start 224.574608 -167.18661)
		(mid 224.399742 -167.151827)
		(end 224.25152 -167.052752)
		(width 0.09525)
		(layer "F.Cu")
		(net "SAS2X28_DRIVE_RX_P_B3")
	)
	(arc
		(start 218.922346 -166.9669)
		(mid 218.588847 -167.033237)
		(end 218.306142 -167.22217)
		(width 0.09525)
		(layer "F.Cu")
		(net "SAS2X28_DRIVE_RX_P_B3")
	)
	(via
		(at 67.436746 -81.8007)
		(size 0.7112)
		(drill 0.3556)
		(layers "F.Cu" "B.Cu")
		(net "P12V_HDD9")
	)
	(via
		(at 64.515746 -93.9927)
		(size 0.7112)
		(drill 0.3556)
		(layers "F.Cu" "B.Cu")
		(net "P12V_HDD9")
	)
	(segment
		(start 224.467928 -270.18996)
		(end 224.464626 -270.186658)
		(width 0.09525)
		(layer "F.Cu")
		(net "SAS2X28_DRIVE_RX_P_B2")
	)
	(segment
		(start 225.399854 -270.18996)
		(end 224.467928 -270.18996)
		(width 0.09525)
		(layer "F.Cu")
		(net "SAS2X28_DRIVE_RX_P_B2")
	)
	(segment
		(start 223.898206 -269.951962)
		(end 219.181426 -269.951962)
		(width 0.09525)
		(layer "F.Cu")
		(net "SAS2X28_DRIVE_RX_P_B2")
	)
	(arc
		(start 224.181416 -270.06931)
		(mid 224.051492 -269.982435)
		(end 223.898206 -269.951962)
		(width 0.09525)
		(layer "F.Cu")
		(net "SAS2X28_DRIVE_RX_P_B2")
	)
	(arc
		(start 224.464626 -270.186658)
		(mid 224.311339 -270.156167)
		(end 224.181416 -270.06931)
		(width 0.09525)
		(layer "F.Cu")
		(net "SAS2X28_DRIVE_RX_P_B2")
	)
	(arc
		(start 219.181426 -269.951962)
		(mid 218.654107 -270.056852)
		(end 218.207082 -270.355568)
		(width 0.09525)
		(layer "F.Cu")
		(net "SAS2X28_DRIVE_RX_P_B2")
	)
	(segment
		(start 31.305246 -343.4207)
		(end 31.432246 -343.2937)
		(width 0.111252)
		(layer "F.Cu")
		(net "DRIVE_ACT_11")
	)
	(segment
		(start 31.432246 -343.2937)
		(end 32.956246 -343.2937)
		(width 0.111252)
		(layer "F.Cu")
		(net "DRIVE_ACT_11")
	)
	(segment
		(start 36.1823 -343.2937)
		(end 32.956246 -343.2937)
		(width 0.111252)
		(layer "F.Cu")
		(net "DRIVE_ACT_11")
	)
	(segment
		(start 37.592 -342.011)
		(end 37.465 -342.011)
		(width 0.111252)
		(layer "F.Cu")
		(net "DRIVE_ACT_11")
	)
	(segment
		(start 37.465 -342.011)
		(end 36.1823 -343.2937)
		(width 0.111252)
		(layer "F.Cu")
		(net "DRIVE_ACT_11")
	)
	(segment
		(start 31.305246 -344.4367)
		(end 31.305246 -343.4207)
		(width 0.111252)
		(layer "F.Cu")
		(net "DRIVE_ACT_11")
	)
	(via
		(at 37.592 -342.011)
		(size 0.7112)
		(drill 0.3556)
		(layers "F.Cu" "B.Cu")
		(net "DRIVE_ACT_11")
	)
	(via
		(at 65.278 -80.318356)
		(size 0.7112)
		(drill 0.3556)
		(layers "F.Cu" "B.Cu")
		(net "P5V_HDD9")
	)
	(via
		(at 53.974746 -77.9907)
		(size 0.7112)
		(drill 0.3556)
		(layers "F.Cu" "B.Cu")
		(net "P5V_HDD9")
	)
	(via
		(at 221.640146 -85.400896)
		(size 0.7112)
		(drill 0.3556)
		(layers "F.Cu" "B.Cu")
		(net "P12V_HDD4")
	)
	(via
		(at 220.547946 -85.3821)
		(size 0.5588)
		(drill 0.3048)
		(layers "F.Cu" "B.Cu")
		(net "P12V_HDD4")
	)
	(via
		(at 204.850746 -92.494608)
		(size 0.7112)
		(drill 0.3556)
		(layers "F.Cu" "B.Cu")
		(net "P12V_HDD4")
	)
	(segment
		(start 220.547946 -85.3821)
		(end 221.62135 -85.3821)
		(width 0.508)
		(layer "B.Cu")
		(net "P12V_HDD4")
	)
	(segment
		(start 221.62135 -85.3821)
		(end 221.640146 -85.400896)
		(width 0.508)
		(layer "B.Cu")
		(net "P12V_HDD4")
	)
	(segment
		(start 218.595448 -373.192548)
		(end 218.586558 -373.201184)
		(width 0.09525)
		(layer "F.Cu")
		(net "SAS2X28_DRIVE_RX_P_B1")
	)
	(segment
		(start 223.921828 -372.951756)
		(end 219.176346 -372.951756)
		(width 0.09525)
		(layer "F.Cu")
		(net "SAS2X28_DRIVE_RX_P_B1")
	)
	(segment
		(start 224.492312 -373.190008)
		(end 224.48901 -373.186706)
		(width 0.09525)
		(layer "F.Cu")
		(net "SAS2X28_DRIVE_RX_P_B1")
	)
	(segment
		(start 225.399854 -373.190008)
		(end 224.492312 -373.190008)
		(width 0.09525)
		(layer "F.Cu")
		(net "SAS2X28_DRIVE_RX_P_B1")
	)
	(arc
		(start 224.48901 -373.186706)
		(mid 224.313464 -373.151788)
		(end 224.164652 -373.05234)
		(width 0.09525)
		(layer "F.Cu")
		(net "SAS2X28_DRIVE_RX_P_B1")
	)
	(arc
		(start 219.176346 -372.951756)
		(mid 218.861953 -373.014386)
		(end 218.595448 -373.192548)
		(width 0.09525)
		(layer "F.Cu")
		(net "SAS2X28_DRIVE_RX_P_B1")
	)
	(arc
		(start 224.164652 -373.05234)
		(mid 224.053243 -372.977899)
		(end 223.921828 -372.951756)
		(width 0.09525)
		(layer "F.Cu")
		(net "SAS2X28_DRIVE_RX_P_B1")
	)
	(segment
		(start 5.9817 -463.0801)
		(end 6.432804 -463.0801)
		(width 0.111252)
		(layer "F.Cu")
		(net "SAS_EXP_A_PWR0")
	)
	(segment
		(start 6.825488 -463.0801)
		(end 8.000746 -463.0801)
		(width 0.111252)
		(layer "F.Cu")
		(net "SAS_EXP_A_PWR0")
	)
	(segment
		(start 195.875148 -492.687102)
		(end 194.707256 -492.687102)
		(width 0.111252)
		(layer "F.Cu")
		(net "SAS_EXP_A_PWR0")
	)
	(segment
		(start 3.193542 -463.501486)
		(end 5.560314 -463.501486)
		(width 0.111252)
		(layer "F.Cu")
		(net "SAS_EXP_A_PWR0")
	)
	(segment
		(start 196.786246 -492.5187)
		(end 196.214746 -492.5187)
		(width 0.111252)
		(layer "F.Cu")
		(net "SAS_EXP_A_PWR0")
	)
	(segment
		(start 196.214746 -492.5187)
		(end 195.960746 -492.7727)
		(width 0.111252)
		(layer "F.Cu")
		(net "SAS_EXP_A_PWR0")
	)
	(segment
		(start 6.43763 -463.075274)
		(end 6.820662 -463.075274)
		(width 0.111252)
		(layer "F.Cu")
		(net "SAS_EXP_A_PWR0")
	)
	(segment
		(start 5.560314 -463.501486)
		(end 5.9817 -463.0801)
		(width 0.111252)
		(layer "F.Cu")
		(net "SAS_EXP_A_PWR0")
	)
	(segment
		(start 8.560054 -463.639408)
		(end 9.279128 -463.639408)
		(width 0.111252)
		(layer "F.Cu")
		(net "SAS_EXP_A_PWR0")
	)
	(segment
		(start 6.820662 -463.075274)
		(end 6.825488 -463.0801)
		(width 0.111252)
		(layer "F.Cu")
		(net "SAS_EXP_A_PWR0")
	)
	(segment
		(start 3.19024 -463.504788)
		(end 3.193542 -463.501486)
		(width 0.111252)
		(layer "F.Cu")
		(net "SAS_EXP_A_PWR0")
	)
	(segment
		(start 195.960746 -492.7727)
		(end 195.875148 -492.687102)
		(width 0.111252)
		(layer "F.Cu")
		(net "SAS_EXP_A_PWR0")
	)
	(segment
		(start 6.432804 -463.0801)
		(end 6.43763 -463.075274)
		(width 0.111252)
		(layer "F.Cu")
		(net "SAS_EXP_A_PWR0")
	)
	(segment
		(start 8.000746 -463.0801)
		(end 8.560054 -463.639408)
		(width 0.111252)
		(layer "F.Cu")
		(net "SAS_EXP_A_PWR0")
	)
	(via
		(at 195.960746 -492.7727)
		(size 0.5588)
		(drill 0.3048)
		(layers "F.Cu" "B.Cu")
		(net "SAS_EXP_A_PWR0")
	)
	(via
		(at 196.900546 -492.7727)
		(size 0.7112)
		(drill 0.3556)
		(layers "F.Cu" "B.Cu")
		(net "SAS_EXP_A_PWR0")
	)
	(via
		(at 9.279128 -463.639408)
		(size 0.5588)
		(drill 0.3048)
		(layers "F.Cu" "B.Cu")
		(net "SAS_EXP_A_PWR0")
	)
	(segment
		(start 195.960746 -492.7727)
		(end 196.900546 -492.7727)
		(width 0.111252)
		(layer "B.Cu")
		(net "SAS_EXP_A_PWR0")
	)
	(segment
		(start 175.923194 -472.859354)
		(end 175.953928 -472.890088)
		(width 0.14605)
		(layer "In5.Cu")
		(net "SAS_EXP_A_PWR0")
	)
	(segment
		(start 8.765794 -464.152742)
		(end 8.765794 -466.03031)
		(width 0.14605)
		(layer "In5.Cu")
		(net "SAS_EXP_A_PWR0")
	)
	(segment
		(start 175.89754 -472.834462)
		(end 175.922432 -472.859354)
		(width 0.14605)
		(layer "In5.Cu")
		(net "SAS_EXP_A_PWR0")
	)
	(segment
		(start 8.765794 -466.03031)
		(end 10.148062 -467.412578)
		(width 0.14605)
		(layer "In5.Cu")
		(net "SAS_EXP_A_PWR0")
	)
	(segment
		(start 36.225226 -472.059)
		(end 37.000688 -472.834462)
		(width 0.14605)
		(layer "In5.Cu")
		(net "SAS_EXP_A_PWR0")
	)
	(segment
		(start 9.279128 -463.639408)
		(end 8.765794 -464.152742)
		(width 0.14605)
		(layer "In5.Cu")
		(net "SAS_EXP_A_PWR0")
	)
	(segment
		(start 175.922432 -472.859354)
		(end 175.923194 -472.859354)
		(width 0.14605)
		(layer "In5.Cu")
		(net "SAS_EXP_A_PWR0")
	)
	(segment
		(start 37.000688 -472.834462)
		(end 175.89754 -472.834462)
		(width 0.14605)
		(layer "In5.Cu")
		(net "SAS_EXP_A_PWR0")
	)
	(segment
		(start 35.605466 -472.059)
		(end 36.225226 -472.059)
		(width 0.14605)
		(layer "In5.Cu")
		(net "SAS_EXP_A_PWR0")
	)
	(segment
		(start 175.953928 -472.890088)
		(end 176.078134 -472.890088)
		(width 0.14605)
		(layer "In5.Cu")
		(net "SAS_EXP_A_PWR0")
	)
	(segment
		(start 35.322764 -471.776298)
		(end 35.605466 -472.059)
		(width 0.14605)
		(layer "In5.Cu")
		(net "SAS_EXP_A_PWR0")
	)
	(segment
		(start 13.654024 -471.595704)
		(end 13.834618 -471.776298)
		(width 0.14605)
		(layer "In5.Cu")
		(net "SAS_EXP_A_PWR0")
	)
	(segment
		(start 13.834618 -471.776298)
		(end 35.322764 -471.776298)
		(width 0.14605)
		(layer "In5.Cu")
		(net "SAS_EXP_A_PWR0")
	)
	(segment
		(start 176.078134 -472.890088)
		(end 195.960746 -492.7727)
		(width 0.14605)
		(layer "In5.Cu")
		(net "SAS_EXP_A_PWR0")
	)
	(segment
		(start 10.148062 -467.412578)
		(end 10.148062 -468.089996)
		(width 0.14605)
		(layer "In5.Cu")
		(net "SAS_EXP_A_PWR0")
	)
	(segment
		(start 10.148062 -468.089996)
		(end 13.65377 -471.595704)
		(width 0.14605)
		(layer "In5.Cu")
		(net "SAS_EXP_A_PWR0")
	)
	(segment
		(start 13.65377 -471.595704)
		(end 13.654024 -471.595704)
		(width 0.14605)
		(layer "In5.Cu")
		(net "SAS_EXP_A_PWR0")
	)
	(via
		(at 210.82 -74.803)
		(size 0.7112)
		(drill 0.3556)
		(layers "F.Cu" "B.Cu")
		(net "P5V_HDD4")
	)
	(via
		(at 221.741746 -74.834496)
		(size 0.7112)
		(drill 0.3556)
		(layers "F.Cu" "B.Cu")
		(net "P5V_HDD4")
	)
	(via
		(at 220.674946 -74.8665)
		(size 0.5588)
		(drill 0.3048)
		(layers "F.Cu" "B.Cu")
		(net "P5V_HDD4")
	)
	(segment
		(start 221.709742 -74.8665)
		(end 221.741746 -74.834496)
		(width 0.508)
		(layer "B.Cu")
		(net "P5V_HDD4")
	)
	(segment
		(start 220.674946 -74.8665)
		(end 221.709742 -74.8665)
		(width 0.508)
		(layer "B.Cu")
		(net "P5V_HDD4")
	)
	(segment
		(start 224.188528 -476.076264)
		(end 224.137728 -476.025464)
		(width 0.09525)
		(layer "F.Cu")
		(net "SAS2X28_DRIVE_RX_P_B0")
	)
	(segment
		(start 223.959928 -475.951804)
		(end 219.291154 -475.951804)
		(width 0.09525)
		(layer "F.Cu")
		(net "SAS2X28_DRIVE_RX_P_B0")
	)
	(segment
		(start 225.396552 -476.186754)
		(end 224.455228 -476.186754)
		(width 0.09525)
		(layer "F.Cu")
		(net "SAS2X28_DRIVE_RX_P_B0")
	)
	(segment
		(start 225.399854 -476.190056)
		(end 225.396552 -476.186754)
		(width 0.09525)
		(layer "F.Cu")
		(net "SAS2X28_DRIVE_RX_P_B0")
	)
	(arc
		(start 224.137728 -476.025464)
		(mid 224.056153 -475.970957)
		(end 223.959928 -475.951804)
		(width 0.09525)
		(layer "F.Cu")
		(net "SAS2X28_DRIVE_RX_P_B0")
	)
	(arc
		(start 219.291154 -475.951804)
		(mid 219.149805 -476.010353)
		(end 219.091256 -476.151702)
		(width 0.09525)
		(layer "F.Cu")
		(net "SAS2X28_DRIVE_RX_P_B0")
	)
	(arc
		(start 224.455228 -476.186754)
		(mid 224.310884 -476.158042)
		(end 224.188528 -476.076264)
		(width 0.09525)
		(layer "F.Cu")
		(net "SAS2X28_DRIVE_RX_P_B0")
	)
	(segment
		(start 21.75002 -37.119814)
		(end 23.055072 -37.119814)
		(width 0.09525)
		(layer "F.Cu")
		(net "SAS2X28_DRIVE_RX_N_A14")
	)
	(segment
		(start 23.172166 -37.00272)
		(end 23.172166 -36.748212)
		(width 0.09525)
		(layer "F.Cu")
		(net "SAS2X28_DRIVE_RX_N_A14")
	)
	(segment
		(start 23.273766 -36.646612)
		(end 25.11679 -36.646612)
		(width 0.09525)
		(layer "F.Cu")
		(net "SAS2X28_DRIVE_RX_N_A14")
	)
	(arc
		(start 23.247858 -36.649914)
		(mid 23.260706 -36.647432)
		(end 23.273766 -36.646612)
		(width 0.09525)
		(layer "F.Cu")
		(net "SAS2X28_DRIVE_RX_N_A14")
	)
	(arc
		(start 23.055072 -37.119814)
		(mid 23.099882 -37.110901)
		(end 23.137876 -37.085524)
		(width 0.09525)
		(layer "F.Cu")
		(net "SAS2X28_DRIVE_RX_N_A14")
	)
	(arc
		(start 23.172166 -36.748212)
		(mid 23.193288 -36.686197)
		(end 23.247858 -36.649914)
		(width 0.09525)
		(layer "F.Cu")
		(net "SAS2X28_DRIVE_RX_N_A14")
	)
	(arc
		(start 25.11679 -36.646612)
		(mid 25.373013 -36.697578)
		(end 25.590246 -36.8427)
		(width 0.09525)
		(layer "F.Cu")
		(net "SAS2X28_DRIVE_RX_N_A14")
	)
	(arc
		(start 23.137876 -37.085524)
		(mid 23.163261 -37.047533)
		(end 23.172166 -37.00272)
		(width 0.09525)
		(layer "F.Cu")
		(net "SAS2X28_DRIVE_RX_N_A14")
	)
	(segment
		(start 25.171146 -31.215076)
		(end 25.171146 -32.0929)
		(width 0.09525)
		(layer "F.Cu")
		(net "SAS2X28_DRIVE_RX_N_B14")
	)
	(segment
		(start 20.73021 -30.402276)
		(end 24.358346 -30.402276)
		(width 0.09525)
		(layer "F.Cu")
		(net "SAS2X28_DRIVE_RX_N_B14")
	)
	(segment
		(start 25.729946 -32.6517)
		(end 26.288746 -32.6517)
		(width 0.09525)
		(layer "F.Cu")
		(net "SAS2X28_DRIVE_RX_N_B14")
	)
	(segment
		(start 19.600164 -30.609794)
		(end 20.17903 -30.609794)
		(width 0.09525)
		(layer "F.Cu")
		(net "SAS2X28_DRIVE_RX_N_B14")
	)
	(segment
		(start 26.61412 -32.78632)
		(end 26.733246 -32.9057)
		(width 0.09525)
		(layer "F.Cu")
		(net "SAS2X28_DRIVE_RX_N_B14")
	)
	(segment
		(start 20.17903 -30.609794)
		(end 20.182332 -30.606492)
		(width 0.09525)
		(layer "F.Cu")
		(net "SAS2X28_DRIVE_RX_N_B14")
	)
	(arc
		(start 24.358346 -30.402276)
		(mid 24.933082 -30.64034)
		(end 25.171146 -31.215076)
		(width 0.09525)
		(layer "F.Cu")
		(net "SAS2X28_DRIVE_RX_N_B14")
	)
	(arc
		(start 25.171146 -32.0929)
		(mid 25.334815 -32.488031)
		(end 25.729946 -32.6517)
		(width 0.09525)
		(layer "F.Cu")
		(net "SAS2X28_DRIVE_RX_N_B14")
	)
	(arc
		(start 26.288746 -32.6517)
		(mid 26.464832 -32.686632)
		(end 26.61412 -32.78632)
		(width 0.09525)
		(layer "F.Cu")
		(net "SAS2X28_DRIVE_RX_N_B14")
	)
	(arc
		(start 20.630134 -30.443678)
		(mid 20.676049 -30.412998)
		(end 20.73021 -30.402276)
		(width 0.09525)
		(layer "F.Cu")
		(net "SAS2X28_DRIVE_RX_N_B14")
	)
	(arc
		(start 20.182332 -30.606492)
		(mid 20.420573 -30.564526)
		(end 20.630134 -30.443678)
		(width 0.09525)
		(layer "F.Cu")
		(net "SAS2X28_DRIVE_RX_N_B14")
	)
	(segment
		(start 216.584784 -171.674028)
		(end 216.584784 -170.484038)
		(width 0.111252)
		(layer "F.Cu")
		(net "HDD_PRSNT3")
	)
	(segment
		(start 216.584784 -170.484038)
		(end 216.5858 -170.483022)
		(width 0.111252)
		(layer "F.Cu")
		(net "HDD_PRSNT3")
	)
	(segment
		(start 216.5858 -170.483022)
		(end 216.5858 -169.545)
		(width 0.111252)
		(layer "F.Cu")
		(net "HDD_PRSNT3")
	)
	(segment
		(start 216.5858 -169.545)
		(end 216.586562 -169.544238)
		(width 0.111252)
		(layer "F.Cu")
		(net "HDD_PRSNT3")
	)
	(via
		(at 10.281412 -456.13828)
		(size 0.5588)
		(drill 0.3048)
		(layers "F.Cu" "B.Cu")
		(net "HDD_PRSNT3")
	)
	(via
		(at 8.153146 -456.4761)
		(size 0.5588)
		(drill 0.3048)
		(layers "F.Cu" "B.Cu")
		(net "HDD_PRSNT3")
	)
	(via
		(at 216.584784 -170.484038)
		(size 0.5588)
		(drill 0.3048)
		(layers "F.Cu" "B.Cu")
		(net "HDD_PRSNT3")
	)
	(via
		(at 216.586562 -169.544238)
		(size 0.7112)
		(drill 0.3556)
		(layers "F.Cu" "B.Cu")
		(net "HDD_PRSNT3")
	)
	(via
		(at 9.031986 -201.958448)
		(size 0.5588)
		(drill 0.3048)
		(layers "F.Cu" "B.Cu")
		(net "HDD_PRSNT3")
	)
	(segment
		(start 8.128 -456.501246)
		(end 2.812542 -456.501246)
		(width 0.111252)
		(layer "B.Cu")
		(net "HDD_PRSNT3")
	)
	(segment
		(start 9.031986 -201.958448)
		(end 8.574786 -201.501248)
		(width 0.111252)
		(layer "B.Cu")
		(net "HDD_PRSNT3")
	)
	(segment
		(start 10.281412 -456.13828)
		(end 9.943592 -456.4761)
		(width 0.111252)
		(layer "B.Cu")
		(net "HDD_PRSNT3")
	)
	(segment
		(start 2.812542 -201.501248)
		(end 2.80924 -201.50455)
		(width 0.111252)
		(layer "B.Cu")
		(net "HDD_PRSNT3")
	)
	(segment
		(start 2.812542 -456.501246)
		(end 2.80924 -456.504548)
		(width 0.111252)
		(layer "B.Cu")
		(net "HDD_PRSNT3")
	)
	(segment
		(start 8.153146 -456.4761)
		(end 8.128 -456.501246)
		(width 0.111252)
		(layer "B.Cu")
		(net "HDD_PRSNT3")
	)
	(segment
		(start 8.574786 -201.501248)
		(end 2.812542 -201.501248)
		(width 0.111252)
		(layer "B.Cu")
		(net "HDD_PRSNT3")
	)
	(segment
		(start 9.943592 -456.4761)
		(end 8.153146 -456.4761)
		(width 0.111252)
		(layer "B.Cu")
		(net "HDD_PRSNT3")
	)
	(segment
		(start 11.731498 -395.60246)
		(end 11.657838 -395.675866)
		(width 0.14605)
		(layer "In2.Cu")
		(net "HDD_PRSNT3")
	)
	(segment
		(start 10.899902 -203.67244)
		(end 10.899902 -211.955126)
		(width 0.14605)
		(layer "In2.Cu")
		(net "HDD_PRSNT3")
	)
	(segment
		(start 9.18591 -201.958448)
		(end 10.899902 -203.67244)
		(width 0.14605)
		(layer "In2.Cu")
		(net "HDD_PRSNT3")
	)
	(segment
		(start 9.031986 -201.958448)
		(end 9.18591 -201.958448)
		(width 0.14605)
		(layer "In2.Cu")
		(net "HDD_PRSNT3")
	)
	(segment
		(start 12.076938 -256.858008)
		(end 12.639802 -257.420872)
		(width 0.14605)
		(layer "In2.Cu")
		(net "HDD_PRSNT3")
	)
	(segment
		(start 10.899902 -211.955126)
		(end 11.330432 -212.385656)
		(width 0.14605)
		(layer "In2.Cu")
		(net "HDD_PRSNT3")
	)
	(segment
		(start 12.328398 -375.311416)
		(end 12.328398 -391.3632)
		(width 0.14605)
		(layer "In2.Cu")
		(net "HDD_PRSNT3")
	)
	(segment
		(start 11.48334 -434.410866)
		(end 6.934962 -438.959244)
		(width 0.14605)
		(layer "In2.Cu")
		(net "HDD_PRSNT3")
	)
	(segment
		(start 11.330432 -217.674444)
		(end 12.076938 -218.42095)
		(width 0.14605)
		(layer "In2.Cu")
		(net "HDD_PRSNT3")
	)
	(segment
		(start 11.382248 -392.30935)
		(end 11.382248 -393.08405)
		(width 0.14605)
		(layer "In2.Cu")
		(net "HDD_PRSNT3")
	)
	(segment
		(start 11.382248 -393.08405)
		(end 11.731498 -393.4333)
		(width 0.14605)
		(layer "In2.Cu")
		(net "HDD_PRSNT3")
	)
	(segment
		(start 12.384786 -268.088364)
		(end 12.38504 -268.088618)
		(width 0.14605)
		(layer "In2.Cu")
		(net "HDD_PRSNT3")
	)
	(segment
		(start 12.639802 -257.420872)
		(end 12.639802 -258.630166)
		(width 0.14605)
		(layer "In2.Cu")
		(net "HDD_PRSNT3")
	)
	(segment
		(start 11.330432 -212.385656)
		(end 11.330432 -217.674444)
		(width 0.14605)
		(layer "In2.Cu")
		(net "HDD_PRSNT3")
	)
	(segment
		(start 12.38504 -366.16005)
		(end 12.84605 -366.62106)
		(width 0.14605)
		(layer "In2.Cu")
		(net "HDD_PRSNT3")
	)
	(segment
		(start 12.38504 -268.088618)
		(end 12.38504 -366.16005)
		(width 0.14605)
		(layer "In2.Cu")
		(net "HDD_PRSNT3")
	)
	(segment
		(start 12.643612 -258.63423)
		(end 13.156946 -259.147564)
		(width 0.14605)
		(layer "In2.Cu")
		(net "HDD_PRSNT3")
	)
	(segment
		(start 13.1572 -259.706364)
		(end 13.1572 -264.699242)
		(width 0.14605)
		(layer "In2.Cu")
		(net "HDD_PRSNT3")
	)
	(segment
		(start 12.076938 -218.42095)
		(end 12.076938 -256.858008)
		(width 0.14605)
		(layer "In2.Cu")
		(net "HDD_PRSNT3")
	)
	(segment
		(start 12.384786 -265.471656)
		(end 12.384786 -268.088364)
		(width 0.14605)
		(layer "In2.Cu")
		(net "HDD_PRSNT3")
	)
	(segment
		(start 11.731498 -393.4333)
		(end 11.731498 -395.60246)
		(width 0.14605)
		(layer "In2.Cu")
		(net "HDD_PRSNT3")
	)
	(segment
		(start 13.156946 -259.147564)
		(end 13.156946 -259.70611)
		(width 0.14605)
		(layer "In2.Cu")
		(net "HDD_PRSNT3")
	)
	(segment
		(start 12.84605 -374.793764)
		(end 12.328398 -375.311416)
		(width 0.14605)
		(layer "In2.Cu")
		(net "HDD_PRSNT3")
	)
	(segment
		(start 11.48334 -414.062164)
		(end 11.48334 -434.410866)
		(width 0.14605)
		(layer "In2.Cu")
		(net "HDD_PRSNT3")
	)
	(segment
		(start 12.639802 -258.630166)
		(end 12.643612 -258.63423)
		(width 0.14605)
		(layer "In2.Cu")
		(net "HDD_PRSNT3")
	)
	(segment
		(start 13.156946 -259.70611)
		(end 13.1572 -259.706364)
		(width 0.14605)
		(layer "In2.Cu")
		(net "HDD_PRSNT3")
	)
	(segment
		(start 11.657838 -413.887666)
		(end 11.48334 -414.062164)
		(width 0.14605)
		(layer "In2.Cu")
		(net "HDD_PRSNT3")
	)
	(segment
		(start 6.934962 -438.959244)
		(end 6.934962 -455.156316)
		(width 0.14605)
		(layer "In2.Cu")
		(net "HDD_PRSNT3")
	)
	(segment
		(start 13.1572 -264.699242)
		(end 12.384786 -265.471656)
		(width 0.14605)
		(layer "In2.Cu")
		(net "HDD_PRSNT3")
	)
	(segment
		(start 6.934962 -455.156316)
		(end 8.153146 -456.3745)
		(width 0.14605)
		(layer "In2.Cu")
		(net "HDD_PRSNT3")
	)
	(segment
		(start 11.657838 -395.675866)
		(end 11.657838 -413.887666)
		(width 0.14605)
		(layer "In2.Cu")
		(net "HDD_PRSNT3")
	)
	(segment
		(start 12.84605 -366.62106)
		(end 12.84605 -374.793764)
		(width 0.14605)
		(layer "In2.Cu")
		(net "HDD_PRSNT3")
	)
	(segment
		(start 8.153146 -456.3745)
		(end 8.153146 -456.4761)
		(width 0.14605)
		(layer "In2.Cu")
		(net "HDD_PRSNT3")
	)
	(segment
		(start 12.328398 -391.3632)
		(end 11.382248 -392.30935)
		(width 0.14605)
		(layer "In2.Cu")
		(net "HDD_PRSNT3")
	)
	(segment
		(start 23.84552 -467.864952)
		(end 24.659336 -467.051136)
		(width 0.14605)
		(layer "In5.Cu")
		(net "HDD_PRSNT3")
	)
	(segment
		(start 11.766804 -458.910944)
		(end 11.766804 -462.374234)
		(width 0.14605)
		(layer "In5.Cu")
		(net "HDD_PRSNT3")
	)
	(segment
		(start 10.281412 -456.13828)
		(end 10.354564 -456.211432)
		(width 0.14605)
		(layer "In5.Cu")
		(net "HDD_PRSNT3")
	)
	(segment
		(start 10.354564 -456.211432)
		(end 10.354564 -457.498704)
		(width 0.14605)
		(layer "In5.Cu")
		(net "HDD_PRSNT3")
	)
	(segment
		(start 11.766804 -462.374234)
		(end 14.549882 -465.157312)
		(width 0.14605)
		(layer "In5.Cu")
		(net "HDD_PRSNT3")
	)
	(segment
		(start 15.09522 -465.157312)
		(end 17.80286 -467.864952)
		(width 0.14605)
		(layer "In5.Cu")
		(net "HDD_PRSNT3")
	)
	(segment
		(start 221.008194 -386.090922)
		(end 221.008194 -385.998212)
		(width 0.14605)
		(layer "In5.Cu")
		(net "HDD_PRSNT3")
	)
	(segment
		(start 230.360728 -376.645678)
		(end 230.360728 -183.305196)
		(width 0.14605)
		(layer "In5.Cu")
		(net "HDD_PRSNT3")
	)
	(segment
		(start 10.354564 -457.498704)
		(end 11.766804 -458.910944)
		(width 0.14605)
		(layer "In5.Cu")
		(net "HDD_PRSNT3")
	)
	(segment
		(start 24.659336 -467.051136)
		(end 140.04798 -467.051136)
		(width 0.14605)
		(layer "In5.Cu")
		(net "HDD_PRSNT3")
	)
	(segment
		(start 140.04798 -467.051136)
		(end 221.008194 -386.090922)
		(width 0.14605)
		(layer "In5.Cu")
		(net "HDD_PRSNT3")
	)
	(segment
		(start 14.549882 -465.157312)
		(end 15.09522 -465.157312)
		(width 0.14605)
		(layer "In5.Cu")
		(net "HDD_PRSNT3")
	)
	(segment
		(start 17.80286 -467.864952)
		(end 23.84552 -467.864952)
		(width 0.14605)
		(layer "In5.Cu")
		(net "HDD_PRSNT3")
	)
	(segment
		(start 217.53957 -170.484038)
		(end 216.584784 -170.484038)
		(width 0.14605)
		(layer "In5.Cu")
		(net "HDD_PRSNT3")
	)
	(segment
		(start 230.360728 -183.305196)
		(end 217.53957 -170.484038)
		(width 0.14605)
		(layer "In5.Cu")
		(net "HDD_PRSNT3")
	)
	(segment
		(start 221.008194 -385.998212)
		(end 230.360728 -376.645678)
		(width 0.14605)
		(layer "In5.Cu")
		(net "HDD_PRSNT3")
	)
	(segment
		(start 37.083746 -106.5657)
		(end 36.829746 -106.5657)
		(width 0.111252)
		(layer "F.Cu")
		(net "SAS_EXP_A_PWR13")
	)
	(segment
		(start 10.922 -449.184522)
		(end 10.922 -449.27901)
		(width 0.111252)
		(layer "F.Cu")
		(net "SAS_EXP_A_PWR13")
	)
	(segment
		(start 35.924744 -107.470702)
		(end 35.940746 -107.4547)
		(width 0.111252)
		(layer "F.Cu")
		(net "SAS_EXP_A_PWR13")
	)
	(segment
		(start 35.940746 -107.4547)
		(end 36.829746 -106.5657)
		(width 0.111252)
		(layer "F.Cu")
		(net "SAS_EXP_A_PWR13")
	)
	(segment
		(start 11.063986 -449.042536)
		(end 10.922 -449.184522)
		(width 0.111252)
		(layer "F.Cu")
		(net "SAS_EXP_A_PWR13")
	)
	(segment
		(start 9.699752 -450.501258)
		(end 3.193542 -450.501258)
		(width 0.111252)
		(layer "F.Cu")
		(net "SAS_EXP_A_PWR13")
	)
	(segment
		(start 3.193542 -450.501258)
		(end 3.19024 -450.50456)
		(width 0.111252)
		(layer "F.Cu")
		(net "SAS_EXP_A_PWR13")
	)
	(segment
		(start 34.988246 -107.470702)
		(end 35.924744 -107.470702)
		(width 0.111252)
		(layer "F.Cu")
		(net "SAS_EXP_A_PWR13")
	)
	(segment
		(start 37.591746 -107.0737)
		(end 37.083746 -106.5657)
		(width 0.111252)
		(layer "F.Cu")
		(net "SAS_EXP_A_PWR13")
	)
	(segment
		(start 10.922 -449.27901)
		(end 9.699752 -450.501258)
		(width 0.111252)
		(layer "F.Cu")
		(net "SAS_EXP_A_PWR13")
	)
	(segment
		(start 37.591746 -108.423202)
		(end 37.591746 -107.0737)
		(width 0.111252)
		(layer "F.Cu")
		(net "SAS_EXP_A_PWR13")
	)
	(via
		(at 36.829746 -106.5657)
		(size 0.7112)
		(drill 0.3556)
		(layers "F.Cu" "B.Cu")
		(net "SAS_EXP_A_PWR13")
	)
	(via
		(at 11.063986 -449.042536)
		(size 0.5588)
		(drill 0.3048)
		(layers "F.Cu" "B.Cu")
		(net "SAS_EXP_A_PWR13")
	)
	(via
		(at 11.963654 -160.61817)
		(size 0.5588)
		(drill 0.3048)
		(layers "F.Cu" "B.Cu")
		(net "SAS_EXP_A_PWR13")
	)
	(via
		(at 35.940746 -107.4547)
		(size 0.5588)
		(drill 0.3048)
		(layers "F.Cu" "B.Cu")
		(net "SAS_EXP_A_PWR13")
	)
	(segment
		(start 15.649194 -214.333328)
		(end 15.683738 -214.367872)
		(width 0.14605)
		(layer "In2.Cu")
		(net "SAS_EXP_A_PWR13")
	)
	(segment
		(start 15.683738 -214.367872)
		(end 15.683738 -255.332738)
		(width 0.14605)
		(layer "In2.Cu")
		(net "SAS_EXP_A_PWR13")
	)
	(segment
		(start 16.322548 -364.634018)
		(end 16.45285 -364.76432)
		(width 0.14605)
		(layer "In2.Cu")
		(net "SAS_EXP_A_PWR13")
	)
	(segment
		(start 11.963654 -160.61817)
		(end 15.225776 -163.880292)
		(width 0.14605)
		(layer "In2.Cu")
		(net "SAS_EXP_A_PWR13")
	)
	(segment
		(start 19.008344 -357.924862)
		(end 16.322548 -360.610658)
		(width 0.14605)
		(layer "In2.Cu")
		(net "SAS_EXP_A_PWR13")
	)
	(segment
		(start 16.0528 -312.870596)
		(end 15.99184 -312.931556)
		(width 0.14605)
		(layer "In2.Cu")
		(net "SAS_EXP_A_PWR13")
	)
	(segment
		(start 15.264638 -415.383218)
		(end 15.09014 -415.557716)
		(width 0.14605)
		(layer "In2.Cu")
		(net "SAS_EXP_A_PWR13")
	)
	(segment
		(start 16.45285 -364.76432)
		(end 16.45285 -376.289316)
		(width 0.14605)
		(layer "In2.Cu")
		(net "SAS_EXP_A_PWR13")
	)
	(segment
		(start 16.018764 -376.723402)
		(end 15.99565 -376.839226)
		(width 0.14605)
		(layer "In2.Cu")
		(net "SAS_EXP_A_PWR13")
	)
	(segment
		(start 15.683738 -255.332738)
		(end 16.3068 -255.9558)
		(width 0.14605)
		(layer "In2.Cu")
		(net "SAS_EXP_A_PWR13")
	)
	(segment
		(start 16.3068 -257.195574)
		(end 18.487898 -259.376672)
		(width 0.14605)
		(layer "In2.Cu")
		(net "SAS_EXP_A_PWR13")
	)
	(segment
		(start 16.0528 -353.567238)
		(end 16.0528 -353.568)
		(width 0.14605)
		(layer "In2.Cu")
		(net "SAS_EXP_A_PWR13")
	)
	(segment
		(start 15.839948 -213.247478)
		(end 15.649194 -213.438232)
		(width 0.14605)
		(layer "In2.Cu")
		(net "SAS_EXP_A_PWR13")
	)
	(segment
		(start 15.09014 -442.020706)
		(end 11.063986 -446.04686)
		(width 0.14605)
		(layer "In2.Cu")
		(net "SAS_EXP_A_PWR13")
	)
	(segment
		(start 15.225776 -163.880292)
		(end 15.225776 -206.971392)
		(width 0.14605)
		(layer "In2.Cu")
		(net "SAS_EXP_A_PWR13")
	)
	(segment
		(start 11.063986 -446.04686)
		(end 11.063986 -449.042536)
		(width 0.14605)
		(layer "In2.Cu")
		(net "SAS_EXP_A_PWR13")
	)
	(segment
		(start 16.3068 -255.9558)
		(end 16.3068 -257.195574)
		(width 0.14605)
		(layer "In2.Cu")
		(net "SAS_EXP_A_PWR13")
	)
	(segment
		(start 16.322548 -360.610658)
		(end 16.322548 -364.634018)
		(width 0.14605)
		(layer "In2.Cu")
		(net "SAS_EXP_A_PWR13")
	)
	(segment
		(start 15.839948 -212.216746)
		(end 15.839948 -213.247478)
		(width 0.14605)
		(layer "In2.Cu")
		(net "SAS_EXP_A_PWR13")
	)
	(segment
		(start 15.225776 -206.971392)
		(end 14.718792 -207.478376)
		(width 0.14605)
		(layer "In2.Cu")
		(net "SAS_EXP_A_PWR13")
	)
	(segment
		(start 15.99184 -313.728608)
		(end 16.0528 -313.789568)
		(width 0.14605)
		(layer "In2.Cu")
		(net "SAS_EXP_A_PWR13")
	)
	(segment
		(start 15.414498 -395.189964)
		(end 15.414498 -397.02359)
		(width 0.14605)
		(layer "In2.Cu")
		(net "SAS_EXP_A_PWR13")
	)
	(segment
		(start 15.264638 -397.17345)
		(end 15.264638 -415.383218)
		(width 0.14605)
		(layer "In2.Cu")
		(net "SAS_EXP_A_PWR13")
	)
	(segment
		(start 15.99565 -394.608812)
		(end 15.414498 -395.189964)
		(width 0.14605)
		(layer "In2.Cu")
		(net "SAS_EXP_A_PWR13")
	)
	(segment
		(start 15.09014 -415.557716)
		(end 15.09014 -442.020706)
		(width 0.14605)
		(layer "In2.Cu")
		(net "SAS_EXP_A_PWR13")
	)
	(segment
		(start 15.99565 -376.839226)
		(end 15.99565 -394.608812)
		(width 0.14605)
		(layer "In2.Cu")
		(net "SAS_EXP_A_PWR13")
	)
	(segment
		(start 16.0528 -313.789568)
		(end 16.0528 -315.728858)
		(width 0.14605)
		(layer "In2.Cu")
		(net "SAS_EXP_A_PWR13")
	)
	(segment
		(start 15.992348 -312.272426)
		(end 15.994126 -312.32729)
		(width 0.14605)
		(layer "In2.Cu")
		(net "SAS_EXP_A_PWR13")
	)
	(segment
		(start 16.0528 -312.50255)
		(end 16.0528 -312.870596)
		(width 0.14605)
		(layer "In2.Cu")
		(net "SAS_EXP_A_PWR13")
	)
	(segment
		(start 15.99184 -312.931556)
		(end 15.99184 -313.728608)
		(width 0.14605)
		(layer "In2.Cu")
		(net "SAS_EXP_A_PWR13")
	)
	(segment
		(start 15.992348 -315.789564)
		(end 15.992348 -353.506786)
		(width 0.14605)
		(layer "In2.Cu")
		(net "SAS_EXP_A_PWR13")
	)
	(segment
		(start 16.45285 -376.289316)
		(end 16.018764 -376.723402)
		(width 0.14605)
		(layer "In2.Cu")
		(net "SAS_EXP_A_PWR13")
	)
	(segment
		(start 16.015208 -312.419238)
		(end 16.0528 -312.50255)
		(width 0.14605)
		(layer "In2.Cu")
		(net "SAS_EXP_A_PWR13")
	)
	(segment
		(start 19.008344 -356.523544)
		(end 19.008344 -357.924862)
		(width 0.14605)
		(layer "In2.Cu")
		(net "SAS_EXP_A_PWR13")
	)
	(segment
		(start 15.994126 -312.32729)
		(end 16.015208 -312.419238)
		(width 0.14605)
		(layer "In2.Cu")
		(net "SAS_EXP_A_PWR13")
	)
	(segment
		(start 15.992348 -353.506786)
		(end 16.0528 -353.567238)
		(width 0.14605)
		(layer "In2.Cu")
		(net "SAS_EXP_A_PWR13")
	)
	(segment
		(start 18.487898 -266.524486)
		(end 15.992348 -269.020036)
		(width 0.14605)
		(layer "In2.Cu")
		(net "SAS_EXP_A_PWR13")
	)
	(segment
		(start 16.0528 -353.568)
		(end 19.008344 -356.523544)
		(width 0.14605)
		(layer "In2.Cu")
		(net "SAS_EXP_A_PWR13")
	)
	(segment
		(start 16.0528 -315.728858)
		(end 15.992348 -315.789564)
		(width 0.14605)
		(layer "In2.Cu")
		(net "SAS_EXP_A_PWR13")
	)
	(segment
		(start 15.414498 -397.02359)
		(end 15.264638 -397.17345)
		(width 0.14605)
		(layer "In2.Cu")
		(net "SAS_EXP_A_PWR13")
	)
	(segment
		(start 14.718792 -211.09559)
		(end 15.839948 -212.216746)
		(width 0.14605)
		(layer "In2.Cu")
		(net "SAS_EXP_A_PWR13")
	)
	(segment
		(start 14.718792 -207.478376)
		(end 14.718792 -211.09559)
		(width 0.14605)
		(layer "In2.Cu")
		(net "SAS_EXP_A_PWR13")
	)
	(segment
		(start 18.487898 -259.376672)
		(end 18.487898 -266.524486)
		(width 0.14605)
		(layer "In2.Cu")
		(net "SAS_EXP_A_PWR13")
	)
	(segment
		(start 15.649194 -213.438232)
		(end 15.649194 -214.333328)
		(width 0.14605)
		(layer "In2.Cu")
		(net "SAS_EXP_A_PWR13")
	)
	(segment
		(start 15.992348 -269.020036)
		(end 15.992348 -312.272426)
		(width 0.14605)
		(layer "In2.Cu")
		(net "SAS_EXP_A_PWR13")
	)
	(segment
		(start 15.192502 -128.171702)
		(end 14.760702 -127.739902)
		(width 0.14605)
		(layer "In5.Cu")
		(net "SAS_EXP_A_PWR13")
	)
	(segment
		(start 31.127446 -112.268)
		(end 35.940746 -107.4547)
		(width 0.14605)
		(layer "In5.Cu")
		(net "SAS_EXP_A_PWR13")
	)
	(segment
		(start 17.59077 -112.268)
		(end 31.127446 -112.268)
		(width 0.14605)
		(layer "In5.Cu")
		(net "SAS_EXP_A_PWR13")
	)
	(segment
		(start 12.217146 -144.2974)
		(end 13.843254 -142.671292)
		(width 0.14605)
		(layer "In5.Cu")
		(net "SAS_EXP_A_PWR13")
	)
	(segment
		(start 11.4046 -160.059116)
		(end 11.4046 -158.75)
		(width 0.14605)
		(layer "In5.Cu")
		(net "SAS_EXP_A_PWR13")
	)
	(segment
		(start 11.4046 -158.75)
		(end 9.172194 -156.517594)
		(width 0.14605)
		(layer "In5.Cu")
		(net "SAS_EXP_A_PWR13")
	)
	(segment
		(start 13.843254 -142.671292)
		(end 13.843254 -136.11606)
		(width 0.14605)
		(layer "In5.Cu")
		(net "SAS_EXP_A_PWR13")
	)
	(segment
		(start 13.843254 -136.11606)
		(end 15.192502 -134.766812)
		(width 0.14605)
		(layer "In5.Cu")
		(net "SAS_EXP_A_PWR13")
	)
	(segment
		(start 11.963654 -160.61817)
		(end 11.4046 -160.059116)
		(width 0.14605)
		(layer "In5.Cu")
		(net "SAS_EXP_A_PWR13")
	)
	(segment
		(start 9.172194 -156.517594)
		(end 9.172194 -146.645376)
		(width 0.14605)
		(layer "In5.Cu")
		(net "SAS_EXP_A_PWR13")
	)
	(segment
		(start 14.760702 -115.098068)
		(end 17.59077 -112.268)
		(width 0.14605)
		(layer "In5.Cu")
		(net "SAS_EXP_A_PWR13")
	)
	(segment
		(start 11.52017 -144.2974)
		(end 12.217146 -144.2974)
		(width 0.14605)
		(layer "In5.Cu")
		(net "SAS_EXP_A_PWR13")
	)
	(segment
		(start 15.192502 -134.766812)
		(end 15.192502 -128.171702)
		(width 0.14605)
		(layer "In5.Cu")
		(net "SAS_EXP_A_PWR13")
	)
	(segment
		(start 9.172194 -146.645376)
		(end 11.52017 -144.2974)
		(width 0.14605)
		(layer "In5.Cu")
		(net "SAS_EXP_A_PWR13")
	)
	(segment
		(start 14.760702 -127.739902)
		(end 14.760702 -115.098068)
		(width 0.14605)
		(layer "In5.Cu")
		(net "SAS_EXP_A_PWR13")
	)
	(segment
		(start 23.172166 -139.950444)
		(end 23.172166 -139.74826)
		(width 0.09525)
		(layer "F.Cu")
		(net "SAS2X28_DRIVE_RX_N_A13")
	)
	(segment
		(start 25.387808 -139.76223)
		(end 25.57653 -139.950952)
		(width 0.09525)
		(layer "F.Cu")
		(net "SAS2X28_DRIVE_RX_N_A13")
	)
	(segment
		(start 23.273766 -139.64666)
		(end 24.962358 -139.64666)
		(width 0.09525)
		(layer "F.Cu")
		(net "SAS2X28_DRIVE_RX_N_A13")
	)
	(segment
		(start 23.110952 -140.058648)
		(end 23.138892 -140.030708)
		(width 0.09525)
		(layer "F.Cu")
		(net "SAS2X28_DRIVE_RX_N_A13")
	)
	(segment
		(start 21.75002 -140.119862)
		(end 22.963124 -140.119862)
		(width 0.09525)
		(layer "F.Cu")
		(net "SAS2X28_DRIVE_RX_N_A13")
	)
	(arc
		(start 25.061672 -139.642596)
		(mid 25.237939 -139.666446)
		(end 25.387808 -139.76223)
		(width 0.09525)
		(layer "F.Cu")
		(net "SAS2X28_DRIVE_RX_N_A13")
	)
	(arc
		(start 23.172166 -139.74826)
		(mid 23.190901 -139.689392)
		(end 23.240238 -139.652248)
		(width 0.09525)
		(layer "F.Cu")
		(net "SAS2X28_DRIVE_RX_N_A13")
	)
	(arc
		(start 22.963124 -140.119862)
		(mid 23.043121 -140.10395)
		(end 23.110952 -140.058648)
		(width 0.09525)
		(layer "F.Cu")
		(net "SAS2X28_DRIVE_RX_N_A13")
	)
	(arc
		(start 24.962358 -139.64666)
		(mid 25.012057 -139.645661)
		(end 25.061672 -139.642596)
		(width 0.09525)
		(layer "F.Cu")
		(net "SAS2X28_DRIVE_RX_N_A13")
	)
	(arc
		(start 23.138892 -140.030708)
		(mid 23.163498 -139.993883)
		(end 23.172166 -139.950444)
		(width 0.09525)
		(layer "F.Cu")
		(net "SAS2X28_DRIVE_RX_N_A13")
	)
	(arc
		(start 23.240238 -139.652248)
		(mid 23.256766 -139.648035)
		(end 23.273766 -139.64666)
		(width 0.09525)
		(layer "F.Cu")
		(net "SAS2X28_DRIVE_RX_N_A13")
	)
	(segment
		(start 20.877276 -133.4389)
		(end 25.31237 -133.4389)
		(width 0.09525)
		(layer "F.Cu")
		(net "SAS2X28_DRIVE_RX_N_B13")
	)
	(segment
		(start 20.362164 -133.609842)
		(end 20.365466 -133.60654)
		(width 0.09525)
		(layer "F.Cu")
		(net "SAS2X28_DRIVE_RX_N_B13")
	)
	(segment
		(start 19.600164 -133.609842)
		(end 20.362164 -133.609842)
		(width 0.09525)
		(layer "F.Cu")
		(net "SAS2X28_DRIVE_RX_N_B13")
	)
	(arc
		(start 20.365466 -133.60654)
		(mid 20.567387 -133.577008)
		(end 20.752308 -133.490716)
		(width 0.09525)
		(layer "F.Cu")
		(net "SAS2X28_DRIVE_RX_N_B13")
	)
	(arc
		(start 25.31237 -133.4389)
		(mid 25.524075 -133.481011)
		(end 25.70353 -133.600952)
		(width 0.09525)
		(layer "F.Cu")
		(net "SAS2X28_DRIVE_RX_N_B13")
	)
	(arc
		(start 20.752308 -133.490716)
		(mid 20.809644 -133.452405)
		(end 20.877276 -133.4389)
		(width 0.09525)
		(layer "F.Cu")
		(net "SAS2X28_DRIVE_RX_N_B13")
	)
	(segment
		(start 42.952924 -207.430878)
		(end 43.179746 -207.6577)
		(width 0.111252)
		(layer "F.Cu")
		(net "SAS_EXP_A_PWR12")
	)
	(segment
		(start 43.306746 -206.340202)
		(end 43.306746 -206.875888)
		(width 0.111252)
		(layer "F.Cu")
		(net "SAS_EXP_A_PWR12")
	)
	(segment
		(start 12.0396 -448.3735)
		(end 10.413746 -448.3735)
		(width 0.111252)
		(layer "F.Cu")
		(net "SAS_EXP_A_PWR12")
	)
	(segment
		(start 9.285986 -449.50126)
		(end 3.193542 -449.50126)
		(width 0.111252)
		(layer "F.Cu")
		(net "SAS_EXP_A_PWR12")
	)
	(segment
		(start 3.193542 -449.50126)
		(end 3.19024 -449.504562)
		(width 0.111252)
		(layer "F.Cu")
		(net "SAS_EXP_A_PWR12")
	)
	(segment
		(start 42.952924 -207.22971)
		(end 42.952924 -207.430878)
		(width 0.111252)
		(layer "F.Cu")
		(net "SAS_EXP_A_PWR12")
	)
	(segment
		(start 43.306746 -206.875888)
		(end 42.952924 -207.22971)
		(width 0.111252)
		(layer "F.Cu")
		(net "SAS_EXP_A_PWR12")
	)
	(segment
		(start 10.413746 -448.3735)
		(end 9.285986 -449.50126)
		(width 0.111252)
		(layer "F.Cu")
		(net "SAS_EXP_A_PWR12")
	)
	(segment
		(start 43.179746 -207.6577)
		(end 43.179746 -208.372202)
		(width 0.111252)
		(layer "F.Cu")
		(net "SAS_EXP_A_PWR12")
	)
	(via
		(at 42.952924 -207.22971)
		(size 0.5588)
		(drill 0.3048)
		(layers "F.Cu" "B.Cu")
		(net "SAS_EXP_A_PWR12")
	)
	(via
		(at 15.496286 -462.87436)
		(size 0.5588)
		(drill 0.3048)
		(layers "F.Cu" "B.Cu")
		(net "SAS_EXP_A_PWR12")
	)
	(via
		(at 12.0396 -448.3735)
		(size 0.5588)
		(drill 0.3048)
		(layers "F.Cu" "B.Cu")
		(net "SAS_EXP_A_PWR12")
	)
	(via
		(at 36.067746 -448.1957)
		(size 0.5588)
		(drill 0.3048)
		(layers "F.Cu" "B.Cu")
		(net "SAS_EXP_A_PWR12")
	)
	(via
		(at 30.772354 -458.502512)
		(size 0.7112)
		(drill 0.3556)
		(layers "F.Cu" "B.Cu")
		(net "SAS_EXP_A_PWR12")
	)
	(segment
		(start 36.067746 -453.20712)
		(end 30.772354 -458.502512)
		(width 0.111252)
		(layer "B.Cu")
		(net "SAS_EXP_A_PWR12")
	)
	(segment
		(start 17.977358 -462.87436)
		(end 20.972018 -459.8797)
		(width 0.111252)
		(layer "B.Cu")
		(net "SAS_EXP_A_PWR12")
	)
	(segment
		(start 20.972018 -459.8797)
		(end 29.395166 -459.8797)
		(width 0.111252)
		(layer "B.Cu")
		(net "SAS_EXP_A_PWR12")
	)
	(segment
		(start 29.395166 -459.8797)
		(end 30.772354 -458.502512)
		(width 0.111252)
		(layer "B.Cu")
		(net "SAS_EXP_A_PWR12")
	)
	(segment
		(start 36.067746 -448.1957)
		(end 36.067746 -453.20712)
		(width 0.111252)
		(layer "B.Cu")
		(net "SAS_EXP_A_PWR12")
	)
	(segment
		(start 15.496286 -462.87436)
		(end 17.977358 -462.87436)
		(width 0.111252)
		(layer "B.Cu")
		(net "SAS_EXP_A_PWR12")
	)
	(segment
		(start 42.952924 -207.22971)
		(end 42.952924 -207.976724)
		(width 0.14605)
		(layer "In5.Cu")
		(net "SAS_EXP_A_PWR12")
	)
	(segment
		(start 86.080346 -409.496768)
		(end 47.432214 -448.1449)
		(width 0.14605)
		(layer "In5.Cu")
		(net "SAS_EXP_A_PWR12")
	)
	(segment
		(start 12.0396 -448.3735)
		(end 12.079986 -448.3735)
		(width 0.14605)
		(layer "In5.Cu")
		(net "SAS_EXP_A_PWR12")
	)
	(segment
		(start 15.467584 -462.845658)
		(end 15.496286 -462.87436)
		(width 0.14605)
		(layer "In5.Cu")
		(net "SAS_EXP_A_PWR12")
	)
	(segment
		(start 14.039596 -450.33311)
		(end 14.039596 -460.904336)
		(width 0.14605)
		(layer "In5.Cu")
		(net "SAS_EXP_A_PWR12")
	)
	(segment
		(start 14.039596 -460.904336)
		(end 14.071346 -460.936086)
		(width 0.14605)
		(layer "In5.Cu")
		(net "SAS_EXP_A_PWR12")
	)
	(segment
		(start 15.467584 -462.548732)
		(end 15.467584 -462.845658)
		(width 0.14605)
		(layer "In5.Cu")
		(net "SAS_EXP_A_PWR12")
	)
	(segment
		(start 79.418942 -270.547846)
		(end 86.080346 -277.20925)
		(width 0.14605)
		(layer "In5.Cu")
		(net "SAS_EXP_A_PWR12")
	)
	(segment
		(start 12.079986 -448.3735)
		(end 14.039596 -450.33311)
		(width 0.14605)
		(layer "In5.Cu")
		(net "SAS_EXP_A_PWR12")
	)
	(segment
		(start 42.952924 -207.976724)
		(end 79.418942 -244.442742)
		(width 0.14605)
		(layer "In5.Cu")
		(net "SAS_EXP_A_PWR12")
	)
	(segment
		(start 79.418942 -244.442742)
		(end 79.418942 -270.547846)
		(width 0.14605)
		(layer "In5.Cu")
		(net "SAS_EXP_A_PWR12")
	)
	(segment
		(start 86.080346 -277.20925)
		(end 86.080346 -409.496768)
		(width 0.14605)
		(layer "In5.Cu")
		(net "SAS_EXP_A_PWR12")
	)
	(segment
		(start 36.118546 -448.1449)
		(end 36.067746 -448.1957)
		(width 0.14605)
		(layer "In5.Cu")
		(net "SAS_EXP_A_PWR12")
	)
	(segment
		(start 47.432214 -448.1449)
		(end 36.118546 -448.1449)
		(width 0.14605)
		(layer "In5.Cu")
		(net "SAS_EXP_A_PWR12")
	)
	(segment
		(start 14.071346 -460.936086)
		(end 14.071346 -461.152494)
		(width 0.14605)
		(layer "In5.Cu")
		(net "SAS_EXP_A_PWR12")
	)
	(segment
		(start 14.071346 -461.152494)
		(end 15.467584 -462.548732)
		(width 0.14605)
		(layer "In5.Cu")
		(net "SAS_EXP_A_PWR12")
	)
	(segment
		(start 23.273766 -242.646708)
		(end 25.381966 -242.646708)
		(width 0.09525)
		(layer "F.Cu")
		(net "SAS2X28_DRIVE_RX_N_A12")
	)
	(segment
		(start 23.172166 -242.934236)
		(end 23.172166 -242.748308)
		(width 0.09525)
		(layer "F.Cu")
		(net "SAS2X28_DRIVE_RX_N_A12")
	)
	(segment
		(start 21.75002 -243.11991)
		(end 22.986492 -243.11991)
		(width 0.09525)
		(layer "F.Cu")
		(net "SAS2X28_DRIVE_RX_N_A12")
	)
	(segment
		(start 23.242524 -242.65128)
		(end 23.242778 -242.65128)
		(width 0.09525)
		(layer "F.Cu")
		(net "SAS2X28_DRIVE_RX_N_A12")
	)
	(arc
		(start 25.381966 -242.646708)
		(mid 25.775924 -242.725071)
		(end 26.10993 -242.948206)
		(width 0.09525)
		(layer "F.Cu")
		(net "SAS2X28_DRIVE_RX_N_A12")
	)
	(arc
		(start 22.986492 -243.11991)
		(mid 23.117783 -243.065527)
		(end 23.172166 -242.934236)
		(width 0.09525)
		(layer "F.Cu")
		(net "SAS2X28_DRIVE_RX_N_A12")
	)
	(arc
		(start 23.242778 -242.65128)
		(mid 23.258094 -242.647781)
		(end 23.273766 -242.646708)
		(width 0.09525)
		(layer "F.Cu")
		(net "SAS2X28_DRIVE_RX_N_A12")
	)
	(arc
		(start 23.172166 -242.748308)
		(mid 23.191529 -242.688308)
		(end 23.242524 -242.65128)
		(width 0.09525)
		(layer "F.Cu")
		(net "SAS2X28_DRIVE_RX_N_A12")
	)
	(segment
		(start 21.188934 -236.318806)
		(end 24.287988 -236.318806)
		(width 0.09525)
		(layer "F.Cu")
		(net "SAS2X28_DRIVE_RX_N_B12")
	)
	(segment
		(start 19.600164 -236.60989)
		(end 20.48637 -236.60989)
		(width 0.09525)
		(layer "F.Cu")
		(net "SAS2X28_DRIVE_RX_N_B12")
	)
	(segment
		(start 24.962612 -236.598206)
		(end 25.34793 -236.598206)
		(width 0.09525)
		(layer "F.Cu")
		(net "SAS2X28_DRIVE_RX_N_B12")
	)
	(arc
		(start 20.837652 -236.464348)
		(mid 20.998822 -236.356658)
		(end 21.188934 -236.318806)
		(width 0.09525)
		(layer "F.Cu")
		(net "SAS2X28_DRIVE_RX_N_B12")
	)
	(arc
		(start 24.287988 -236.318806)
		(mid 24.470533 -236.355116)
		(end 24.6253 -236.458506)
		(width 0.09525)
		(layer "F.Cu")
		(net "SAS2X28_DRIVE_RX_N_B12")
	)
	(arc
		(start 20.48637 -236.60989)
		(mid 20.676496 -236.572072)
		(end 20.837652 -236.464348)
		(width 0.09525)
		(layer "F.Cu")
		(net "SAS2X28_DRIVE_RX_N_B12")
	)
	(arc
		(start 24.6253 -236.458506)
		(mid 24.78006 -236.561913)
		(end 24.962612 -236.598206)
		(width 0.09525)
		(layer "F.Cu")
		(net "SAS2X28_DRIVE_RX_N_B12")
	)
	(segment
		(start 27.608022 -338.798154)
		(end 27.743912 -338.66201)
		(width 0.09525)
		(layer "F.Cu")
		(net "SAS2X28_B_HDD11_RX_+")
	)
	(segment
		(start 26.923746 -338.976208)
		(end 27.177746 -338.976208)
		(width 0.09525)
		(layer "F.Cu")
		(net "SAS2X28_B_HDD11_RX_+")
	)
	(segment
		(start 26.435812 -338.696808)
		(end 26.567892 -338.828634)
		(width 0.09525)
		(layer "F.Cu")
		(net "SAS2X28_B_HDD11_RX_+")
	)
	(via
		(at 27.743912 -338.66201)
		(size 0.5588)
		(drill 0.3048)
		(layers "F.Cu" "B.Cu")
		(net "SAS2X28_B_HDD11_RX_+")
	)
	(arc
		(start 27.177746 -338.976208)
		(mid 27.410598 -338.929985)
		(end 27.608022 -338.798154)
		(width 0.09525)
		(layer "F.Cu")
		(net "SAS2X28_B_HDD11_RX_+")
	)
	(arc
		(start 26.567892 -338.828634)
		(mid 26.731144 -338.937809)
		(end 26.923746 -338.976208)
		(width 0.09525)
		(layer "F.Cu")
		(net "SAS2X28_B_HDD11_RX_+")
	)
	(segment
		(start 25.666446 -268.29766)
		(end 25.6667 -268.297914)
		(width 0.09525)
		(layer "B.Cu")
		(net "SAS2X28_B_HDD11_RX_+")
	)
	(segment
		(start 25.899872 -268.06398)
		(end 29.57068 -264.39368)
		(width 0.09525)
		(layer "B.Cu")
		(net "SAS2X28_B_HDD11_RX_+")
	)
	(segment
		(start 4.691888 -163.498784)
		(end 2.811526 -163.498784)
		(width 0.09525)
		(layer "B.Cu")
		(net "SAS2X28_B_HDD11_RX_+")
	)
	(segment
		(start 29.57068 -264.39368)
		(end 30.185106 -263.779254)
		(width 0.09525)
		(layer "B.Cu")
		(net "SAS2X28_B_HDD11_RX_+")
	)
	(segment
		(start 25.089866 -337.754214)
		(end 25.089866 -269.68958)
		(width 0.09525)
		(layer "B.Cu")
		(net "SAS2X28_B_HDD11_RX_+")
	)
	(segment
		(start 25.856946 -338.7979)
		(end 25.285446 -338.2264)
		(width 0.09525)
		(layer "B.Cu")
		(net "SAS2X28_B_HDD11_RX_+")
	)
	(segment
		(start 25.6667 -268.297914)
		(end 25.900126 -268.064234)
		(width 0.09525)
		(layer "B.Cu")
		(net "SAS2X28_B_HDD11_RX_+")
	)
	(segment
		(start 27.126946 -338.9757)
		(end 26.286206 -338.9757)
		(width 0.09525)
		(layer "B.Cu")
		(net "SAS2X28_B_HDD11_RX_+")
	)
	(segment
		(start 4.693412 -163.500308)
		(end 4.691888 -163.498784)
		(width 0.09525)
		(layer "B.Cu")
		(net "SAS2X28_B_HDD11_RX_+")
	)
	(segment
		(start 30.784546 -262.330946)
		(end 30.784546 -190.277496)
		(width 0.09525)
		(layer "B.Cu")
		(net "SAS2X28_B_HDD11_RX_+")
	)
	(segment
		(start 14.096746 -171.39793)
		(end 14.096746 -164.739828)
		(width 0.09525)
		(layer "B.Cu")
		(net "SAS2X28_B_HDD11_RX_+")
	)
	(segment
		(start 13.18768 -163.830508)
		(end 5.490718 -163.830508)
		(width 0.09525)
		(layer "B.Cu")
		(net "SAS2X28_B_HDD11_RX_+")
	)
	(segment
		(start 25.900126 -268.064234)
		(end 25.899872 -268.06398)
		(width 0.09525)
		(layer "B.Cu")
		(net "SAS2X28_B_HDD11_RX_+")
	)
	(segment
		(start 27.743912 -338.66201)
		(end 27.644852 -338.761324)
		(width 0.09525)
		(layer "B.Cu")
		(net "SAS2X28_B_HDD11_RX_+")
	)
	(segment
		(start 30.034992 -188.467746)
		(end 14.896846 -173.3296)
		(width 0.09525)
		(layer "B.Cu")
		(net "SAS2X28_B_HDD11_RX_+")
	)
	(arc
		(start 27.644852 -338.761324)
		(mid 27.40722 -338.920012)
		(end 27.126946 -338.9757)
		(width 0.09525)
		(layer "B.Cu")
		(net "SAS2X28_B_HDD11_RX_+")
	)
	(arc
		(start 30.784546 -190.277496)
		(mid 30.589799 -189.298053)
		(end 30.034992 -188.467746)
		(width 0.09525)
		(layer "B.Cu")
		(net "SAS2X28_B_HDD11_RX_+")
	)
	(arc
		(start 14.896846 -173.3296)
		(mid 14.304668 -172.443342)
		(end 14.096746 -171.39793)
		(width 0.09525)
		(layer "B.Cu")
		(net "SAS2X28_B_HDD11_RX_+")
	)
	(arc
		(start 5.490718 -163.830508)
		(mid 5.357941 -163.804097)
		(end 5.245354 -163.728908)
		(width 0.09525)
		(layer "B.Cu")
		(net "SAS2X28_B_HDD11_RX_+")
	)
	(arc
		(start 30.185106 -263.779254)
		(mid 30.628884 -263.11472)
		(end 30.784546 -262.330946)
		(width 0.09525)
		(layer "B.Cu")
		(net "SAS2X28_B_HDD11_RX_+")
	)
	(arc
		(start 14.096746 -164.739828)
		(mid 14.027494 -164.391763)
		(end 13.8303 -164.0967)
		(width 0.09525)
		(layer "B.Cu")
		(net "SAS2X28_B_HDD11_RX_+")
	)
	(arc
		(start 5.245354 -163.728908)
		(mid 4.992121 -163.559703)
		(end 4.693412 -163.500308)
		(width 0.09525)
		(layer "B.Cu")
		(net "SAS2X28_B_HDD11_RX_+")
	)
	(arc
		(start 25.089866 -269.68958)
		(mid 25.239709 -268.936268)
		(end 25.666446 -268.29766)
		(width 0.09525)
		(layer "B.Cu")
		(net "SAS2X28_B_HDD11_RX_+")
	)
	(arc
		(start 13.8303 -164.0967)
		(mid 13.535463 -163.899697)
		(end 13.18768 -163.830508)
		(width 0.09525)
		(layer "B.Cu")
		(net "SAS2X28_B_HDD11_RX_+")
	)
	(arc
		(start 26.286206 -338.9757)
		(mid 26.053894 -338.92949)
		(end 25.856946 -338.7979)
		(width 0.09525)
		(layer "B.Cu")
		(net "SAS2X28_B_HDD11_RX_+")
	)
	(arc
		(start 25.285446 -338.2264)
		(mid 25.140691 -338.009759)
		(end 25.089866 -337.754214)
		(width 0.09525)
		(layer "B.Cu")
		(net "SAS2X28_B_HDD11_RX_+")
	)
	(segment
		(start 31.495746 -279.9207)
		(end 30.098746 -278.5237)
		(width 0.111252)
		(layer "F.Cu")
		(net "SAS_EXP_A_PWR7")
	)
	(segment
		(start 3.193542 -454.50125)
		(end 3.19024 -454.504552)
		(width 0.111252)
		(layer "F.Cu")
		(net "SAS_EXP_A_PWR7")
	)
	(segment
		(start 31.495746 -279.200102)
		(end 31.68142 -279.014428)
		(width 0.111252)
		(layer "F.Cu")
		(net "SAS_EXP_A_PWR7")
	)
	(segment
		(start 7.85241 -454.50125)
		(end 3.193542 -454.50125)
		(width 0.111252)
		(layer "F.Cu")
		(net "SAS_EXP_A_PWR7")
	)
	(segment
		(start 31.495746 -280.0477)
		(end 31.495746 -279.9207)
		(width 0.111252)
		(layer "F.Cu")
		(net "SAS_EXP_A_PWR7")
	)
	(segment
		(start 30.098746 -278.5237)
		(end 29.527246 -278.5237)
		(width 0.111252)
		(layer "F.Cu")
		(net "SAS_EXP_A_PWR7")
	)
	(segment
		(start 31.495746 -279.9207)
		(end 31.495746 -279.200102)
		(width 0.111252)
		(layer "F.Cu")
		(net "SAS_EXP_A_PWR7")
	)
	(segment
		(start 8.079994 -454.728834)
		(end 7.85241 -454.50125)
		(width 0.111252)
		(layer "F.Cu")
		(net "SAS_EXP_A_PWR7")
	)
	(via
		(at 31.495746 -280.0477)
		(size 0.5588)
		(drill 0.3048)
		(layers "F.Cu" "B.Cu")
		(net "SAS_EXP_A_PWR7")
	)
	(via
		(at 25.399746 -445.40805)
		(size 0.5588)
		(drill 0.3048)
		(layers "F.Cu" "B.Cu")
		(net "SAS_EXP_A_PWR7")
	)
	(via
		(at 30.729428 -279.332182)
		(size 0.7112)
		(drill 0.3556)
		(layers "F.Cu" "B.Cu")
		(net "SAS_EXP_A_PWR7")
	)
	(via
		(at 8.079994 -454.728834)
		(size 0.5588)
		(drill 0.3048)
		(layers "F.Cu" "B.Cu")
		(net "SAS_EXP_A_PWR7")
	)
	(segment
		(start 8.644128 -454.1647)
		(end 8.079994 -454.728834)
		(width 0.111252)
		(layer "B.Cu")
		(net "SAS_EXP_A_PWR7")
	)
	(segment
		(start 15.601188 -454.032874)
		(end 15.532862 -454.1012)
		(width 0.111252)
		(layer "B.Cu")
		(net "SAS_EXP_A_PWR7")
	)
	(segment
		(start 9.708388 -454.159874)
		(end 9.38403 -454.159874)
		(width 0.111252)
		(layer "B.Cu")
		(net "SAS_EXP_A_PWR7")
	)
	(segment
		(start 16.052038 -454.0377)
		(end 16.047212 -454.032874)
		(width 0.111252)
		(layer "B.Cu")
		(net "SAS_EXP_A_PWR7")
	)
	(segment
		(start 9.379204 -454.1647)
		(end 8.644128 -454.1647)
		(width 0.111252)
		(layer "B.Cu")
		(net "SAS_EXP_A_PWR7")
	)
	(segment
		(start 25.399746 -445.40805)
		(end 25.399746 -446.227454)
		(width 0.111252)
		(layer "B.Cu")
		(net "SAS_EXP_A_PWR7")
	)
	(segment
		(start 25.399746 -446.227454)
		(end 17.5895 -454.0377)
		(width 0.111252)
		(layer "B.Cu")
		(net "SAS_EXP_A_PWR7")
	)
	(segment
		(start 9.767062 -454.1012)
		(end 9.708388 -454.159874)
		(width 0.111252)
		(layer "B.Cu")
		(net "SAS_EXP_A_PWR7")
	)
	(segment
		(start 15.532862 -454.1012)
		(end 9.767062 -454.1012)
		(width 0.111252)
		(layer "B.Cu")
		(net "SAS_EXP_A_PWR7")
	)
	(segment
		(start 31.495746 -280.0477)
		(end 31.394146 -279.9969)
		(width 0.111252)
		(layer "B.Cu")
		(net "SAS_EXP_A_PWR7")
	)
	(segment
		(start 16.047212 -454.032874)
		(end 15.601188 -454.032874)
		(width 0.111252)
		(layer "B.Cu")
		(net "SAS_EXP_A_PWR7")
	)
	(segment
		(start 17.5895 -454.0377)
		(end 16.052038 -454.0377)
		(width 0.111252)
		(layer "B.Cu")
		(net "SAS_EXP_A_PWR7")
	)
	(segment
		(start 31.394146 -279.9969)
		(end 30.729428 -279.332182)
		(width 0.111252)
		(layer "B.Cu")
		(net "SAS_EXP_A_PWR7")
	)
	(segment
		(start 9.38403 -454.159874)
		(end 9.379204 -454.1647)
		(width 0.111252)
		(layer "B.Cu")
		(net "SAS_EXP_A_PWR7")
	)
	(segment
		(start 48.983646 -298.173394)
		(end 48.983646 -279.546304)
		(width 0.14605)
		(layer "In5.Cu")
		(net "SAS_EXP_A_PWR7")
	)
	(segment
		(start 48.983646 -279.546304)
		(end 48.98263 -279.544018)
		(width 0.14605)
		(layer "In5.Cu")
		(net "SAS_EXP_A_PWR7")
	)
	(segment
		(start 42.858436 -273.419824)
		(end 42.465498 -273.419824)
		(width 0.14605)
		(layer "In5.Cu")
		(net "SAS_EXP_A_PWR7")
	)
	(segment
		(start 32.8676 -278.675846)
		(end 31.495746 -280.0477)
		(width 0.14605)
		(layer "In5.Cu")
		(net "SAS_EXP_A_PWR7")
	)
	(segment
		(start 40.659812 -271.2212)
		(end 33.792922 -271.2212)
		(width 0.14605)
		(layer "In5.Cu")
		(net "SAS_EXP_A_PWR7")
	)
	(segment
		(start 41.679622 -272.633948)
		(end 41.679622 -272.24101)
		(width 0.14605)
		(layer "In5.Cu")
		(net "SAS_EXP_A_PWR7")
	)
	(segment
		(start 82.3468 -395.2494)
		(end 82.3468 -331.536548)
		(width 0.14605)
		(layer "In5.Cu")
		(net "SAS_EXP_A_PWR7")
	)
	(segment
		(start 42.465498 -273.419824)
		(end 42.13987 -273.745452)
		(width 0.14605)
		(layer "In5.Cu")
		(net "SAS_EXP_A_PWR7")
	)
	(segment
		(start 25.399746 -445.40805)
		(end 25.660096 -445.1477)
		(width 0.14605)
		(layer "In5.Cu")
		(net "SAS_EXP_A_PWR7")
	)
	(segment
		(start 82.3468 -331.536548)
		(end 48.983646 -298.173394)
		(width 0.14605)
		(layer "In5.Cu")
		(net "SAS_EXP_A_PWR7")
	)
	(segment
		(start 41.679622 -273.745452)
		(end 41.353994 -273.419824)
		(width 0.14605)
		(layer "In5.Cu")
		(net "SAS_EXP_A_PWR7")
	)
	(segment
		(start 25.660096 -445.1477)
		(end 46.805342 -445.1477)
		(width 0.14605)
		(layer "In5.Cu")
		(net "SAS_EXP_A_PWR7")
	)
	(segment
		(start 41.353994 -272.959576)
		(end 41.679622 -272.633948)
		(width 0.14605)
		(layer "In5.Cu")
		(net "SAS_EXP_A_PWR7")
	)
	(segment
		(start 33.792922 -271.2212)
		(end 33.528 -271.486122)
		(width 0.14605)
		(layer "In5.Cu")
		(net "SAS_EXP_A_PWR7")
	)
	(segment
		(start 32.8676 -276.987)
		(end 32.8676 -278.675846)
		(width 0.14605)
		(layer "In5.Cu")
		(net "SAS_EXP_A_PWR7")
	)
	(segment
		(start 33.528 -271.486122)
		(end 33.528 -276.3266)
		(width 0.14605)
		(layer "In5.Cu")
		(net "SAS_EXP_A_PWR7")
	)
	(segment
		(start 41.679622 -272.24101)
		(end 40.659812 -271.2212)
		(width 0.14605)
		(layer "In5.Cu")
		(net "SAS_EXP_A_PWR7")
	)
	(segment
		(start 46.805342 -445.1477)
		(end 82.822796 -409.130246)
		(width 0.14605)
		(layer "In5.Cu")
		(net "SAS_EXP_A_PWR7")
	)
	(segment
		(start 82.822796 -409.130246)
		(end 82.822796 -395.725396)
		(width 0.14605)
		(layer "In5.Cu")
		(net "SAS_EXP_A_PWR7")
	)
	(segment
		(start 42.13987 -273.745452)
		(end 41.679622 -273.745452)
		(width 0.14605)
		(layer "In5.Cu")
		(net "SAS_EXP_A_PWR7")
	)
	(segment
		(start 82.822796 -395.725396)
		(end 82.3468 -395.2494)
		(width 0.14605)
		(layer "In5.Cu")
		(net "SAS_EXP_A_PWR7")
	)
	(segment
		(start 41.353994 -273.419824)
		(end 41.353994 -272.959576)
		(width 0.14605)
		(layer "In5.Cu")
		(net "SAS_EXP_A_PWR7")
	)
	(segment
		(start 33.528 -276.3266)
		(end 32.8676 -276.987)
		(width 0.14605)
		(layer "In5.Cu")
		(net "SAS_EXP_A_PWR7")
	)
	(segment
		(start 48.98263 -279.544018)
		(end 42.858436 -273.419824)
		(width 0.14605)
		(layer "In5.Cu")
		(net "SAS_EXP_A_PWR7")
	)
	(segment
		(start 23.240746 -346.000832)
		(end 23.240746 -345.881706)
		(width 0.09525)
		(layer "F.Cu")
		(net "SAS2X28_DRIVE_RX_N_A11")
	)
	(segment
		(start 26.291286 -345.791282)
		(end 26.435812 -345.935808)
		(width 0.09525)
		(layer "F.Cu")
		(net "SAS2X28_DRIVE_RX_N_A11")
	)
	(segment
		(start 21.75002 -346.119958)
		(end 23.12162 -346.119958)
		(width 0.09525)
		(layer "F.Cu")
		(net "SAS2X28_DRIVE_RX_N_A11")
	)
	(segment
		(start 23.475696 -345.646756)
		(end 25.94229 -345.646756)
		(width 0.09525)
		(layer "F.Cu")
		(net "SAS2X28_DRIVE_RX_N_A11")
	)
	(arc
		(start 23.375366 -345.6686)
		(mid 23.383303 -345.665022)
		(end 23.391368 -345.661742)
		(width 0.09525)
		(layer "F.Cu")
		(net "SAS2X28_DRIVE_RX_N_A11")
	)
	(arc
		(start 23.12162 -346.119958)
		(mid 23.205855 -346.085067)
		(end 23.240746 -346.000832)
		(width 0.09525)
		(layer "F.Cu")
		(net "SAS2X28_DRIVE_RX_N_A11")
	)
	(arc
		(start 23.436072 -345.649804)
		(mid 23.455561 -345.647328)
		(end 23.475188 -345.646502)
		(width 0.09525)
		(layer "F.Cu")
		(net "SAS2X28_DRIVE_RX_N_A11")
	)
	(arc
		(start 23.475188 -345.646502)
		(mid 23.475442 -345.646629)
		(end 23.475696 -345.646756)
		(width 0.09525)
		(layer "F.Cu")
		(net "SAS2X28_DRIVE_RX_N_A11")
	)
	(arc
		(start 23.391368 -345.661742)
		(mid 23.392383 -345.661485)
		(end 23.3934 -345.661234)
		(width 0.09525)
		(layer "F.Cu")
		(net "SAS2X28_DRIVE_RX_N_A11")
	)
	(arc
		(start 25.94229 -345.646756)
		(mid 26.131153 -345.684323)
		(end 26.291286 -345.791282)
		(width 0.09525)
		(layer "F.Cu")
		(net "SAS2X28_DRIVE_RX_N_A11")
	)
	(arc
		(start 23.40737 -345.656662)
		(mid 23.421614 -345.652785)
		(end 23.436072 -345.649804)
		(width 0.09525)
		(layer "F.Cu")
		(net "SAS2X28_DRIVE_RX_N_A11")
	)
	(arc
		(start 23.3934 -345.661234)
		(mid 23.400348 -345.658835)
		(end 23.40737 -345.656662)
		(width 0.09525)
		(layer "F.Cu")
		(net "SAS2X28_DRIVE_RX_N_A11")
	)
	(arc
		(start 23.240746 -345.881706)
		(mid 23.277146 -345.755615)
		(end 23.375366 -345.6686)
		(width 0.09525)
		(layer "F.Cu")
		(net "SAS2X28_DRIVE_RX_N_A11")
	)
	(segment
		(start 27.431746 -331.244702)
		(end 27.431746 -332.159102)
		(width 0.111252)
		(layer "F.Cu")
		(net "HDD_PRSNT11")
	)
	(via
		(at 87.737696 -332.7527)
		(size 0.5588)
		(drill 0.3048)
		(layers "F.Cu" "B.Cu")
		(net "HDD_PRSNT11")
	)
	(via
		(at 12.801346 -213.7283)
		(size 0.7112)
		(drill 0.3556)
		(layers "F.Cu" "B.Cu")
		(net "HDD_PRSNT11")
	)
	(via
		(at 22.86 -209.804)
		(size 0.5588)
		(drill 0.3048)
		(layers "F.Cu" "B.Cu")
		(net "HDD_PRSNT11")
	)
	(via
		(at 12.04976 -447.393314)
		(size 0.5588)
		(drill 0.3048)
		(layers "F.Cu" "B.Cu")
		(net "HDD_PRSNT11")
	)
	(via
		(at 27.431746 -332.159102)
		(size 0.5588)
		(drill 0.3048)
		(layers "F.Cu" "B.Cu")
		(net "HDD_PRSNT11")
	)
	(via
		(at 17.49044 -213.031324)
		(size 0.5588)
		(drill 0.3048)
		(layers "F.Cu" "B.Cu")
		(net "HDD_PRSNT11")
	)
	(segment
		(start 12.481052 -214.04834)
		(end 12.801346 -213.7283)
		(width 0.111252)
		(layer "B.Cu")
		(net "HDD_PRSNT11")
	)
	(segment
		(start 2.812542 -448.501262)
		(end 2.80924 -448.504564)
		(width 0.111252)
		(layer "B.Cu")
		(net "HDD_PRSNT11")
	)
	(segment
		(start 22.86 -209.804)
		(end 20.717764 -209.804)
		(width 0.111252)
		(layer "B.Cu")
		(net "HDD_PRSNT11")
	)
	(segment
		(start 2.80924 -213.50478)
		(end 2.812542 -213.501478)
		(width 0.111252)
		(layer "B.Cu")
		(net "HDD_PRSNT11")
	)
	(segment
		(start 15.71117 -213.7283)
		(end 12.801346 -213.7283)
		(width 0.111252)
		(layer "B.Cu")
		(net "HDD_PRSNT11")
	)
	(segment
		(start 17.49044 -213.031324)
		(end 16.408146 -213.031324)
		(width 0.111252)
		(layer "B.Cu")
		(net "HDD_PRSNT11")
	)
	(segment
		(start 12.04976 -447.393314)
		(end 10.941812 -448.501262)
		(width 0.111252)
		(layer "B.Cu")
		(net "HDD_PRSNT11")
	)
	(segment
		(start 2.812542 -213.501478)
		(end 5.818124 -213.501478)
		(width 0.111252)
		(layer "B.Cu")
		(net "HDD_PRSNT11")
	)
	(segment
		(start 12.088368 -214.04834)
		(end 12.481052 -214.04834)
		(width 0.111252)
		(layer "B.Cu")
		(net "HDD_PRSNT11")
	)
	(segment
		(start 10.941812 -448.501262)
		(end 2.812542 -448.501262)
		(width 0.111252)
		(layer "B.Cu")
		(net "HDD_PRSNT11")
	)
	(segment
		(start 6.36905 -214.052404)
		(end 12.084304 -214.052404)
		(width 0.111252)
		(layer "B.Cu")
		(net "HDD_PRSNT11")
	)
	(segment
		(start 20.717764 -209.804)
		(end 17.49044 -213.031324)
		(width 0.111252)
		(layer "B.Cu")
		(net "HDD_PRSNT11")
	)
	(segment
		(start 12.084304 -214.052404)
		(end 12.088368 -214.04834)
		(width 0.111252)
		(layer "B.Cu")
		(net "HDD_PRSNT11")
	)
	(segment
		(start 5.818124 -213.501478)
		(end 6.36905 -214.052404)
		(width 0.111252)
		(layer "B.Cu")
		(net "HDD_PRSNT11")
	)
	(segment
		(start 16.408146 -213.031324)
		(end 15.71117 -213.7283)
		(width 0.111252)
		(layer "B.Cu")
		(net "HDD_PRSNT11")
	)
	(segment
		(start 17.49044 -213.229952)
		(end 17.217898 -213.502494)
		(width 0.14605)
		(layer "In2.Cu")
		(net "HDD_PRSNT11")
	)
	(segment
		(start 17.511522 -377.144026)
		(end 17.511522 -395.006322)
		(width 0.14605)
		(layer "In2.Cu")
		(net "HDD_PRSNT11")
	)
	(segment
		(start 20.069048 -257.105404)
		(end 20.210272 -257.246628)
		(width 0.14605)
		(layer "In2.Cu")
		(net "HDD_PRSNT11")
	)
	(segment
		(start 16.674846 -413.512508)
		(end 21.1074 -417.945062)
		(width 0.14605)
		(layer "In2.Cu")
		(net "HDD_PRSNT11")
	)
	(segment
		(start 20.069048 -256.017776)
		(end 20.069048 -257.105404)
		(width 0.14605)
		(layer "In2.Cu")
		(net "HDD_PRSNT11")
	)
	(segment
		(start 21.1074 -417.945062)
		(end 21.1074 -418.962078)
		(width 0.14605)
		(layer "In2.Cu")
		(net "HDD_PRSNT11")
	)
	(segment
		(start 16.998696 -250.962414)
		(end 19.567144 -253.531116)
		(width 0.14605)
		(layer "In2.Cu")
		(net "HDD_PRSNT11")
	)
	(segment
		(start 16.767048 -395.750796)
		(end 16.767048 -397.58747)
		(width 0.14605)
		(layer "In2.Cu")
		(net "HDD_PRSNT11")
	)
	(segment
		(start 28.527502 -332.159102)
		(end 29.10205 -332.73365)
		(width 0.14605)
		(layer "In2.Cu")
		(net "HDD_PRSNT11")
	)
	(segment
		(start 17.511522 -395.006322)
		(end 16.767048 -395.750796)
		(width 0.14605)
		(layer "In2.Cu")
		(net "HDD_PRSNT11")
	)
	(segment
		(start 19.567144 -253.531116)
		(end 19.567144 -255.515872)
		(width 0.14605)
		(layer "In2.Cu")
		(net "HDD_PRSNT11")
	)
	(segment
		(start 16.767048 -397.58747)
		(end 16.674846 -397.679672)
		(width 0.14605)
		(layer "In2.Cu")
		(net "HDD_PRSNT11")
	)
	(segment
		(start 86.848696 -332.73365)
		(end 86.867746 -332.7527)
		(width 0.14605)
		(layer "In2.Cu")
		(net "HDD_PRSNT11")
	)
	(segment
		(start 20.488148 -313.80684)
		(end 17.91843 -316.376558)
		(width 0.14605)
		(layer "In2.Cu")
		(net "HDD_PRSNT11")
	)
	(segment
		(start 27.431746 -332.159102)
		(end 28.527502 -332.159102)
		(width 0.14605)
		(layer "In2.Cu")
		(net "HDD_PRSNT11")
	)
	(segment
		(start 17.8054 -361.041188)
		(end 17.8054 -376.850148)
		(width 0.14605)
		(layer "In2.Cu")
		(net "HDD_PRSNT11")
	)
	(segment
		(start 21.1074 -419.69817)
		(end 21.1074 -420.727124)
		(width 0.14605)
		(layer "In2.Cu")
		(net "HDD_PRSNT11")
	)
	(segment
		(start 17.49044 -213.031324)
		(end 17.49044 -213.229952)
		(width 0.14605)
		(layer "In2.Cu")
		(net "HDD_PRSNT11")
	)
	(segment
		(start 20.488148 -303.384712)
		(end 20.488148 -313.80684)
		(width 0.14605)
		(layer "In2.Cu")
		(net "HDD_PRSNT11")
	)
	(segment
		(start 16.585438 -442.857636)
		(end 12.04976 -447.393314)
		(width 0.14605)
		(layer "In2.Cu")
		(net "HDD_PRSNT11")
	)
	(segment
		(start 86.867746 -332.7527)
		(end 87.737696 -332.7527)
		(width 0.14605)
		(layer "In2.Cu")
		(net "HDD_PRSNT11")
	)
	(segment
		(start 21.155152 -419.201854)
		(end 21.155152 -419.458394)
		(width 0.14605)
		(layer "In2.Cu")
		(net "HDD_PRSNT11")
	)
	(segment
		(start 19.389598 -260.679438)
		(end 19.389598 -302.286162)
		(width 0.14605)
		(layer "In2.Cu")
		(net "HDD_PRSNT11")
	)
	(segment
		(start 19.567144 -255.515872)
		(end 20.069048 -256.017776)
		(width 0.14605)
		(layer "In2.Cu")
		(net "HDD_PRSNT11")
	)
	(segment
		(start 19.389598 -302.286162)
		(end 20.488148 -303.384712)
		(width 0.14605)
		(layer "In2.Cu")
		(net "HDD_PRSNT11")
	)
	(segment
		(start 21.606002 -353.047808)
		(end 21.606002 -357.240586)
		(width 0.14605)
		(layer "In2.Cu")
		(net "HDD_PRSNT11")
	)
	(segment
		(start 17.91843 -349.360236)
		(end 21.606002 -353.047808)
		(width 0.14605)
		(layer "In2.Cu")
		(net "HDD_PRSNT11")
	)
	(segment
		(start 16.585438 -425.249086)
		(end 16.585438 -442.857636)
		(width 0.14605)
		(layer "In2.Cu")
		(net "HDD_PRSNT11")
	)
	(segment
		(start 16.998696 -213.72195)
		(end 16.998696 -250.962414)
		(width 0.14605)
		(layer "In2.Cu")
		(net "HDD_PRSNT11")
	)
	(segment
		(start 21.155152 -419.458394)
		(end 21.1074 -419.69817)
		(width 0.14605)
		(layer "In2.Cu")
		(net "HDD_PRSNT11")
	)
	(segment
		(start 17.217898 -213.502494)
		(end 16.998696 -213.72195)
		(width 0.14605)
		(layer "In2.Cu")
		(net "HDD_PRSNT11")
	)
	(segment
		(start 17.91843 -316.376558)
		(end 17.91843 -349.360236)
		(width 0.14605)
		(layer "In2.Cu")
		(net "HDD_PRSNT11")
	)
	(segment
		(start 16.674846 -397.679672)
		(end 16.674846 -413.512508)
		(width 0.14605)
		(layer "In2.Cu")
		(net "HDD_PRSNT11")
	)
	(segment
		(start 21.1074 -420.727124)
		(end 16.585438 -425.249086)
		(width 0.14605)
		(layer "In2.Cu")
		(net "HDD_PRSNT11")
	)
	(segment
		(start 29.10205 -332.73365)
		(end 86.848696 -332.73365)
		(width 0.14605)
		(layer "In2.Cu")
		(net "HDD_PRSNT11")
	)
	(segment
		(start 20.210272 -257.246628)
		(end 20.210272 -259.858764)
		(width 0.14605)
		(layer "In2.Cu")
		(net "HDD_PRSNT11")
	)
	(segment
		(start 20.210272 -259.858764)
		(end 19.389598 -260.679438)
		(width 0.14605)
		(layer "In2.Cu")
		(net "HDD_PRSNT11")
	)
	(segment
		(start 21.606002 -357.240586)
		(end 17.8054 -361.041188)
		(width 0.14605)
		(layer "In2.Cu")
		(net "HDD_PRSNT11")
	)
	(segment
		(start 17.8054 -376.850148)
		(end 17.511522 -377.144026)
		(width 0.14605)
		(layer "In2.Cu")
		(net "HDD_PRSNT11")
	)
	(segment
		(start 21.1074 -418.962078)
		(end 21.155152 -419.201854)
		(width 0.14605)
		(layer "In2.Cu")
		(net "HDD_PRSNT11")
	)
	(segment
		(start 47.46117 -206.454248)
		(end 36.395152 -206.454248)
		(width 0.14605)
		(layer "In5.Cu")
		(net "HDD_PRSNT11")
	)
	(segment
		(start 87.277194 -269.408148)
		(end 85.692996 -267.82395)
		(width 0.14605)
		(layer "In5.Cu")
		(net "HDD_PRSNT11")
	)
	(segment
		(start 87.277194 -279.021794)
		(end 87.277194 -269.408148)
		(width 0.14605)
		(layer "In5.Cu")
		(net "HDD_PRSNT11")
	)
	(segment
		(start 85.692996 -267.82395)
		(end 85.692996 -244.686074)
		(width 0.14605)
		(layer "In5.Cu")
		(net "HDD_PRSNT11")
	)
	(segment
		(start 85.692996 -244.686074)
		(end 47.46117 -206.454248)
		(width 0.14605)
		(layer "In5.Cu")
		(net "HDD_PRSNT11")
	)
	(segment
		(start 87.737696 -332.7527)
		(end 87.737696 -279.482296)
		(width 0.14605)
		(layer "In5.Cu")
		(net "HDD_PRSNT11")
	)
	(segment
		(start 33.0454 -209.804)
		(end 22.86 -209.804)
		(width 0.14605)
		(layer "In5.Cu")
		(net "HDD_PRSNT11")
	)
	(segment
		(start 87.737696 -279.482296)
		(end 87.277194 -279.021794)
		(width 0.14605)
		(layer "In5.Cu")
		(net "HDD_PRSNT11")
	)
	(segment
		(start 36.395152 -206.454248)
		(end 33.0454 -209.804)
		(width 0.14605)
		(layer "In5.Cu")
		(net "HDD_PRSNT11")
	)
	(segment
		(start 21.127466 -339.3567)
		(end 24.9936 -339.3567)
		(width 0.09525)
		(layer "F.Cu")
		(net "SAS2X28_DRIVE_RX_N_B11")
	)
	(segment
		(start 19.600164 -339.609938)
		(end 20.52066 -339.609938)
		(width 0.09525)
		(layer "F.Cu")
		(net "SAS2X28_DRIVE_RX_N_B11")
	)
	(segment
		(start 20.52066 -339.609938)
		(end 20.523962 -339.606636)
		(width 0.09525)
		(layer "F.Cu")
		(net "SAS2X28_DRIVE_RX_N_B11")
	)
	(arc
		(start 24.9936 -339.3567)
		(mid 25.292981 -339.416251)
		(end 25.546812 -339.585808)
		(width 0.09525)
		(layer "F.Cu")
		(net "SAS2X28_DRIVE_RX_N_B11")
	)
	(arc
		(start 20.523962 -339.606636)
		(mid 20.687261 -339.574154)
		(end 20.825714 -339.481668)
		(width 0.09525)
		(layer "F.Cu")
		(net "SAS2X28_DRIVE_RX_N_B11")
	)
	(arc
		(start 20.825714 -339.481668)
		(mid 20.964159 -339.389162)
		(end 21.127466 -339.3567)
		(width 0.09525)
		(layer "F.Cu")
		(net "SAS2X28_DRIVE_RX_N_B11")
	)
	(segment
		(start 3.19024 -458.504544)
		(end 6.137656 -458.504544)
		(width 0.111252)
		(layer "F.Cu")
		(net "SAS_EXP_A_PWR2")
	)
	(segment
		(start 8.011668 -457.917296)
		(end 8.220964 -457.708)
		(width 0.111252)
		(layer "F.Cu")
		(net "SAS_EXP_A_PWR2")
	)
	(segment
		(start 8.220964 -457.708)
		(end 10.083546 -457.708)
		(width 0.111252)
		(layer "F.Cu")
		(net "SAS_EXP_A_PWR2")
	)
	(segment
		(start 6.724904 -457.917296)
		(end 8.011668 -457.917296)
		(width 0.111252)
		(layer "F.Cu")
		(net "SAS_EXP_A_PWR2")
	)
	(segment
		(start 195.920614 -286.738568)
		(end 194.839082 -286.738568)
		(width 0.111252)
		(layer "F.Cu")
		(net "SAS_EXP_A_PWR2")
	)
	(segment
		(start 196.913246 -286.3977)
		(end 196.849746 -286.3977)
		(width 0.111252)
		(layer "F.Cu")
		(net "SAS_EXP_A_PWR2")
	)
	(segment
		(start 196.214746 -287.0327)
		(end 195.920614 -286.738568)
		(width 0.111252)
		(layer "F.Cu")
		(net "SAS_EXP_A_PWR2")
	)
	(segment
		(start 196.849746 -286.3977)
		(end 196.214746 -287.0327)
		(width 0.111252)
		(layer "F.Cu")
		(net "SAS_EXP_A_PWR2")
	)
	(segment
		(start 10.083546 -457.708)
		(end 11.886946 -455.9046)
		(width 0.111252)
		(layer "F.Cu")
		(net "SAS_EXP_A_PWR2")
	)
	(segment
		(start 6.137656 -458.504544)
		(end 6.724904 -457.917296)
		(width 0.111252)
		(layer "F.Cu")
		(net "SAS_EXP_A_PWR2")
	)
	(via
		(at 196.693282 -287.84169)
		(size 0.7112)
		(drill 0.3556)
		(layers "F.Cu" "B.Cu")
		(net "SAS_EXP_A_PWR2")
	)
	(via
		(at 11.886946 -455.9046)
		(size 0.5588)
		(drill 0.3048)
		(layers "F.Cu" "B.Cu")
		(net "SAS_EXP_A_PWR2")
	)
	(via
		(at 196.214746 -287.0327)
		(size 0.5588)
		(drill 0.3048)
		(layers "F.Cu" "B.Cu")
		(net "SAS_EXP_A_PWR2")
	)
	(segment
		(start 196.214746 -287.0327)
		(end 196.693282 -287.511236)
		(width 0.111252)
		(layer "B.Cu")
		(net "SAS_EXP_A_PWR2")
	)
	(segment
		(start 196.693282 -287.511236)
		(end 196.693282 -287.84169)
		(width 0.111252)
		(layer "B.Cu")
		(net "SAS_EXP_A_PWR2")
	)
	(segment
		(start 196.474334 -341.139526)
		(end 196.474334 -287.292288)
		(width 0.14605)
		(layer "In5.Cu")
		(net "SAS_EXP_A_PWR2")
	)
	(segment
		(start 15.842996 -463.353912)
		(end 17.727168 -465.238084)
		(width 0.14605)
		(layer "In5.Cu")
		(net "SAS_EXP_A_PWR2")
	)
	(segment
		(start 15.297658 -463.353912)
		(end 15.842996 -463.353912)
		(width 0.14605)
		(layer "In5.Cu")
		(net "SAS_EXP_A_PWR2")
	)
	(segment
		(start 13.570204 -461.626458)
		(end 15.297658 -463.353912)
		(width 0.14605)
		(layer "In5.Cu")
		(net "SAS_EXP_A_PWR2")
	)
	(segment
		(start 219.07246 -363.737652)
		(end 196.474334 -341.139526)
		(width 0.14605)
		(layer "In5.Cu")
		(net "SAS_EXP_A_PWR2")
	)
	(segment
		(start 12.2174 -455.9046)
		(end 13.570204 -457.257404)
		(width 0.14605)
		(layer "In5.Cu")
		(net "SAS_EXP_A_PWR2")
	)
	(segment
		(start 218.899994 -384.31724)
		(end 218.899994 -381.118872)
		(width 0.14605)
		(layer "In5.Cu")
		(net "SAS_EXP_A_PWR2")
	)
	(segment
		(start 218.899994 -381.118872)
		(end 219.07246 -380.946406)
		(width 0.14605)
		(layer "In5.Cu")
		(net "SAS_EXP_A_PWR2")
	)
	(segment
		(start 11.886946 -455.9046)
		(end 12.2174 -455.9046)
		(width 0.14605)
		(layer "In5.Cu")
		(net "SAS_EXP_A_PWR2")
	)
	(segment
		(start 13.570204 -457.257404)
		(end 13.570204 -461.626458)
		(width 0.14605)
		(layer "In5.Cu")
		(net "SAS_EXP_A_PWR2")
	)
	(segment
		(start 17.727168 -465.238084)
		(end 137.97915 -465.238084)
		(width 0.14605)
		(layer "In5.Cu")
		(net "SAS_EXP_A_PWR2")
	)
	(segment
		(start 219.07246 -380.946406)
		(end 219.07246 -363.737652)
		(width 0.14605)
		(layer "In5.Cu")
		(net "SAS_EXP_A_PWR2")
	)
	(segment
		(start 138.02741 -465.190078)
		(end 218.899994 -384.31724)
		(width 0.14605)
		(layer "In5.Cu")
		(net "SAS_EXP_A_PWR2")
	)
	(segment
		(start 137.97915 -465.238084)
		(end 138.02741 -465.190078)
		(width 0.14605)
		(layer "In5.Cu")
		(net "SAS_EXP_A_PWR2")
	)
	(segment
		(start 196.474334 -287.292288)
		(end 196.214746 -287.0327)
		(width 0.14605)
		(layer "In5.Cu")
		(net "SAS_EXP_A_PWR2")
	)
	(segment
		(start 23.172166 -448.914266)
		(end 23.172166 -448.748404)
		(width 0.09525)
		(layer "F.Cu")
		(net "SAS2X28_DRIVE_RX_N_A10")
	)
	(segment
		(start 23.001478 -449.10375)
		(end 23.07209 -449.07454)
		(width 0.09525)
		(layer "F.Cu")
		(net "SAS2X28_DRIVE_RX_N_A10")
	)
	(segment
		(start 23.14956 -448.997324)
		(end 23.161244 -448.968876)
		(width 0.09525)
		(layer "F.Cu")
		(net "SAS2X28_DRIVE_RX_N_A10")
	)
	(segment
		(start 23.273766 -448.646804)
		(end 25.601676 -448.646804)
		(width 0.09525)
		(layer "F.Cu")
		(net "SAS2X28_DRIVE_RX_N_A10")
	)
	(segment
		(start 21.75002 -449.120006)
		(end 22.919436 -449.120006)
		(width 0.09525)
		(layer "F.Cu")
		(net "SAS2X28_DRIVE_RX_N_A10")
	)
	(arc
		(start 23.07209 -449.07454)
		(mid 23.118508 -449.043635)
		(end 23.14956 -448.997324)
		(width 0.09525)
		(layer "F.Cu")
		(net "SAS2X28_DRIVE_RX_N_A10")
	)
	(arc
		(start 25.601676 -448.646804)
		(mid 26.007881 -448.727603)
		(end 26.352246 -448.9577)
		(width 0.09525)
		(layer "F.Cu")
		(net "SAS2X28_DRIVE_RX_N_A10")
	)
	(arc
		(start 22.919436 -449.120006)
		(mid 22.961254 -449.115903)
		(end 23.001478 -449.10375)
		(width 0.09525)
		(layer "F.Cu")
		(net "SAS2X28_DRIVE_RX_N_A10")
	)
	(arc
		(start 23.161244 -448.968876)
		(mid 23.169413 -448.942111)
		(end 23.172166 -448.914266)
		(width 0.09525)
		(layer "F.Cu")
		(net "SAS2X28_DRIVE_RX_N_A10")
	)
	(arc
		(start 23.172166 -448.748404)
		(mid 23.190901 -448.689536)
		(end 23.240238 -448.652392)
		(width 0.09525)
		(layer "F.Cu")
		(net "SAS2X28_DRIVE_RX_N_A10")
	)
	(arc
		(start 23.240238 -448.652392)
		(mid 23.256766 -448.648179)
		(end 23.273766 -448.646804)
		(width 0.09525)
		(layer "F.Cu")
		(net "SAS2X28_DRIVE_RX_N_A10")
	)
	(segment
		(start 20.743672 -442.609986)
		(end 20.746974 -442.606684)
		(width 0.09525)
		(layer "F.Cu")
		(net "SAS2X28_DRIVE_RX_N_B10")
	)
	(segment
		(start 25.781762 -442.67247)
		(end 25.844246 -442.7347)
		(width 0.09525)
		(layer "F.Cu")
		(net "SAS2X28_DRIVE_RX_N_B10")
	)
	(segment
		(start 21.173694 -442.4299)
		(end 25.196546 -442.4299)
		(width 0.09525)
		(layer "F.Cu")
		(net "SAS2X28_DRIVE_RX_N_B10")
	)
	(segment
		(start 19.600164 -442.609986)
		(end 20.743672 -442.609986)
		(width 0.09525)
		(layer "F.Cu")
		(net "SAS2X28_DRIVE_RX_N_B10")
	)
	(arc
		(start 20.746974 -442.606684)
		(mid 20.816959 -442.592763)
		(end 20.87626 -442.55309)
		(width 0.09525)
		(layer "F.Cu")
		(net "SAS2X28_DRIVE_RX_N_B10")
	)
	(arc
		(start 20.87626 -442.55309)
		(mid 21.012724 -442.461908)
		(end 21.173694 -442.4299)
		(width 0.09525)
		(layer "F.Cu")
		(net "SAS2X28_DRIVE_RX_N_B10")
	)
	(arc
		(start 25.196546 -442.4299)
		(mid 25.513272 -442.492994)
		(end 25.781762 -442.67247)
		(width 0.09525)
		(layer "F.Cu")
		(net "SAS2X28_DRIVE_RX_N_B10")
	)
	(segment
		(start 20.53336 -341.210138)
		(end 20.536662 -341.206836)
		(width 0.09525)
		(layer "F.Cu")
		(net "SAS2X28_B_HDD11_TX_-")
	)
	(segment
		(start 6.501384 -166.160704)
		(end 5.46608 -166.160704)
		(width 0.09525)
		(layer "F.Cu")
		(net "SAS2X28_B_HDD11_TX_-")
	)
	(segment
		(start 19.600164 -341.210138)
		(end 20.53336 -341.210138)
		(width 0.09525)
		(layer "F.Cu")
		(net "SAS2X28_B_HDD11_TX_-")
	)
	(segment
		(start 6.857746 -166.7637)
		(end 6.857746 -166.562278)
		(width 0.09525)
		(layer "F.Cu")
		(net "SAS2X28_B_HDD11_TX_-")
	)
	(segment
		(start 4.644644 -166.498778)
		(end 3.192526 -166.498778)
		(width 0.09525)
		(layer "F.Cu")
		(net "SAS2X28_B_HDD11_TX_-")
	)
	(segment
		(start 20.975828 -341.3887)
		(end 21.340318 -341.3887)
		(width 0.09525)
		(layer "F.Cu")
		(net "SAS2X28_B_HDD11_TX_-")
	)
	(segment
		(start 4.646168 -166.500302)
		(end 4.644644 -166.498778)
		(width 0.09525)
		(layer "F.Cu")
		(net "SAS2X28_B_HDD11_TX_-")
	)
	(via
		(at 6.857746 -166.7637)
		(size 0.5588)
		(drill 0.3048)
		(layers "F.Cu" "B.Cu")
		(net "SAS2X28_B_HDD11_TX_-")
	)
	(via
		(at 22.07006 -341.08644)
		(size 0.5588)
		(drill 0.3048)
		(layers "F.Cu" "B.Cu")
		(net "SAS2X28_B_HDD11_TX_-")
	)
	(arc
		(start 5.46608 -166.160704)
		(mid 5.321736 -166.189416)
		(end 5.19938 -166.271194)
		(width 0.09525)
		(layer "F.Cu")
		(net "SAS2X28_B_HDD11_TX_-")
	)
	(arc
		(start 20.853146 -341.3379)
		(mid 20.909433 -341.37551)
		(end 20.975828 -341.3887)
		(width 0.09525)
		(layer "F.Cu")
		(net "SAS2X28_B_HDD11_TX_-")
	)
	(arc
		(start 6.857746 -166.562278)
		(mid 6.824742 -166.396355)
		(end 6.730746 -166.2557)
		(width 0.09525)
		(layer "F.Cu")
		(net "SAS2X28_B_HDD11_TX_-")
	)
	(arc
		(start 5.19938 -166.271194)
		(mid 4.945564 -166.440788)
		(end 4.646168 -166.500302)
		(width 0.09525)
		(layer "F.Cu")
		(net "SAS2X28_B_HDD11_TX_-")
	)
	(arc
		(start 20.536662 -341.206836)
		(mid 20.707931 -341.240904)
		(end 20.853146 -341.3379)
		(width 0.09525)
		(layer "F.Cu")
		(net "SAS2X28_B_HDD11_TX_-")
	)
	(arc
		(start 21.340318 -341.3887)
		(mid 21.735248 -341.310144)
		(end 22.07006 -341.08644)
		(width 0.09525)
		(layer "F.Cu")
		(net "SAS2X28_B_HDD11_TX_-")
	)
	(arc
		(start 6.730746 -166.2557)
		(mid 6.625514 -166.185386)
		(end 6.501384 -166.160704)
		(width 0.09525)
		(layer "F.Cu")
		(net "SAS2X28_B_HDD11_TX_-")
	)
	(segment
		(start 28.81376 -263.311132)
		(end 24.304498 -267.820394)
		(width 0.09525)
		(layer "B.Cu")
		(net "SAS2X28_B_HDD11_TX_-")
	)
	(segment
		(start 13.2588 -173.951646)
		(end 13.258546 -173.9519)
		(width 0.09525)
		(layer "B.Cu")
		(net "SAS2X28_B_HDD11_TX_-")
	)
	(segment
		(start 7.107428 -166.2049)
		(end 11.832336 -166.2049)
		(width 0.09525)
		(layer "B.Cu")
		(net "SAS2X28_B_HDD11_TX_-")
	)
	(segment
		(start 12.623546 -167.355266)
		(end 12.623546 -172.418502)
		(width 0.09525)
		(layer "B.Cu")
		(net "SAS2X28_B_HDD11_TX_-")
	)
	(segment
		(start 23.819866 -268.991334)
		(end 23.819866 -334.446626)
		(width 0.09525)
		(layer "B.Cu")
		(net "SAS2X28_B_HDD11_TX_-")
	)
	(segment
		(start 23.587456 -336.412586)
		(end 23.587456 -336.698336)
		(width 0.09525)
		(layer "B.Cu")
		(net "SAS2X28_B_HDD11_TX_-")
	)
	(segment
		(start 6.857746 -166.7637)
		(end 6.857746 -166.562278)
		(width 0.09525)
		(layer "B.Cu")
		(net "SAS2X28_B_HDD11_TX_-")
	)
	(segment
		(start 13.258546 -173.9519)
		(end 29.082746 -189.7761)
		(width 0.09525)
		(layer "B.Cu")
		(net "SAS2X28_B_HDD11_TX_-")
	)
	(segment
		(start 23.568914 -341.4395)
		(end 22.922484 -341.4395)
		(width 0.09525)
		(layer "B.Cu")
		(net "SAS2X28_B_HDD11_TX_-")
	)
	(segment
		(start 23.819866 -337.163156)
		(end 23.819866 -340.980268)
		(width 0.09525)
		(layer "B.Cu")
		(net "SAS2X28_B_HDD11_TX_-")
	)
	(segment
		(start 23.587456 -334.911446)
		(end 23.587456 -335.197196)
		(width 0.09525)
		(layer "B.Cu")
		(net "SAS2X28_B_HDD11_TX_-")
	)
	(segment
		(start 23.819866 -335.662016)
		(end 23.819866 -335.947766)
		(width 0.09525)
		(layer "B.Cu")
		(net "SAS2X28_B_HDD11_TX_-")
	)
	(segment
		(start 29.514546 -190.818516)
		(end 29.514546 -261.619746)
		(width 0.09525)
		(layer "B.Cu")
		(net "SAS2X28_B_HDD11_TX_-")
	)
	(arc
		(start 12.212066 -166.36238)
		(mid 12.516638 -166.817876)
		(end 12.623546 -167.355266)
		(width 0.09525)
		(layer "B.Cu")
		(net "SAS2X28_B_HDD11_TX_-")
	)
	(arc
		(start 23.587456 -336.698336)
		(mid 23.617253 -336.828654)
		(end 23.703534 -336.930746)
		(width 0.09525)
		(layer "B.Cu")
		(net "SAS2X28_B_HDD11_TX_-")
	)
	(arc
		(start 23.819866 -335.947766)
		(mid 23.790069 -336.078084)
		(end 23.703788 -336.180176)
		(width 0.09525)
		(layer "B.Cu")
		(net "SAS2X28_B_HDD11_TX_-")
	)
	(arc
		(start 22.922484 -341.4395)
		(mid 22.461165 -341.347738)
		(end 22.07006 -341.08644)
		(width 0.09525)
		(layer "B.Cu")
		(net "SAS2X28_B_HDD11_TX_-")
	)
	(arc
		(start 23.587456 -335.197196)
		(mid 23.617253 -335.327514)
		(end 23.703534 -335.429606)
		(width 0.09525)
		(layer "B.Cu")
		(net "SAS2X28_B_HDD11_TX_-")
	)
	(arc
		(start 6.984746 -166.2557)
		(mid 7.041033 -166.21809)
		(end 7.107428 -166.2049)
		(width 0.09525)
		(layer "B.Cu")
		(net "SAS2X28_B_HDD11_TX_-")
	)
	(arc
		(start 29.082746 -189.7761)
		(mid 29.402312 -190.254365)
		(end 29.514546 -190.818516)
		(width 0.09525)
		(layer "B.Cu")
		(net "SAS2X28_B_HDD11_TX_-")
	)
	(arc
		(start 23.642066 -341.40902)
		(mid 23.608532 -341.431554)
		(end 23.568914 -341.4395)
		(width 0.09525)
		(layer "B.Cu")
		(net "SAS2X28_B_HDD11_TX_-")
	)
	(arc
		(start 23.703788 -334.679036)
		(mid 23.617389 -334.78111)
		(end 23.587456 -334.911446)
		(width 0.09525)
		(layer "B.Cu")
		(net "SAS2X28_B_HDD11_TX_-")
	)
	(arc
		(start 23.703788 -336.180176)
		(mid 23.617389 -336.28225)
		(end 23.587456 -336.412586)
		(width 0.09525)
		(layer "B.Cu")
		(net "SAS2X28_B_HDD11_TX_-")
	)
	(arc
		(start 23.819866 -340.980268)
		(mid 23.773665 -341.212357)
		(end 23.642066 -341.40902)
		(width 0.09525)
		(layer "B.Cu")
		(net "SAS2X28_B_HDD11_TX_-")
	)
	(arc
		(start 11.832336 -166.2049)
		(mid 12.037889 -166.245823)
		(end 12.212066 -166.36238)
		(width 0.09525)
		(layer "B.Cu")
		(net "SAS2X28_B_HDD11_TX_-")
	)
	(arc
		(start 12.623546 -172.418502)
		(mid 12.788756 -173.248219)
		(end 13.2588 -173.951646)
		(width 0.09525)
		(layer "B.Cu")
		(net "SAS2X28_B_HDD11_TX_-")
	)
	(arc
		(start 23.703534 -336.930746)
		(mid 23.789933 -337.03282)
		(end 23.819866 -337.163156)
		(width 0.09525)
		(layer "B.Cu")
		(net "SAS2X28_B_HDD11_TX_-")
	)
	(arc
		(start 23.819866 -334.446626)
		(mid 23.790069 -334.576944)
		(end 23.703788 -334.679036)
		(width 0.09525)
		(layer "B.Cu")
		(net "SAS2X28_B_HDD11_TX_-")
	)
	(arc
		(start 24.304498 -267.820394)
		(mid 23.945697 -268.357656)
		(end 23.819866 -268.991334)
		(width 0.09525)
		(layer "B.Cu")
		(net "SAS2X28_B_HDD11_TX_-")
	)
	(arc
		(start 29.514546 -261.619746)
		(mid 29.332423 -262.535162)
		(end 28.81376 -263.311132)
		(width 0.09525)
		(layer "B.Cu")
		(net "SAS2X28_B_HDD11_TX_-")
	)
	(arc
		(start 6.857746 -166.562278)
		(mid 6.89075 -166.396355)
		(end 6.984746 -166.2557)
		(width 0.09525)
		(layer "B.Cu")
		(net "SAS2X28_B_HDD11_TX_-")
	)
	(arc
		(start 23.703534 -335.429606)
		(mid 23.789933 -335.53168)
		(end 23.819866 -335.662016)
		(width 0.09525)
		(layer "B.Cu")
		(net "SAS2X28_B_HDD11_TX_-")
	)
	(segment
		(start 196.742558 -389.584184)
		(end 195.599558 -389.584184)
		(width 0.111252)
		(layer "F.Cu")
		(net "SAS_EXP_A_PWR1")
	)
	(segment
		(start 197.22592 -389.100822)
		(end 196.742558 -389.584184)
		(width 0.111252)
		(layer "F.Cu")
		(net "SAS_EXP_A_PWR1")
	)
	(segment
		(start 8.668766 -461.077818)
		(end 8.241792 -461.504792)
		(width 0.111252)
		(layer "F.Cu")
		(net "SAS_EXP_A_PWR1")
	)
	(segment
		(start 197.467474 -389.100822)
		(end 197.22592 -389.100822)
		(width 0.111252)
		(layer "F.Cu")
		(net "SAS_EXP_A_PWR1")
	)
	(segment
		(start 8.241792 -461.504792)
		(end 3.19024 -461.504792)
		(width 0.111252)
		(layer "F.Cu")
		(net "SAS_EXP_A_PWR1")
	)
	(via
		(at 196.719952 -390.52373)
		(size 0.7112)
		(drill 0.3556)
		(layers "F.Cu" "B.Cu")
		(net "SAS_EXP_A_PWR1")
	)
	(via
		(at 22.008846 -461.5434)
		(size 0.5588)
		(drill 0.3048)
		(layers "F.Cu" "B.Cu")
		(net "SAS_EXP_A_PWR1")
	)
	(via
		(at 196.742558 -389.584184)
		(size 0.5588)
		(drill 0.3048)
		(layers "F.Cu" "B.Cu")
		(net "SAS_EXP_A_PWR1")
	)
	(via
		(at 8.668766 -461.077818)
		(size 0.5588)
		(drill 0.3048)
		(layers "F.Cu" "B.Cu")
		(net "SAS_EXP_A_PWR1")
	)
	(segment
		(start 8.668766 -461.077818)
		(end 11.100308 -463.50936)
		(width 0.111252)
		(layer "B.Cu")
		(net "SAS_EXP_A_PWR1")
	)
	(segment
		(start 21.170646 -461.5434)
		(end 22.008846 -461.5434)
		(width 0.111252)
		(layer "B.Cu")
		(net "SAS_EXP_A_PWR1")
	)
	(segment
		(start 19.204686 -463.50936)
		(end 21.170646 -461.5434)
		(width 0.111252)
		(layer "B.Cu")
		(net "SAS_EXP_A_PWR1")
	)
	(segment
		(start 196.722746 -390.520936)
		(end 196.719952 -390.52373)
		(width 0.111252)
		(layer "B.Cu")
		(net "SAS_EXP_A_PWR1")
	)
	(segment
		(start 11.100308 -463.50936)
		(end 19.204686 -463.50936)
		(width 0.111252)
		(layer "B.Cu")
		(net "SAS_EXP_A_PWR1")
	)
	(segment
		(start 196.722746 -389.8519)
		(end 196.722746 -390.520936)
		(width 0.111252)
		(layer "B.Cu")
		(net "SAS_EXP_A_PWR1")
	)
	(segment
		(start 196.742558 -389.584184)
		(end 196.722746 -389.8519)
		(width 0.111252)
		(layer "B.Cu")
		(net "SAS_EXP_A_PWR1")
	)
	(segment
		(start 196.742558 -390.853168)
		(end 196.742558 -389.584184)
		(width 0.14605)
		(layer "In5.Cu")
		(net "SAS_EXP_A_PWR1")
	)
	(segment
		(start 125.06198 -462.533746)
		(end 196.742558 -390.853168)
		(width 0.14605)
		(layer "In5.Cu")
		(net "SAS_EXP_A_PWR1")
	)
	(segment
		(start 22.008846 -461.5434)
		(end 22.999192 -462.533746)
		(width 0.14605)
		(layer "In5.Cu")
		(net "SAS_EXP_A_PWR1")
	)
	(segment
		(start 22.999192 -462.533746)
		(end 125.06198 -462.533746)
		(width 0.14605)
		(layer "In5.Cu")
		(net "SAS_EXP_A_PWR1")
	)
	(segment
		(start 38.250114 -56.879998)
		(end 37.009832 -56.879998)
		(width 0.09525)
		(layer "F.Cu")
		(net "SAS2X28_DRIVE_RX_N_A9")
	)
	(segment
		(start 36.72586 -57.346596)
		(end 34.214816 -57.346596)
		(width 0.09525)
		(layer "F.Cu")
		(net "SAS2X28_DRIVE_RX_N_A9")
	)
	(segment
		(start 36.82746 -57.062624)
		(end 36.82746 -57.244996)
		(width 0.09525)
		(layer "F.Cu")
		(net "SAS2X28_DRIVE_RX_N_A9")
	)
	(arc
		(start 37.009832 -56.879998)
		(mid 36.880786 -56.933503)
		(end 36.82746 -57.062624)
		(width 0.09525)
		(layer "F.Cu")
		(net "SAS2X28_DRIVE_RX_N_A9")
	)
	(arc
		(start 34.214816 -57.346596)
		(mid 33.808611 -57.265797)
		(end 33.464246 -57.0357)
		(width 0.09525)
		(layer "F.Cu")
		(net "SAS2X28_DRIVE_RX_N_A9")
	)
	(arc
		(start 36.748212 -57.343802)
		(mid 36.737114 -57.345817)
		(end 36.72586 -57.346596)
		(width 0.09525)
		(layer "F.Cu")
		(net "SAS2X28_DRIVE_RX_N_A9")
	)
	(arc
		(start 36.82746 -57.244996)
		(mid 36.805115 -57.308224)
		(end 36.748212 -57.343802)
		(width 0.09525)
		(layer "F.Cu")
		(net "SAS2X28_DRIVE_RX_N_A9")
	)
	(segment
		(start 33.473644 -63.267844)
		(end 33.464246 -63.2587)
		(width 0.09525)
		(layer "F.Cu")
		(net "SAS2X28_DRIVE_RX_N_B9")
	)
	(segment
		(start 38.862 -63.542926)
		(end 34.137346 -63.542926)
		(width 0.09525)
		(layer "F.Cu")
		(net "SAS2X28_DRIVE_RX_N_B9")
	)
	(segment
		(start 39.242238 -63.390018)
		(end 39.238936 -63.386716)
		(width 0.09525)
		(layer "F.Cu")
		(net "SAS2X28_DRIVE_RX_N_B9")
	)
	(segment
		(start 40.39997 -63.390018)
		(end 39.242238 -63.390018)
		(width 0.09525)
		(layer "F.Cu")
		(net "SAS2X28_DRIVE_RX_N_B9")
	)
	(arc
		(start 39.026846 -63.4746)
		(mid 38.951214 -63.525136)
		(end 38.862 -63.542926)
		(width 0.09525)
		(layer "F.Cu")
		(net "SAS2X28_DRIVE_RX_N_B9")
	)
	(arc
		(start 39.238936 -63.386716)
		(mid 39.124141 -63.40955)
		(end 39.026846 -63.4746)
		(width 0.09525)
		(layer "F.Cu")
		(net "SAS2X28_DRIVE_RX_N_B9")
	)
	(arc
		(start 34.043874 -63.5381)
		(mid 33.735365 -63.452332)
		(end 33.473644 -63.267844)
		(width 0.09525)
		(layer "F.Cu")
		(net "SAS2X28_DRIVE_RX_N_B9")
	)
	(arc
		(start 34.137346 -63.542926)
		(mid 34.118546 -63.542733)
		(end 34.099754 -63.542164)
		(width 0.09525)
		(layer "F.Cu")
		(net "SAS2X28_DRIVE_RX_N_B9")
	)
	(arc
		(start 34.099754 -63.542164)
		(mid 34.071784 -63.540548)
		(end 34.043874 -63.5381)
		(width 0.09525)
		(layer "F.Cu")
		(net "SAS2X28_DRIVE_RX_N_B9")
	)
	(segment
		(start 4.667758 -165.500304)
		(end 4.666234 -165.49878)
		(width 0.09525)
		(layer "F.Cu")
		(net "SAS2X28_B_HDD11_TX_+")
	)
	(segment
		(start 6.227572 -165.830504)
		(end 5.46481 -165.830504)
		(width 0.09525)
		(layer "F.Cu")
		(net "SAS2X28_B_HDD11_TX_+")
	)
	(segment
		(start 20.354036 -342.009984)
		(end 20.357338 -342.006682)
		(width 0.09525)
		(layer "F.Cu")
		(net "SAS2X28_B_HDD11_TX_+")
	)
	(segment
		(start 21.052028 -341.7189)
		(end 21.284946 -341.7189)
		(width 0.09525)
		(layer "F.Cu")
		(net "SAS2X28_B_HDD11_TX_+")
	)
	(segment
		(start 4.666234 -165.49878)
		(end 3.192526 -165.49878)
		(width 0.09525)
		(layer "F.Cu")
		(net "SAS2X28_B_HDD11_TX_+")
	)
	(segment
		(start 22.068028 -342.043258)
		(end 22.07006 -342.04529)
		(width 0.09525)
		(layer "F.Cu")
		(net "SAS2X28_B_HDD11_TX_+")
	)
	(segment
		(start 19.600164 -342.009984)
		(end 20.354036 -342.009984)
		(width 0.09525)
		(layer "F.Cu")
		(net "SAS2X28_B_HDD11_TX_+")
	)
	(via
		(at 6.791198 -165.597078)
		(size 0.5588)
		(drill 0.3048)
		(layers "F.Cu" "B.Cu")
		(net "SAS2X28_B_HDD11_TX_+")
	)
	(via
		(at 22.07006 -342.04529)
		(size 0.5588)
		(drill 0.3048)
		(layers "F.Cu" "B.Cu")
		(net "SAS2X28_B_HDD11_TX_+")
	)
	(arc
		(start 6.791198 -165.597078)
		(mid 6.532604 -165.769865)
		(end 6.227572 -165.830504)
		(width 0.09525)
		(layer "F.Cu")
		(net "SAS2X28_B_HDD11_TX_+")
	)
	(arc
		(start 20.357338 -342.006682)
		(mid 20.666925 -341.945101)
		(end 20.929346 -341.7697)
		(width 0.09525)
		(layer "F.Cu")
		(net "SAS2X28_B_HDD11_TX_+")
	)
	(arc
		(start 5.192014 -165.717474)
		(mid 4.951483 -165.556757)
		(end 4.667758 -165.500304)
		(width 0.09525)
		(layer "F.Cu")
		(net "SAS2X28_B_HDD11_TX_+")
	)
	(arc
		(start 5.46481 -165.830504)
		(mid 5.317161 -165.801135)
		(end 5.192014 -165.717474)
		(width 0.09525)
		(layer "F.Cu")
		(net "SAS2X28_B_HDD11_TX_+")
	)
	(arc
		(start 20.929346 -341.7697)
		(mid 20.985633 -341.73209)
		(end 21.052028 -341.7189)
		(width 0.09525)
		(layer "F.Cu")
		(net "SAS2X28_B_HDD11_TX_+")
	)
	(arc
		(start 21.284946 -341.7189)
		(mid 21.708745 -341.803199)
		(end 22.068028 -342.043258)
		(width 0.09525)
		(layer "F.Cu")
		(net "SAS2X28_B_HDD11_TX_+")
	)
	(segment
		(start 7.461504 -165.8747)
		(end 11.83259 -165.8747)
		(width 0.09525)
		(layer "B.Cu")
		(net "SAS2X28_B_HDD11_TX_+")
	)
	(segment
		(start 13.492226 -173.71822)
		(end 29.316426 -189.54242)
		(width 0.09525)
		(layer "B.Cu")
		(net "SAS2X28_B_HDD11_TX_+")
	)
	(segment
		(start 24.150066 -268.99108)
		(end 24.150066 -340.980522)
		(width 0.09525)
		(layer "B.Cu")
		(net "SAS2X28_B_HDD11_TX_+")
	)
	(segment
		(start 12.953746 -167.355012)
		(end 12.953746 -172.418248)
		(width 0.09525)
		(layer "B.Cu")
		(net "SAS2X28_B_HDD11_TX_+")
	)
	(segment
		(start 29.04744 -263.544812)
		(end 24.538178 -268.054074)
		(width 0.09525)
		(layer "B.Cu")
		(net "SAS2X28_B_HDD11_TX_+")
	)
	(segment
		(start 23.569168 -341.7697)
		(end 22.735286 -341.7697)
		(width 0.09525)
		(layer "B.Cu")
		(net "SAS2X28_B_HDD11_TX_+")
	)
	(segment
		(start 29.844746 -190.818262)
		(end 29.844746 -261.62)
		(width 0.09525)
		(layer "B.Cu")
		(net "SAS2X28_B_HDD11_TX_+")
	)
	(arc
		(start 23.875746 -341.6427)
		(mid 23.735087 -341.736685)
		(end 23.569168 -341.7697)
		(width 0.09525)
		(layer "B.Cu")
		(net "SAS2X28_B_HDD11_TX_+")
	)
	(arc
		(start 22.735286 -341.7697)
		(mid 22.375251 -341.841315)
		(end 22.07006 -342.04529)
		(width 0.09525)
		(layer "B.Cu")
		(net "SAS2X28_B_HDD11_TX_+")
	)
	(arc
		(start 29.844746 -261.62)
		(mid 29.637537 -262.661709)
		(end 29.04744 -263.544812)
		(width 0.09525)
		(layer "B.Cu")
		(net "SAS2X28_B_HDD11_TX_+")
	)
	(arc
		(start 12.953746 -172.418248)
		(mid 13.09369 -173.121793)
		(end 13.492226 -173.71822)
		(width 0.09525)
		(layer "B.Cu")
		(net "SAS2X28_B_HDD11_TX_+")
	)
	(arc
		(start 29.316426 -189.54242)
		(mid 29.707445 -190.12781)
		(end 29.844746 -190.818262)
		(width 0.09525)
		(layer "B.Cu")
		(net "SAS2X28_B_HDD11_TX_+")
	)
	(arc
		(start 6.791198 -165.597078)
		(mid 7.098737 -165.802569)
		(end 7.461504 -165.8747)
		(width 0.09525)
		(layer "B.Cu")
		(net "SAS2X28_B_HDD11_TX_+")
	)
	(arc
		(start 24.150066 -340.980522)
		(mid 24.078779 -341.338904)
		(end 23.875746 -341.6427)
		(width 0.09525)
		(layer "B.Cu")
		(net "SAS2X28_B_HDD11_TX_+")
	)
	(arc
		(start 11.83259 -165.8747)
		(mid 12.164436 -165.940708)
		(end 12.445746 -166.1287)
		(width 0.09525)
		(layer "B.Cu")
		(net "SAS2X28_B_HDD11_TX_+")
	)
	(arc
		(start 24.538178 -268.054074)
		(mid 24.250927 -268.483976)
		(end 24.150066 -268.99108)
		(width 0.09525)
		(layer "B.Cu")
		(net "SAS2X28_B_HDD11_TX_+")
	)
	(arc
		(start 12.445746 -166.1287)
		(mid 12.821688 -166.691337)
		(end 12.953746 -167.355012)
		(width 0.09525)
		(layer "B.Cu")
		(net "SAS2X28_B_HDD11_TX_+")
	)
	(segment
		(start 3.193542 -448.501262)
		(end 3.19024 -448.504564)
		(width 0.111252)
		(layer "F.Cu")
		(net "SAS_EXP_A_PWR11")
	)
	(segment
		(start 9.574784 -448.501262)
		(end 3.193542 -448.501262)
		(width 0.111252)
		(layer "F.Cu")
		(net "SAS_EXP_A_PWR11")
	)
	(segment
		(start 29.082746 -302.6537)
		(end 29.336746 -302.9077)
		(width 0.111252)
		(layer "F.Cu")
		(net "SAS_EXP_A_PWR11")
	)
	(segment
		(start 20.827746 -302.6537)
		(end 29.082746 -302.6537)
		(width 0.111252)
		(layer "F.Cu")
		(net "SAS_EXP_A_PWR11")
	)
	(segment
		(start 28.701746 -305.273202)
		(end 27.812746 -305.273202)
		(width 0.111252)
		(layer "F.Cu")
		(net "SAS_EXP_A_PWR11")
	)
	(segment
		(start 19.557746 -303.9237)
		(end 20.827746 -302.6537)
		(width 0.111252)
		(layer "F.Cu")
		(net "SAS_EXP_A_PWR11")
	)
	(segment
		(start 11.632946 -446.4431)
		(end 9.574784 -448.501262)
		(width 0.111252)
		(layer "F.Cu")
		(net "SAS_EXP_A_PWR11")
	)
	(segment
		(start 29.336746 -304.638202)
		(end 28.701746 -305.273202)
		(width 0.111252)
		(layer "F.Cu")
		(net "SAS_EXP_A_PWR11")
	)
	(segment
		(start 27.812746 -305.273202)
		(end 27.812746 -307.432202)
		(width 0.111252)
		(layer "F.Cu")
		(net "SAS_EXP_A_PWR11")
	)
	(segment
		(start 29.336746 -302.9077)
		(end 29.336746 -304.1777)
		(width 0.111252)
		(layer "F.Cu")
		(net "SAS_EXP_A_PWR11")
	)
	(segment
		(start 29.336746 -304.1777)
		(end 29.336746 -304.638202)
		(width 0.111252)
		(layer "F.Cu")
		(net "SAS_EXP_A_PWR11")
	)
	(via
		(at 19.557746 -303.9237)
		(size 0.5588)
		(drill 0.3048)
		(layers "F.Cu" "B.Cu")
		(net "SAS_EXP_A_PWR11")
	)
	(via
		(at 11.632946 -446.4431)
		(size 0.5588)
		(drill 0.3048)
		(layers "F.Cu" "B.Cu")
		(net "SAS_EXP_A_PWR11")
	)
	(via
		(at 29.336746 -304.1777)
		(size 0.7112)
		(drill 0.3556)
		(layers "F.Cu" "B.Cu")
		(net "SAS_EXP_A_PWR11")
	)
	(segment
		(start 16.773398 -364.447074)
		(end 16.9037 -364.577376)
		(width 0.14605)
		(layer "In2.Cu")
		(net "SAS_EXP_A_PWR11")
	)
	(segment
		(start 15.715488 -397.361156)
		(end 15.715488 -415.570162)
		(width 0.14605)
		(layer "In2.Cu")
		(net "SAS_EXP_A_PWR11")
	)
	(segment
		(start 19.459194 -356.336346)
		(end 19.459194 -358.111806)
		(width 0.14605)
		(layer "In2.Cu")
		(net "SAS_EXP_A_PWR11")
	)
	(segment
		(start 16.9037 -364.577376)
		(end 16.9037 -376.47626)
		(width 0.14605)
		(layer "In2.Cu")
		(net "SAS_EXP_A_PWR11")
	)
	(segment
		(start 19.557746 -313.461654)
		(end 17.01673 -316.00267)
		(width 0.14605)
		(layer "In2.Cu")
		(net "SAS_EXP_A_PWR11")
	)
	(segment
		(start 15.865348 -395.376908)
		(end 15.865348 -397.211296)
		(width 0.14605)
		(layer "In2.Cu")
		(net "SAS_EXP_A_PWR11")
	)
	(segment
		(start 15.54099 -415.74466)
		(end 15.54099 -442.535056)
		(width 0.14605)
		(layer "In2.Cu")
		(net "SAS_EXP_A_PWR11")
	)
	(segment
		(start 16.570198 -394.672058)
		(end 15.865348 -395.376908)
		(width 0.14605)
		(layer "In2.Cu")
		(net "SAS_EXP_A_PWR11")
	)
	(segment
		(start 19.459194 -358.111806)
		(end 16.773398 -360.797602)
		(width 0.14605)
		(layer "In2.Cu")
		(net "SAS_EXP_A_PWR11")
	)
	(segment
		(start 16.609822 -394.581634)
		(end 16.570198 -394.672058)
		(width 0.14605)
		(layer "In2.Cu")
		(net "SAS_EXP_A_PWR11")
	)
	(segment
		(start 15.715488 -415.570162)
		(end 15.54099 -415.74466)
		(width 0.14605)
		(layer "In2.Cu")
		(net "SAS_EXP_A_PWR11")
	)
	(segment
		(start 17.01673 -316.00267)
		(end 17.01673 -353.893882)
		(width 0.14605)
		(layer "In2.Cu")
		(net "SAS_EXP_A_PWR11")
	)
	(segment
		(start 16.9037 -376.47626)
		(end 16.609822 -376.770138)
		(width 0.14605)
		(layer "In2.Cu")
		(net "SAS_EXP_A_PWR11")
	)
	(segment
		(start 16.773398 -360.797602)
		(end 16.773398 -364.447074)
		(width 0.14605)
		(layer "In2.Cu")
		(net "SAS_EXP_A_PWR11")
	)
	(segment
		(start 15.865348 -397.211296)
		(end 15.715488 -397.361156)
		(width 0.14605)
		(layer "In2.Cu")
		(net "SAS_EXP_A_PWR11")
	)
	(segment
		(start 16.609822 -376.770138)
		(end 16.609822 -394.581634)
		(width 0.14605)
		(layer "In2.Cu")
		(net "SAS_EXP_A_PWR11")
	)
	(segment
		(start 15.54099 -442.535056)
		(end 11.632946 -446.4431)
		(width 0.14605)
		(layer "In2.Cu")
		(net "SAS_EXP_A_PWR11")
	)
	(segment
		(start 17.01673 -353.893882)
		(end 19.459194 -356.336346)
		(width 0.14605)
		(layer "In2.Cu")
		(net "SAS_EXP_A_PWR11")
	)
	(segment
		(start 19.557746 -303.9237)
		(end 19.557746 -313.461654)
		(width 0.14605)
		(layer "In2.Cu")
		(net "SAS_EXP_A_PWR11")
	)
	(segment
		(start 26.435812 -339.585808)
		(end 26.567892 -339.453982)
		(width 0.09525)
		(layer "F.Cu")
		(net "SAS2X28_B_HDD11_RX_-")
	)
	(segment
		(start 26.923746 -339.306408)
		(end 27.177746 -339.306408)
		(width 0.09525)
		(layer "F.Cu")
		(net "SAS2X28_B_HDD11_RX_-")
	)
	(segment
		(start 27.60726 -339.484462)
		(end 27.743912 -339.62086)
		(width 0.09525)
		(layer "F.Cu")
		(net "SAS2X28_B_HDD11_RX_-")
	)
	(via
		(at 27.743912 -339.62086)
		(size 0.5588)
		(drill 0.3048)
		(layers "F.Cu" "B.Cu")
		(net "SAS2X28_B_HDD11_RX_-")
	)
	(arc
		(start 27.177746 -339.306408)
		(mid 27.410199 -339.352739)
		(end 27.60726 -339.484462)
		(width 0.09525)
		(layer "F.Cu")
		(net "SAS2X28_B_HDD11_RX_-")
	)
	(arc
		(start 26.567892 -339.453982)
		(mid 26.731144 -339.344807)
		(end 26.923746 -339.306408)
		(width 0.09525)
		(layer "F.Cu")
		(net "SAS2X28_B_HDD11_RX_-")
	)
	(segment
		(start 27.743912 -339.62086)
		(end 27.642312 -339.519514)
		(width 0.09525)
		(layer "B.Cu")
		(net "SAS2X28_B_HDD11_RX_-")
	)
	(segment
		(start 29.801566 -188.701426)
		(end 14.663166 -173.563026)
		(width 0.09525)
		(layer "B.Cu")
		(net "SAS2X28_B_HDD11_RX_-")
	)
	(segment
		(start 25.43302 -268.064234)
		(end 25.432766 -268.06398)
		(width 0.09525)
		(layer "B.Cu")
		(net "SAS2X28_B_HDD11_RX_-")
	)
	(segment
		(start 4.983226 -164.500306)
		(end 4.981702 -164.498782)
		(width 0.09525)
		(layer "B.Cu")
		(net "SAS2X28_B_HDD11_RX_-")
	)
	(segment
		(start 25.432766 -268.06398)
		(end 29.951426 -263.545574)
		(width 0.09525)
		(layer "B.Cu")
		(net "SAS2X28_B_HDD11_RX_-")
	)
	(segment
		(start 4.981702 -164.498782)
		(end 2.811526 -164.498782)
		(width 0.09525)
		(layer "B.Cu")
		(net "SAS2X28_B_HDD11_RX_-")
	)
	(segment
		(start 13.766546 -171.397676)
		(end 13.766546 -164.740082)
		(width 0.09525)
		(layer "B.Cu")
		(net "SAS2X28_B_HDD11_RX_-")
	)
	(segment
		(start 24.759666 -337.754214)
		(end 24.759666 -269.689326)
		(width 0.09525)
		(layer "B.Cu")
		(net "SAS2X28_B_HDD11_RX_-")
	)
	(segment
		(start 25.572466 -338.980526)
		(end 25.05202 -338.46008)
		(width 0.09525)
		(layer "B.Cu")
		(net "SAS2X28_B_HDD11_RX_-")
	)
	(segment
		(start 13.187172 -164.160708)
		(end 5.808218 -164.160708)
		(width 0.09525)
		(layer "B.Cu")
		(net "SAS2X28_B_HDD11_RX_-")
	)
	(segment
		(start 14.663166 -173.563026)
		(end 14.66342 -173.563026)
		(width 0.09525)
		(layer "B.Cu")
		(net "SAS2X28_B_HDD11_RX_-")
	)
	(segment
		(start 27.126946 -339.3059)
		(end 26.358088 -339.3059)
		(width 0.09525)
		(layer "B.Cu")
		(net "SAS2X28_B_HDD11_RX_-")
	)
	(segment
		(start 30.454346 -262.3312)
		(end 30.454346 -190.277496)
		(width 0.09525)
		(layer "B.Cu")
		(net "SAS2X28_B_HDD11_RX_-")
	)
	(arc
		(start 14.66342 -173.563026)
		(mid 13.999633 -172.569554)
		(end 13.766546 -171.397676)
		(width 0.09525)
		(layer "B.Cu")
		(net "SAS2X28_B_HDD11_RX_-")
	)
	(arc
		(start 25.05202 -338.46008)
		(mid 24.835657 -338.136225)
		(end 24.759666 -337.754214)
		(width 0.09525)
		(layer "B.Cu")
		(net "SAS2X28_B_HDD11_RX_-")
	)
	(arc
		(start 30.454346 -190.277496)
		(mid 30.284685 -189.424552)
		(end 29.801566 -188.701426)
		(width 0.09525)
		(layer "B.Cu")
		(net "SAS2X28_B_HDD11_RX_-")
	)
	(arc
		(start 13.766546 -164.740082)
		(mid 13.722444 -164.518365)
		(end 13.596874 -164.33038)
		(width 0.09525)
		(layer "B.Cu")
		(net "SAS2X28_B_HDD11_RX_-")
	)
	(arc
		(start 26.358088 -339.3059)
		(mid 25.932928 -339.22133)
		(end 25.572466 -338.980526)
		(width 0.09525)
		(layer "B.Cu")
		(net "SAS2X28_B_HDD11_RX_-")
	)
	(arc
		(start 5.364734 -164.295836)
		(mid 5.306435 -164.347861)
		(end 5.24256 -164.392864)
		(width 0.09525)
		(layer "B.Cu")
		(net "SAS2X28_B_HDD11_RX_-")
	)
	(arc
		(start 27.642312 -339.519514)
		(mid 27.405875 -339.361439)
		(end 27.126946 -339.3059)
		(width 0.09525)
		(layer "B.Cu")
		(net "SAS2X28_B_HDD11_RX_-")
	)
	(arc
		(start 24.759666 -269.689326)
		(mid 24.934776 -268.809842)
		(end 25.43302 -268.064234)
		(width 0.09525)
		(layer "B.Cu")
		(net "SAS2X28_B_HDD11_RX_-")
	)
	(arc
		(start 29.951426 -263.545574)
		(mid 30.323654 -262.9884)
		(end 30.454346 -262.3312)
		(width 0.09525)
		(layer "B.Cu")
		(net "SAS2X28_B_HDD11_RX_-")
	)
	(arc
		(start 5.808218 -164.160708)
		(mid 5.576425 -164.19528)
		(end 5.364734 -164.295836)
		(width 0.09525)
		(layer "B.Cu")
		(net "SAS2X28_B_HDD11_RX_-")
	)
	(arc
		(start 13.596874 -164.33038)
		(mid 13.408901 -164.204781)
		(end 13.187172 -164.160708)
		(width 0.09525)
		(layer "B.Cu")
		(net "SAS2X28_B_HDD11_RX_-")
	)
	(arc
		(start 5.24256 -164.392864)
		(mid 5.123577 -164.472366)
		(end 4.983226 -164.500306)
		(width 0.09525)
		(layer "B.Cu")
		(net "SAS2X28_B_HDD11_RX_-")
	)
	(segment
		(start 39.368984 -166.390066)
		(end 39.365682 -166.386764)
		(width 0.09525)
		(layer "F.Cu")
		(net "SAS2X28_DRIVE_RX_N_B8")
	)
	(segment
		(start 39.115746 -166.6367)
		(end 35.248342 -166.6367)
		(width 0.09525)
		(layer "F.Cu")
		(net "SAS2X28_DRIVE_RX_N_B8")
	)
	(segment
		(start 40.39997 -166.390066)
		(end 39.368984 -166.390066)
		(width 0.09525)
		(layer "F.Cu")
		(net "SAS2X28_DRIVE_RX_N_B8")
	)
	(arc
		(start 39.138352 -166.634414)
		(mid 39.127101 -166.636076)
		(end 39.115746 -166.6367)
		(width 0.09525)
		(layer "F.Cu")
		(net "SAS2X28_DRIVE_RX_N_B8")
	)
	(arc
		(start 39.365682 -166.386764)
		(mid 39.278753 -166.422771)
		(end 39.242746 -166.5097)
		(width 0.09525)
		(layer "F.Cu")
		(net "SAS2X28_DRIVE_RX_N_B8")
	)
	(arc
		(start 39.242746 -166.5097)
		(mid 39.213207 -166.591034)
		(end 39.138352 -166.634414)
		(width 0.09525)
		(layer "F.Cu")
		(net "SAS2X28_DRIVE_RX_N_B8")
	)
	(arc
		(start 35.248342 -166.6367)
		(mid 34.75553 -166.538674)
		(end 34.337752 -166.25951)
		(width 0.09525)
		(layer "F.Cu")
		(net "SAS2X28_DRIVE_RX_N_B8")
	)
	(segment
		(start 38.250114 -159.880046)
		(end 36.94811 -159.880046)
		(width 0.09525)
		(layer "F.Cu")
		(net "SAS2X28_DRIVE_RX_N_A8")
	)
	(segment
		(start 36.82746 -159.985964)
		(end 36.82746 -160.245044)
		(width 0.09525)
		(layer "F.Cu")
		(net "SAS2X28_DRIVE_RX_N_A8")
	)
	(segment
		(start 36.72586 -160.346644)
		(end 35.051746 -160.346644)
		(width 0.09525)
		(layer "F.Cu")
		(net "SAS2X28_DRIVE_RX_N_A8")
	)
	(segment
		(start 34.362136 -160.061148)
		(end 34.337752 -160.03651)
		(width 0.09525)
		(layer "F.Cu")
		(net "SAS2X28_DRIVE_RX_N_A8")
	)
	(arc
		(start 36.758626 -160.341056)
		(mid 36.742474 -160.345205)
		(end 36.72586 -160.346644)
		(width 0.09525)
		(layer "F.Cu")
		(net "SAS2X28_DRIVE_RX_N_A8")
	)
	(arc
		(start 36.82746 -160.245044)
		(mid 36.808471 -160.304106)
		(end 36.758626 -160.341056)
		(width 0.09525)
		(layer "F.Cu")
		(net "SAS2X28_DRIVE_RX_N_A8")
	)
	(arc
		(start 36.94811 -159.880046)
		(mid 36.897954 -159.890023)
		(end 36.8554 -159.9184)
		(width 0.09525)
		(layer "F.Cu")
		(net "SAS2X28_DRIVE_RX_N_A8")
	)
	(arc
		(start 36.8554 -159.9184)
		(mid 36.834687 -159.949399)
		(end 36.82746 -159.985964)
		(width 0.09525)
		(layer "F.Cu")
		(net "SAS2X28_DRIVE_RX_N_A8")
	)
	(arc
		(start 35.051746 -160.346644)
		(mid 34.678535 -160.272501)
		(end 34.362136 -160.061148)
		(width 0.09525)
		(layer "F.Cu")
		(net "SAS2X28_DRIVE_RX_N_A8")
	)
	(segment
		(start 9.543796 -455.79665)
		(end 7.839202 -457.501244)
		(width 0.111252)
		(layer "F.Cu")
		(net "SAS_EXP_A_PWR6")
	)
	(segment
		(start 7.839202 -457.501244)
		(end 3.193542 -457.501244)
		(width 0.111252)
		(layer "F.Cu")
		(net "SAS_EXP_A_PWR6")
	)
	(segment
		(start 83.8962 -396.5448)
		(end 83.248246 -395.896846)
		(width 0.111252)
		(layer "F.Cu")
		(net "SAS_EXP_A_PWR6")
	)
	(segment
		(start 83.121246 -395.4907)
		(end 81.216246 -395.4907)
		(width 0.111252)
		(layer "F.Cu")
		(net "SAS_EXP_A_PWR6")
	)
	(segment
		(start 9.543796 -455.6887)
		(end 9.543796 -455.79665)
		(width 0.111252)
		(layer "F.Cu")
		(net "SAS_EXP_A_PWR6")
	)
	(segment
		(start 83.248246 -395.6177)
		(end 83.121246 -395.4907)
		(width 0.111252)
		(layer "F.Cu")
		(net "SAS_EXP_A_PWR6")
	)
	(segment
		(start 3.193542 -457.501244)
		(end 3.19024 -457.504546)
		(width 0.111252)
		(layer "F.Cu")
		(net "SAS_EXP_A_PWR6")
	)
	(segment
		(start 83.248246 -395.896846)
		(end 83.248246 -395.6177)
		(width 0.111252)
		(layer "F.Cu")
		(net "SAS_EXP_A_PWR6")
	)
	(via
		(at 83.8962 -396.5448)
		(size 0.5588)
		(drill 0.3048)
		(layers "F.Cu" "B.Cu")
		(net "SAS_EXP_A_PWR6")
	)
	(via
		(at 25.196546 -447.522346)
		(size 0.5588)
		(drill 0.3048)
		(layers "F.Cu" "B.Cu")
		(net "SAS_EXP_A_PWR6")
	)
	(via
		(at 15.8242 -454.5711)
		(size 0.7112)
		(drill 0.3556)
		(layers "F.Cu" "B.Cu")
		(net "SAS_EXP_A_PWR6")
	)
	(via
		(at 9.543796 -455.6887)
		(size 0.5588)
		(drill 0.3048)
		(layers "F.Cu" "B.Cu")
		(net "SAS_EXP_A_PWR6")
	)
	(segment
		(start 18.147792 -454.5711)
		(end 15.8242 -454.5711)
		(width 0.111252)
		(layer "B.Cu")
		(net "SAS_EXP_A_PWR6")
	)
	(segment
		(start 15.819374 -454.566274)
		(end 10.666222 -454.566274)
		(width 0.111252)
		(layer "B.Cu")
		(net "SAS_EXP_A_PWR6")
	)
	(segment
		(start 15.8242 -454.5711)
		(end 15.819374 -454.566274)
		(width 0.111252)
		(layer "B.Cu")
		(net "SAS_EXP_A_PWR6")
	)
	(segment
		(start 25.196546 -447.522346)
		(end 18.147792 -454.5711)
		(width 0.111252)
		(layer "B.Cu")
		(net "SAS_EXP_A_PWR6")
	)
	(segment
		(start 10.666222 -454.566274)
		(end 9.543796 -455.6887)
		(width 0.111252)
		(layer "B.Cu")
		(net "SAS_EXP_A_PWR6")
	)
	(segment
		(start 47.17923 -446.0494)
		(end 47.20463 -446.024)
		(width 0.14605)
		(layer "In5.Cu")
		(net "SAS_EXP_A_PWR6")
	)
	(segment
		(start 26.669492 -446.0494)
		(end 47.17923 -446.0494)
		(width 0.14605)
		(layer "In5.Cu")
		(net "SAS_EXP_A_PWR6")
	)
	(segment
		(start 25.196546 -447.522346)
		(end 26.669492 -446.0494)
		(width 0.14605)
		(layer "In5.Cu")
		(net "SAS_EXP_A_PWR6")
	)
	(segment
		(start 83.8962 -409.767532)
		(end 83.8962 -396.5448)
		(width 0.14605)
		(layer "In5.Cu")
		(net "SAS_EXP_A_PWR6")
	)
	(segment
		(start 47.20463 -446.024)
		(end 47.639732 -446.024)
		(width 0.14605)
		(layer "In5.Cu")
		(net "SAS_EXP_A_PWR6")
	)
	(segment
		(start 47.639732 -446.024)
		(end 83.8962 -409.767532)
		(width 0.14605)
		(layer "In5.Cu")
		(net "SAS_EXP_A_PWR6")
	)
	(segment
		(start 23.273766 -349.456756)
		(end 23.7236 -349.456756)
		(width 0.09525)
		(layer "F.Cu")
		(net "SAS2X28_A_HDD11_TX_+")
	)
	(segment
		(start 24.509984 -349.782638)
		(end 24.638 -349.9104)
		(width 0.09525)
		(layer "F.Cu")
		(net "SAS2X28_A_HDD11_TX_+")
	)
	(segment
		(start 21.75002 -349.929958)
		(end 23.039578 -349.929958)
		(width 0.09525)
		(layer "F.Cu")
		(net "SAS2X28_A_HDD11_TX_+")
	)
	(segment
		(start 23.172166 -349.79737)
		(end 23.172166 -349.558356)
		(width 0.09525)
		(layer "F.Cu")
		(net "SAS2X28_A_HDD11_TX_+")
	)
	(segment
		(start 4.833874 -347.49994)
		(end 4.83235 -347.498416)
		(width 0.09525)
		(layer "F.Cu")
		(net "SAS2X28_A_HDD11_TX_+")
	)
	(segment
		(start 5.901182 -347.83014)
		(end 5.562346 -347.83014)
		(width 0.09525)
		(layer "F.Cu")
		(net "SAS2X28_A_HDD11_TX_+")
	)
	(segment
		(start 4.83235 -347.498416)
		(end 3.192526 -347.498416)
		(width 0.09525)
		(layer "F.Cu")
		(net "SAS2X28_A_HDD11_TX_+")
	)
	(segment
		(start 5.31114 -347.726254)
		(end 5.262626 -347.677486)
		(width 0.09525)
		(layer "F.Cu")
		(net "SAS2X28_A_HDD11_TX_+")
	)
	(via
		(at 24.638 -349.9104)
		(size 0.5588)
		(drill 0.3048)
		(layers "F.Cu" "B.Cu")
		(net "SAS2X28_A_HDD11_TX_+")
	)
	(via
		(at 6.491732 -347.585538)
		(size 0.5588)
		(drill 0.3048)
		(layers "F.Cu" "B.Cu")
		(net "SAS2X28_A_HDD11_TX_+")
	)
	(arc
		(start 23.242524 -349.461582)
		(mid 23.257956 -349.45794)
		(end 23.273766 -349.456756)
		(width 0.09525)
		(layer "F.Cu")
		(net "SAS2X28_A_HDD11_TX_+")
	)
	(arc
		(start 6.491732 -347.585538)
		(mid 6.220785 -347.766579)
		(end 5.901182 -347.83014)
		(width 0.09525)
		(layer "F.Cu")
		(net "SAS2X28_A_HDD11_TX_+")
	)
	(arc
		(start 5.562346 -347.83014)
		(mid 5.426404 -347.803193)
		(end 5.31114 -347.726254)
		(width 0.09525)
		(layer "F.Cu")
		(net "SAS2X28_A_HDD11_TX_+")
	)
	(arc
		(start 23.172166 -349.558356)
		(mid 23.191604 -349.498508)
		(end 23.242524 -349.461582)
		(width 0.09525)
		(layer "F.Cu")
		(net "SAS2X28_A_HDD11_TX_+")
	)
	(arc
		(start 23.133304 -349.891096)
		(mid 23.162091 -349.848108)
		(end 23.172166 -349.79737)
		(width 0.09525)
		(layer "F.Cu")
		(net "SAS2X28_A_HDD11_TX_+")
	)
	(arc
		(start 23.039578 -349.929958)
		(mid 23.090303 -349.91985)
		(end 23.133304 -349.891096)
		(width 0.09525)
		(layer "F.Cu")
		(net "SAS2X28_A_HDD11_TX_+")
	)
	(arc
		(start 23.7236 -349.456756)
		(mid 24.149192 -349.541505)
		(end 24.509984 -349.782638)
		(width 0.09525)
		(layer "F.Cu")
		(net "SAS2X28_A_HDD11_TX_+")
	)
	(arc
		(start 5.262626 -347.677486)
		(mid 5.065913 -347.546047)
		(end 4.833874 -347.49994)
		(width 0.09525)
		(layer "F.Cu")
		(net "SAS2X28_A_HDD11_TX_+")
	)
	(segment
		(start 8.130794 -347.831664)
		(end 7.085838 -347.831664)
		(width 0.09525)
		(layer "B.Cu")
		(net "SAS2X28_A_HDD11_TX_+")
	)
	(segment
		(start 24.896826 -349.368872)
		(end 25.65019 -349.368872)
		(width 0.09525)
		(layer "B.Cu")
		(net "SAS2X28_A_HDD11_TX_+")
	)
	(segment
		(start 17.888204 -347.599254)
		(end 17.602454 -347.599254)
		(width 0.09525)
		(layer "B.Cu")
		(net "SAS2X28_A_HDD11_TX_+")
	)
	(segment
		(start 11.133074 -347.831664)
		(end 10.847324 -347.831664)
		(width 0.09525)
		(layer "B.Cu")
		(net "SAS2X28_A_HDD11_TX_+")
	)
	(segment
		(start 11.883644 -347.599254)
		(end 11.597894 -347.599254)
		(width 0.09525)
		(layer "B.Cu")
		(net "SAS2X28_A_HDD11_TX_+")
	)
	(segment
		(start 13.384784 -347.599254)
		(end 13.099034 -347.599254)
		(width 0.09525)
		(layer "B.Cu")
		(net "SAS2X28_A_HDD11_TX_+")
	)
	(segment
		(start 10.382504 -347.599254)
		(end 10.096754 -347.599254)
		(width 0.09525)
		(layer "B.Cu")
		(net "SAS2X28_A_HDD11_TX_+")
	)
	(segment
		(start 9.631934 -347.831664)
		(end 9.346184 -347.831664)
		(width 0.09525)
		(layer "B.Cu")
		(net "SAS2X28_A_HDD11_TX_+")
	)
	(segment
		(start 20.390612 -347.831664)
		(end 18.353024 -347.831664)
		(width 0.09525)
		(layer "B.Cu")
		(net "SAS2X28_A_HDD11_TX_+")
	)
	(segment
		(start 24.638 -349.9104)
		(end 24.638 -349.83166)
		(width 0.09525)
		(layer "B.Cu")
		(net "SAS2X28_A_HDD11_TX_+")
	)
	(segment
		(start 17.137634 -347.831664)
		(end 13.849604 -347.831664)
		(width 0.09525)
		(layer "B.Cu")
		(net "SAS2X28_A_HDD11_TX_+")
	)
	(segment
		(start 8.881364 -347.599254)
		(end 8.595614 -347.599254)
		(width 0.09525)
		(layer "B.Cu")
		(net "SAS2X28_A_HDD11_TX_+")
	)
	(segment
		(start 23.75027 -350.574864)
		(end 21.442426 -348.26702)
		(width 0.09525)
		(layer "B.Cu")
		(net "SAS2X28_A_HDD11_TX_+")
	)
	(segment
		(start 26.319988 -349.819976)
		(end 26.319988 -350.251776)
		(width 0.09525)
		(layer "B.Cu")
		(net "SAS2X28_A_HDD11_TX_+")
	)
	(segment
		(start 12.634214 -347.831664)
		(end 12.348464 -347.831664)
		(width 0.09525)
		(layer "B.Cu")
		(net "SAS2X28_A_HDD11_TX_+")
	)
	(segment
		(start 25.495758 -350.8375)
		(end 24.383492 -350.8375)
		(width 0.09525)
		(layer "B.Cu")
		(net "SAS2X28_A_HDD11_TX_+")
	)
	(segment
		(start 26.319988 -350.251776)
		(end 26.320242 -350.251776)
		(width 0.09525)
		(layer "B.Cu")
		(net "SAS2X28_A_HDD11_TX_+")
	)
	(arc
		(start 17.370044 -347.715332)
		(mid 17.26797 -347.801731)
		(end 17.137634 -347.831664)
		(width 0.09525)
		(layer "B.Cu")
		(net "SAS2X28_A_HDD11_TX_+")
	)
	(arc
		(start 12.866624 -347.715332)
		(mid 12.76455 -347.801731)
		(end 12.634214 -347.831664)
		(width 0.09525)
		(layer "B.Cu")
		(net "SAS2X28_A_HDD11_TX_+")
	)
	(arc
		(start 8.363204 -347.715332)
		(mid 8.26113 -347.801731)
		(end 8.130794 -347.831664)
		(width 0.09525)
		(layer "B.Cu")
		(net "SAS2X28_A_HDD11_TX_+")
	)
	(arc
		(start 9.864344 -347.715332)
		(mid 9.76227 -347.801731)
		(end 9.631934 -347.831664)
		(width 0.09525)
		(layer "B.Cu")
		(net "SAS2X28_A_HDD11_TX_+")
	)
	(arc
		(start 8.595614 -347.599254)
		(mid 8.465296 -347.629051)
		(end 8.363204 -347.715332)
		(width 0.09525)
		(layer "B.Cu")
		(net "SAS2X28_A_HDD11_TX_+")
	)
	(arc
		(start 11.365484 -347.715332)
		(mid 11.26341 -347.801731)
		(end 11.133074 -347.831664)
		(width 0.09525)
		(layer "B.Cu")
		(net "SAS2X28_A_HDD11_TX_+")
	)
	(arc
		(start 10.614914 -347.715332)
		(mid 10.512797 -347.629101)
		(end 10.382504 -347.599254)
		(width 0.09525)
		(layer "B.Cu")
		(net "SAS2X28_A_HDD11_TX_+")
	)
	(arc
		(start 21.442426 -348.26702)
		(mid 20.959805 -347.944792)
		(end 20.390612 -347.831664)
		(width 0.09525)
		(layer "B.Cu")
		(net "SAS2X28_A_HDD11_TX_+")
	)
	(arc
		(start 18.353024 -347.831664)
		(mid 18.222689 -347.801728)
		(end 18.120614 -347.715332)
		(width 0.09525)
		(layer "B.Cu")
		(net "SAS2X28_A_HDD11_TX_+")
	)
	(arc
		(start 26.23312 -349.61068)
		(mid 26.29739 -349.706677)
		(end 26.319988 -349.819976)
		(width 0.09525)
		(layer "B.Cu")
		(net "SAS2X28_A_HDD11_TX_+")
	)
	(arc
		(start 17.602454 -347.599254)
		(mid 17.472136 -347.629051)
		(end 17.370044 -347.715332)
		(width 0.09525)
		(layer "B.Cu")
		(net "SAS2X28_A_HDD11_TX_+")
	)
	(arc
		(start 12.116054 -347.715332)
		(mid 12.013937 -347.629101)
		(end 11.883644 -347.599254)
		(width 0.09525)
		(layer "B.Cu")
		(net "SAS2X28_A_HDD11_TX_+")
	)
	(arc
		(start 26.320242 -350.251776)
		(mid 26.278141 -350.414781)
		(end 26.182066 -350.55302)
		(width 0.09525)
		(layer "B.Cu")
		(net "SAS2X28_A_HDD11_TX_+")
	)
	(arc
		(start 24.383492 -350.8375)
		(mid 24.040769 -350.769141)
		(end 23.75027 -350.574864)
		(width 0.09525)
		(layer "B.Cu")
		(net "SAS2X28_A_HDD11_TX_+")
	)
	(arc
		(start 9.113774 -347.715332)
		(mid 9.011657 -347.629101)
		(end 8.881364 -347.599254)
		(width 0.09525)
		(layer "B.Cu")
		(net "SAS2X28_A_HDD11_TX_+")
	)
	(arc
		(start 18.120614 -347.715332)
		(mid 18.018497 -347.629101)
		(end 17.888204 -347.599254)
		(width 0.09525)
		(layer "B.Cu")
		(net "SAS2X28_A_HDD11_TX_+")
	)
	(arc
		(start 11.597894 -347.599254)
		(mid 11.467576 -347.629051)
		(end 11.365484 -347.715332)
		(width 0.09525)
		(layer "B.Cu")
		(net "SAS2X28_A_HDD11_TX_+")
	)
	(arc
		(start 10.096754 -347.599254)
		(mid 9.966436 -347.629051)
		(end 9.864344 -347.715332)
		(width 0.09525)
		(layer "B.Cu")
		(net "SAS2X28_A_HDD11_TX_+")
	)
	(arc
		(start 9.346184 -347.831664)
		(mid 9.215849 -347.801728)
		(end 9.113774 -347.715332)
		(width 0.09525)
		(layer "B.Cu")
		(net "SAS2X28_A_HDD11_TX_+")
	)
	(arc
		(start 12.348464 -347.831664)
		(mid 12.218129 -347.801728)
		(end 12.116054 -347.715332)
		(width 0.09525)
		(layer "B.Cu")
		(net "SAS2X28_A_HDD11_TX_+")
	)
	(arc
		(start 24.8158 -349.4024)
		(mid 24.852975 -349.37756)
		(end 24.896826 -349.368872)
		(width 0.09525)
		(layer "B.Cu")
		(net "SAS2X28_A_HDD11_TX_+")
	)
	(arc
		(start 26.182066 -350.55302)
		(mid 25.867214 -350.763524)
		(end 25.495758 -350.8375)
		(width 0.09525)
		(layer "B.Cu")
		(net "SAS2X28_A_HDD11_TX_+")
	)
	(arc
		(start 7.085838 -347.831664)
		(mid 6.764295 -347.767705)
		(end 6.491732 -347.585538)
		(width 0.09525)
		(layer "B.Cu")
		(net "SAS2X28_A_HDD11_TX_+")
	)
	(arc
		(start 13.099034 -347.599254)
		(mid 12.968716 -347.629051)
		(end 12.866624 -347.715332)
		(width 0.09525)
		(layer "B.Cu")
		(net "SAS2X28_A_HDD11_TX_+")
	)
	(arc
		(start 13.849604 -347.831664)
		(mid 13.719269 -347.801728)
		(end 13.617194 -347.715332)
		(width 0.09525)
		(layer "B.Cu")
		(net "SAS2X28_A_HDD11_TX_+")
	)
	(arc
		(start 25.65019 -349.368872)
		(mid 25.965696 -349.431817)
		(end 26.23312 -349.61068)
		(width 0.09525)
		(layer "B.Cu")
		(net "SAS2X28_A_HDD11_TX_+")
	)
	(arc
		(start 24.638 -349.83166)
		(mid 24.68421 -349.599348)
		(end 24.8158 -349.4024)
		(width 0.09525)
		(layer "B.Cu")
		(net "SAS2X28_A_HDD11_TX_+")
	)
	(arc
		(start 10.847324 -347.831664)
		(mid 10.716989 -347.801728)
		(end 10.614914 -347.715332)
		(width 0.09525)
		(layer "B.Cu")
		(net "SAS2X28_A_HDD11_TX_+")
	)
	(arc
		(start 13.617194 -347.715332)
		(mid 13.515077 -347.629101)
		(end 13.384784 -347.599254)
		(width 0.09525)
		(layer "B.Cu")
		(net "SAS2X28_A_HDD11_TX_+")
	)
	(segment
		(start 36.72586 -263.346692)
		(end 34.483548 -263.346692)
		(width 0.09525)
		(layer "F.Cu")
		(net "SAS2X28_DRIVE_RX_N_A7")
	)
	(segment
		(start 36.82746 -263.06272)
		(end 36.82746 -263.245092)
		(width 0.09525)
		(layer "F.Cu")
		(net "SAS2X28_DRIVE_RX_N_A7")
	)
	(segment
		(start 38.250114 -262.880094)
		(end 37.009832 -262.880094)
		(width 0.09525)
		(layer "F.Cu")
		(net "SAS2X28_DRIVE_RX_N_A7")
	)
	(arc
		(start 34.174684 -263.301734)
		(mid 33.929499 -263.194179)
		(end 33.718246 -263.0297)
		(width 0.09525)
		(layer "F.Cu")
		(net "SAS2X28_DRIVE_RX_N_A7")
	)
	(arc
		(start 34.483548 -263.346692)
		(mid 34.365109 -263.340192)
		(end 34.24809 -263.320784)
		(width 0.09525)
		(layer "F.Cu")
		(net "SAS2X28_DRIVE_RX_N_A7")
	)
	(arc
		(start 36.82746 -263.245092)
		(mid 36.808401 -263.304252)
		(end 36.758372 -263.341104)
		(width 0.09525)
		(layer "F.Cu")
		(net "SAS2X28_DRIVE_RX_N_A7")
	)
	(arc
		(start 37.009832 -262.880094)
		(mid 36.880786 -262.933599)
		(end 36.82746 -263.06272)
		(width 0.09525)
		(layer "F.Cu")
		(net "SAS2X28_DRIVE_RX_N_A7")
	)
	(arc
		(start 36.758372 -263.341104)
		(mid 36.742345 -263.345232)
		(end 36.72586 -263.346692)
		(width 0.09525)
		(layer "F.Cu")
		(net "SAS2X28_DRIVE_RX_N_A7")
	)
	(arc
		(start 34.24809 -263.320784)
		(mid 34.21122 -263.311903)
		(end 34.174684 -263.301734)
		(width 0.09525)
		(layer "F.Cu")
		(net "SAS2X28_DRIVE_RX_N_A7")
	)
	(segment
		(start 39.451534 -269.390114)
		(end 39.448232 -269.386812)
		(width 0.09525)
		(layer "F.Cu")
		(net "SAS2X28_DRIVE_RX_N_B7")
	)
	(segment
		(start 39.010082 -269.605506)
		(end 34.391346 -269.605506)
		(width 0.09525)
		(layer "F.Cu")
		(net "SAS2X28_DRIVE_RX_N_B7")
	)
	(segment
		(start 40.39997 -269.390114)
		(end 39.451534 -269.390114)
		(width 0.09525)
		(layer "F.Cu")
		(net "SAS2X28_DRIVE_RX_N_B7")
	)
	(segment
		(start 39.253922 -269.46733)
		(end 39.190422 -269.53083)
		(width 0.09525)
		(layer "F.Cu")
		(net "SAS2X28_DRIVE_RX_N_B7")
	)
	(segment
		(start 33.844738 -269.378938)
		(end 33.718246 -269.2527)
		(width 0.09525)
		(layer "F.Cu")
		(net "SAS2X28_DRIVE_RX_N_B7")
	)
	(arc
		(start 39.190422 -269.53083)
		(mid 39.107681 -269.586116)
		(end 39.010082 -269.605506)
		(width 0.09525)
		(layer "F.Cu")
		(net "SAS2X28_DRIVE_RX_N_B7")
	)
	(arc
		(start 39.448232 -269.386812)
		(mid 39.34306 -269.407732)
		(end 39.253922 -269.46733)
		(width 0.09525)
		(layer "F.Cu")
		(net "SAS2X28_DRIVE_RX_N_B7")
	)
	(arc
		(start 34.391346 -269.605506)
		(mid 34.095518 -269.546569)
		(end 33.844738 -269.378938)
		(width 0.09525)
		(layer "F.Cu")
		(net "SAS2X28_DRIVE_RX_N_B7")
	)
	(segment
		(start 34.416746 -434.3781)
		(end 34.416746 -435.5592)
		(width 0.111252)
		(layer "F.Cu")
		(net "SAS_EXP_A_PWR10")
	)
	(segment
		(start 34.543746 -433.5272)
		(end 34.543746 -434.2511)
		(width 0.111252)
		(layer "F.Cu")
		(net "SAS_EXP_A_PWR10")
	)
	(segment
		(start 34.543746 -434.2511)
		(end 34.416746 -434.3781)
		(width 0.111252)
		(layer "F.Cu")
		(net "SAS_EXP_A_PWR10")
	)
	(segment
		(start 7.365746 -461.981042)
		(end 8.541004 -461.981042)
		(width 0.111252)
		(layer "F.Cu")
		(net "SAS_EXP_A_PWR10")
	)
	(segment
		(start 6.841998 -462.50479)
		(end 7.365746 -461.981042)
		(width 0.111252)
		(layer "F.Cu")
		(net "SAS_EXP_A_PWR10")
	)
	(segment
		(start 3.19024 -462.50479)
		(end 6.841998 -462.50479)
		(width 0.111252)
		(layer "F.Cu")
		(net "SAS_EXP_A_PWR10")
	)
	(segment
		(start 8.541004 -461.981042)
		(end 9.245346 -461.2767)
		(width 0.111252)
		(layer "F.Cu")
		(net "SAS_EXP_A_PWR10")
	)
	(segment
		(start 9.245346 -461.2767)
		(end 9.245346 -460.469742)
		(width 0.111252)
		(layer "F.Cu")
		(net "SAS_EXP_A_PWR10")
	)
	(segment
		(start 9.245346 -460.469742)
		(end 9.112504 -460.3369)
		(width 0.111252)
		(layer "F.Cu")
		(net "SAS_EXP_A_PWR10")
	)
	(via
		(at 34.416746 -434.3781)
		(size 0.5588)
		(drill 0.3048)
		(layers "F.Cu" "B.Cu")
		(net "SAS_EXP_A_PWR10")
	)
	(via
		(at 23.240746 -458.609446)
		(size 0.7112)
		(drill 0.3556)
		(layers "F.Cu" "B.Cu")
		(net "SAS_EXP_A_PWR10")
	)
	(via
		(at 34.518346 -437.5277)
		(size 0.7112)
		(drill 0.3556)
		(layers "F.Cu" "B.Cu")
		(net "SAS_EXP_A_PWR10")
	)
	(via
		(at 9.112504 -460.3369)
		(size 0.5588)
		(drill 0.3048)
		(layers "F.Cu" "B.Cu")
		(net "SAS_EXP_A_PWR10")
	)
	(segment
		(start 34.3662 -449.1736)
		(end 34.3662 -438.218326)
		(width 0.111252)
		(layer "B.Cu")
		(net "SAS_EXP_A_PWR10")
	)
	(segment
		(start 23.240746 -458.609446)
		(end 24.930354 -458.609446)
		(width 0.111252)
		(layer "B.Cu")
		(net "SAS_EXP_A_PWR10")
	)
	(segment
		(start 10.458958 -458.990446)
		(end 22.859746 -458.990446)
		(width 0.111252)
		(layer "B.Cu")
		(net "SAS_EXP_A_PWR10")
	)
	(segment
		(start 34.416746 -434.3781)
		(end 34.518346 -434.4797)
		(width 0.111252)
		(layer "B.Cu")
		(net "SAS_EXP_A_PWR10")
	)
	(segment
		(start 34.518346 -438.06618)
		(end 34.518346 -437.5277)
		(width 0.111252)
		(layer "B.Cu")
		(net "SAS_EXP_A_PWR10")
	)
	(segment
		(start 22.859746 -458.990446)
		(end 23.240746 -458.609446)
		(width 0.111252)
		(layer "B.Cu")
		(net "SAS_EXP_A_PWR10")
	)
	(segment
		(start 34.518346 -434.4797)
		(end 34.518346 -437.5277)
		(width 0.111252)
		(layer "B.Cu")
		(net "SAS_EXP_A_PWR10")
	)
	(segment
		(start 9.112504 -460.3369)
		(end 10.458958 -458.990446)
		(width 0.111252)
		(layer "B.Cu")
		(net "SAS_EXP_A_PWR10")
	)
	(segment
		(start 24.930354 -458.609446)
		(end 34.3662 -449.1736)
		(width 0.111252)
		(layer "B.Cu")
		(net "SAS_EXP_A_PWR10")
	)
	(segment
		(start 34.3662 -438.218326)
		(end 34.518346 -438.06618)
		(width 0.111252)
		(layer "B.Cu")
		(net "SAS_EXP_A_PWR10")
	)
	(via
		(at 73.278746 -19.4437)
		(size 0.7112)
		(drill 0.4064)
		(layers "F.Cu" "B.Cu")
		(net "5V_PRE_14")
	)
	(via
		(at 18.922746 -20.4851)
		(size 0.5588)
		(drill 0.3048)
		(layers "F.Cu" "B.Cu")
		(net "5V_PRE_14")
	)
	(via
		(at 73.532746 -20.4597)
		(size 0.7112)
		(drill 0.4064)
		(layers "F.Cu" "B.Cu")
		(net "5V_PRE_14")
	)
	(via
		(at 18.922746 -21.3487)
		(size 0.5588)
		(drill 0.3048)
		(layers "F.Cu" "B.Cu")
		(net "5V_PRE_14")
	)
	(via
		(at 73.659746 -18.4277)
		(size 0.7112)
		(drill 0.4064)
		(layers "F.Cu" "B.Cu")
		(net "5V_PRE_14")
	)
	(via
		(at 72.643746 -18.4277)
		(size 0.7112)
		(drill 0.3556)
		(layers "F.Cu" "B.Cu")
		(net "5V_PRE_14")
	)
	(segment
		(start 73.659746 -18.4277)
		(end 72.643746 -18.4277)
		(width 0.508)
		(layer "B.Cu")
		(net "5V_PRE_14")
	)
	(segment
		(start 6.478778 -348.49943)
		(end 6.292342 -348.312994)
		(width 0.09525)
		(layer "F.Cu")
		(net "SAS2X28_A_HDD11_TX_-")
	)
	(segment
		(start 4.684014 -348.498414)
		(end 3.192526 -348.498414)
		(width 0.09525)
		(layer "F.Cu")
		(net "SAS2X28_A_HDD11_TX_-")
	)
	(segment
		(start 21.75002 -348.659958)
		(end 22.932898 -348.659958)
		(width 0.09525)
		(layer "F.Cu")
		(net "SAS2X28_A_HDD11_TX_-")
	)
	(segment
		(start 23.101808 -348.729808)
		(end 23.129748 -348.757494)
		(width 0.09525)
		(layer "F.Cu")
		(net "SAS2X28_A_HDD11_TX_-")
	)
	(segment
		(start 24.590502 -348.933262)
		(end 24.696166 -348.827598)
		(width 0.09525)
		(layer "F.Cu")
		(net "SAS2X28_A_HDD11_TX_-")
	)
	(segment
		(start 5.923788 -348.16034)
		(end 5.505196 -348.16034)
		(width 0.09525)
		(layer "F.Cu")
		(net "SAS2X28_A_HDD11_TX_-")
	)
	(segment
		(start 4.685538 -348.499938)
		(end 4.684014 -348.498414)
		(width 0.09525)
		(layer "F.Cu")
		(net "SAS2X28_A_HDD11_TX_-")
	)
	(segment
		(start 23.172166 -348.859856)
		(end 23.172166 -349.024956)
		(width 0.09525)
		(layer "F.Cu")
		(net "SAS2X28_A_HDD11_TX_-")
	)
	(segment
		(start 23.273766 -349.126556)
		(end 24.12365 -349.126556)
		(width 0.09525)
		(layer "F.Cu")
		(net "SAS2X28_A_HDD11_TX_-")
	)
	(via
		(at 6.478778 -348.49943)
		(size 0.5588)
		(drill 0.3048)
		(layers "F.Cu" "B.Cu")
		(net "SAS2X28_A_HDD11_TX_-")
	)
	(via
		(at 24.696166 -348.827598)
		(size 0.5588)
		(drill 0.3048)
		(layers "F.Cu" "B.Cu")
		(net "SAS2X28_A_HDD11_TX_-")
	)
	(arc
		(start 23.129748 -348.757494)
		(mid 23.161128 -348.804458)
		(end 23.172166 -348.859856)
		(width 0.09525)
		(layer "F.Cu")
		(net "SAS2X28_A_HDD11_TX_-")
	)
	(arc
		(start 6.292342 -348.312994)
		(mid 6.123248 -348.200009)
		(end 5.923788 -348.16034)
		(width 0.09525)
		(layer "F.Cu")
		(net "SAS2X28_A_HDD11_TX_-")
	)
	(arc
		(start 23.172166 -349.024956)
		(mid 23.191769 -349.084948)
		(end 23.243032 -349.12173)
		(width 0.09525)
		(layer "F.Cu")
		(net "SAS2X28_A_HDD11_TX_-")
	)
	(arc
		(start 23.243032 -349.12173)
		(mid 23.258213 -349.125333)
		(end 23.273766 -349.126556)
		(width 0.09525)
		(layer "F.Cu")
		(net "SAS2X28_A_HDD11_TX_-")
	)
	(arc
		(start 22.932898 -348.659958)
		(mid 23.024296 -348.678103)
		(end 23.101808 -348.729808)
		(width 0.09525)
		(layer "F.Cu")
		(net "SAS2X28_A_HDD11_TX_-")
	)
	(arc
		(start 5.146548 -348.30893)
		(mid 4.935035 -348.450259)
		(end 4.685538 -348.499938)
		(width 0.09525)
		(layer "F.Cu")
		(net "SAS2X28_A_HDD11_TX_-")
	)
	(arc
		(start 24.12365 -349.126556)
		(mid 24.376291 -349.07632)
		(end 24.590502 -348.933262)
		(width 0.09525)
		(layer "F.Cu")
		(net "SAS2X28_A_HDD11_TX_-")
	)
	(arc
		(start 5.505196 -348.16034)
		(mid 5.311084 -348.198951)
		(end 5.146548 -348.30893)
		(width 0.09525)
		(layer "F.Cu")
		(net "SAS2X28_A_HDD11_TX_-")
	)
	(segment
		(start 25.496012 -351.1677)
		(end 24.383746 -351.1677)
		(width 0.09525)
		(layer "B.Cu")
		(net "SAS2X28_A_HDD11_TX_-")
	)
	(segment
		(start 26.650188 -349.819722)
		(end 26.650188 -350.277176)
		(width 0.09525)
		(layer "B.Cu")
		(net "SAS2X28_A_HDD11_TX_-")
	)
	(segment
		(start 20.390866 -348.161864)
		(end 7.238746 -348.161864)
		(width 0.09525)
		(layer "B.Cu")
		(net "SAS2X28_A_HDD11_TX_-")
	)
	(segment
		(start 6.51764 -348.460568)
		(end 6.478778 -348.49943)
		(width 0.09525)
		(layer "B.Cu")
		(net "SAS2X28_A_HDD11_TX_-")
	)
	(segment
		(start 25.20569 -349.038672)
		(end 25.649936 -349.038672)
		(width 0.09525)
		(layer "B.Cu")
		(net "SAS2X28_A_HDD11_TX_-")
	)
	(segment
		(start 23.51659 -350.808544)
		(end 21.208746 -348.5007)
		(width 0.09525)
		(layer "B.Cu")
		(net "SAS2X28_A_HDD11_TX_-")
	)
	(arc
		(start 26.4668 -349.377)
		(mid 26.602522 -349.580123)
		(end 26.650188 -349.819722)
		(width 0.09525)
		(layer "B.Cu")
		(net "SAS2X28_A_HDD11_TX_-")
	)
	(arc
		(start 25.649936 -349.038672)
		(mid 26.092009 -349.126606)
		(end 26.4668 -349.377)
		(width 0.09525)
		(layer "B.Cu")
		(net "SAS2X28_A_HDD11_TX_-")
	)
	(arc
		(start 26.650188 -350.277176)
		(mid 26.578621 -350.552954)
		(end 26.415746 -350.7867)
		(width 0.09525)
		(layer "B.Cu")
		(net "SAS2X28_A_HDD11_TX_-")
	)
	(arc
		(start 24.383746 -351.1677)
		(mid 23.914457 -351.074353)
		(end 23.51659 -350.808544)
		(width 0.09525)
		(layer "B.Cu")
		(net "SAS2X28_A_HDD11_TX_-")
	)
	(arc
		(start 24.696166 -348.827598)
		(mid 24.929938 -348.983799)
		(end 25.20569 -349.038672)
		(width 0.09525)
		(layer "B.Cu")
		(net "SAS2X28_A_HDD11_TX_-")
	)
	(arc
		(start 7.238746 -348.161864)
		(mid 6.848482 -348.239492)
		(end 6.51764 -348.460568)
		(width 0.09525)
		(layer "B.Cu")
		(net "SAS2X28_A_HDD11_TX_-")
	)
	(arc
		(start 26.415746 -350.7867)
		(mid 25.993768 -351.068656)
		(end 25.496012 -351.1677)
		(width 0.09525)
		(layer "B.Cu")
		(net "SAS2X28_A_HDD11_TX_-")
	)
	(arc
		(start 21.208746 -348.5007)
		(mid 20.8335 -348.249939)
		(end 20.390866 -348.161864)
		(width 0.09525)
		(layer "B.Cu")
		(net "SAS2X28_A_HDD11_TX_-")
	)
	(segment
		(start 36.594796 -366.34674)
		(end 33.77311 -366.34674)
		(width 0.09525)
		(layer "F.Cu")
		(net "SAS2X28_DRIVE_RX_N_A6")
	)
	(segment
		(start 33.445196 -366.21085)
		(end 33.30956 -366.075214)
		(width 0.09525)
		(layer "F.Cu")
		(net "SAS2X28_DRIVE_RX_N_A6")
	)
	(segment
		(start 38.250114 -365.880142)
		(end 38.246812 -365.87684)
		(width 0.09525)
		(layer "F.Cu")
		(net "SAS2X28_DRIVE_RX_N_A6")
	)
	(segment
		(start 38.246812 -365.87684)
		(end 37.064696 -365.87684)
		(width 0.09525)
		(layer "F.Cu")
		(net "SAS2X28_DRIVE_RX_N_A6")
	)
	(arc
		(start 37.064696 -365.87684)
		(mid 36.898561 -365.945655)
		(end 36.829746 -366.11179)
		(width 0.09525)
		(layer "F.Cu")
		(net "SAS2X28_DRIVE_RX_N_A6")
	)
	(arc
		(start 36.660836 -366.337088)
		(mid 36.660582 -366.337088)
		(end 36.660328 -366.337088)
		(width 0.09525)
		(layer "F.Cu")
		(net "SAS2X28_DRIVE_RX_N_A6")
	)
	(arc
		(start 36.660328 -366.337088)
		(mid 36.627903 -366.344227)
		(end 36.594796 -366.34674)
		(width 0.09525)
		(layer "F.Cu")
		(net "SAS2X28_DRIVE_RX_N_A6")
	)
	(arc
		(start 36.829746 -366.11179)
		(mid 36.782828 -366.252579)
		(end 36.660836 -366.337088)
		(width 0.09525)
		(layer "F.Cu")
		(net "SAS2X28_DRIVE_RX_N_A6")
	)
	(arc
		(start 33.77311 -366.34674)
		(mid 33.595634 -366.31142)
		(end 33.445196 -366.21085)
		(width 0.09525)
		(layer "F.Cu")
		(net "SAS2X28_DRIVE_RX_N_A6")
	)
	(segment
		(start 39.192708 -372.390162)
		(end 39.189406 -372.38686)
		(width 0.09525)
		(layer "F.Cu")
		(net "SAS2X28_DRIVE_RX_N_B6")
	)
	(segment
		(start 38.622224 -372.62181)
		(end 34.090864 -372.62181)
		(width 0.09525)
		(layer "F.Cu")
		(net "SAS2X28_DRIVE_RX_N_B6")
	)
	(segment
		(start 40.39997 -372.390162)
		(end 39.192708 -372.390162)
		(width 0.09525)
		(layer "F.Cu")
		(net "SAS2X28_DRIVE_RX_N_B6")
	)
	(arc
		(start 39.189406 -372.38686)
		(mid 39.08783 -372.407065)
		(end 39.0017 -372.464584)
		(width 0.09525)
		(layer "F.Cu")
		(net "SAS2X28_DRIVE_RX_N_B6")
	)
	(arc
		(start 34.090864 -372.62181)
		(mid 33.668037 -372.537704)
		(end 33.30956 -372.298214)
		(width 0.09525)
		(layer "F.Cu")
		(net "SAS2X28_DRIVE_RX_N_B6")
	)
	(arc
		(start 39.0017 -372.464584)
		(mid 38.827595 -372.580917)
		(end 38.622224 -372.62181)
		(width 0.09525)
		(layer "F.Cu")
		(net "SAS2X28_DRIVE_RX_N_B6")
	)
	(segment
		(start 84.354162 -494.825782)
		(end 84.043266 -494.514886)
		(width 0.111252)
		(layer "F.Cu")
		(net "SAS_EXP_A_PWR5")
	)
	(segment
		(start 7.143242 -465.207858)
		(end 6.436868 -464.501484)
		(width 0.111252)
		(layer "F.Cu")
		(net "SAS_EXP_A_PWR5")
	)
	(segment
		(start 84.354162 -495.359182)
		(end 84.354162 -494.825782)
		(width 0.111252)
		(layer "F.Cu")
		(net "SAS_EXP_A_PWR5")
	)
	(segment
		(start 85.336634 -494.641886)
		(end 85.22208 -494.75644)
		(width 0.111252)
		(layer "F.Cu")
		(net "SAS_EXP_A_PWR5")
	)
	(segment
		(start 6.436868 -464.501484)
		(end 3.193542 -464.501484)
		(width 0.111252)
		(layer "F.Cu")
		(net "SAS_EXP_A_PWR5")
	)
	(segment
		(start 85.22208 -494.75644)
		(end 85.22208 -496.2271)
		(width 0.111252)
		(layer "F.Cu")
		(net "SAS_EXP_A_PWR5")
	)
	(segment
		(start 85.22208 -496.2271)
		(end 84.354162 -495.359182)
		(width 0.111252)
		(layer "F.Cu")
		(net "SAS_EXP_A_PWR5")
	)
	(segment
		(start 84.043266 -494.514886)
		(end 83.050634 -494.514886)
		(width 0.111252)
		(layer "F.Cu")
		(net "SAS_EXP_A_PWR5")
	)
	(segment
		(start 3.193542 -464.501484)
		(end 3.19024 -464.504786)
		(width 0.111252)
		(layer "F.Cu")
		(net "SAS_EXP_A_PWR5")
	)
	(via
		(at 85.22208 -496.2271)
		(size 0.7112)
		(drill 0.3556)
		(layers "F.Cu" "B.Cu")
		(net "SAS_EXP_A_PWR5")
	)
	(via
		(at 84.354162 -494.825782)
		(size 0.5588)
		(drill 0.3048)
		(layers "F.Cu" "B.Cu")
		(net "SAS_EXP_A_PWR5")
	)
	(via
		(at 7.143242 -465.207858)
		(size 0.5588)
		(drill 0.3048)
		(layers "F.Cu" "B.Cu")
		(net "SAS_EXP_A_PWR5")
	)
	(segment
		(start 34.83102 -475.09938)
		(end 34.870898 -475.126304)
		(width 0.14605)
		(layer "In5.Cu")
		(net "SAS_EXP_A_PWR5")
	)
	(segment
		(start 13.280136 -472.497404)
		(end 13.46073 -472.677998)
		(width 0.14605)
		(layer "In5.Cu")
		(net "SAS_EXP_A_PWR5")
	)
	(segment
		(start 13.279882 -472.497404)
		(end 13.280136 -472.497404)
		(width 0.14605)
		(layer "In5.Cu")
		(net "SAS_EXP_A_PWR5")
	)
	(segment
		(start 7.143242 -465.207858)
		(end 7.143242 -465.683346)
		(width 0.14605)
		(layer "In5.Cu")
		(net "SAS_EXP_A_PWR5")
	)
	(segment
		(start 69.690742 -475.126304)
		(end 84.784692 -490.220254)
		(width 0.14605)
		(layer "In5.Cu")
		(net "SAS_EXP_A_PWR5")
	)
	(segment
		(start 9.246362 -467.786466)
		(end 9.246362 -468.463884)
		(width 0.14605)
		(layer "In5.Cu")
		(net "SAS_EXP_A_PWR5")
	)
	(segment
		(start 84.784692 -494.395252)
		(end 84.354162 -494.825782)
		(width 0.14605)
		(layer "In5.Cu")
		(net "SAS_EXP_A_PWR5")
	)
	(segment
		(start 34.870898 -475.126304)
		(end 69.690742 -475.126304)
		(width 0.14605)
		(layer "In5.Cu")
		(net "SAS_EXP_A_PWR5")
	)
	(segment
		(start 9.246362 -468.463884)
		(end 13.279882 -472.497404)
		(width 0.14605)
		(layer "In5.Cu")
		(net "SAS_EXP_A_PWR5")
	)
	(segment
		(start 13.46073 -472.677998)
		(end 32.409638 -472.677998)
		(width 0.14605)
		(layer "In5.Cu")
		(net "SAS_EXP_A_PWR5")
	)
	(segment
		(start 32.409638 -472.677998)
		(end 34.83102 -475.09938)
		(width 0.14605)
		(layer "In5.Cu")
		(net "SAS_EXP_A_PWR5")
	)
	(segment
		(start 84.784692 -490.220254)
		(end 84.784692 -494.395252)
		(width 0.14605)
		(layer "In5.Cu")
		(net "SAS_EXP_A_PWR5")
	)
	(segment
		(start 7.143242 -465.683346)
		(end 9.246362 -467.786466)
		(width 0.14605)
		(layer "In5.Cu")
		(net "SAS_EXP_A_PWR5")
	)
	(via
		(at 36.994846 -129.4257)
		(size 0.7112)
		(drill 0.4064)
		(layers "F.Cu" "B.Cu")
		(net "5V_PRE_13")
	)
	(via
		(at 33.616646 -129.2987)
		(size 0.7112)
		(drill 0.3556)
		(layers "F.Cu" "B.Cu")
		(net "5V_PRE_13")
	)
	(via
		(at 25.145746 -123.9647)
		(size 0.7112)
		(drill 0.4064)
		(layers "F.Cu" "B.Cu")
		(net "5V_PRE_13")
	)
	(via
		(at 24.002746 -123.5837)
		(size 0.7112)
		(drill 0.4064)
		(layers "F.Cu" "B.Cu")
		(net "5V_PRE_13")
	)
	(via
		(at 34.632646 -129.2987)
		(size 0.7112)
		(drill 0.4064)
		(layers "F.Cu" "B.Cu")
		(net "5V_PRE_13")
	)
	(segment
		(start 34.632646 -129.2987)
		(end 33.616646 -129.2987)
		(width 0.508)
		(layer "B.Cu")
		(net "5V_PRE_13")
	)
	(segment
		(start 39.440358 -475.39021)
		(end 39.437056 -475.386908)
		(width 0.09525)
		(layer "F.Cu")
		(net "SAS2X28_DRIVE_RX_N_B5")
	)
	(segment
		(start 38.870636 -475.621604)
		(end 34.442146 -475.621604)
		(width 0.09525)
		(layer "F.Cu")
		(net "SAS2X28_DRIVE_RX_N_B5")
	)
	(segment
		(start 40.39997 -475.39021)
		(end 39.440358 -475.39021)
		(width 0.09525)
		(layer "F.Cu")
		(net "SAS2X28_DRIVE_RX_N_B5")
	)
	(segment
		(start 33.581594 -475.264988)
		(end 33.487868 -475.171516)
		(width 0.09525)
		(layer "F.Cu")
		(net "SAS2X28_DRIVE_RX_N_B5")
	)
	(arc
		(start 39.437056 -475.386908)
		(mid 39.309333 -475.412314)
		(end 39.20109 -475.484698)
		(width 0.09525)
		(layer "F.Cu")
		(net "SAS2X28_DRIVE_RX_N_B5")
	)
	(arc
		(start 39.20109 -475.484698)
		(mid 39.049476 -475.586003)
		(end 38.870636 -475.621604)
		(width 0.09525)
		(layer "F.Cu")
		(net "SAS2X28_DRIVE_RX_N_B5")
	)
	(arc
		(start 34.322766 -475.615508)
		(mid 33.921792 -475.504517)
		(end 33.581594 -475.264988)
		(width 0.09525)
		(layer "F.Cu")
		(net "SAS2X28_DRIVE_RX_N_B5")
	)
	(arc
		(start 34.442146 -475.621604)
		(mid 34.382381 -475.620023)
		(end 34.322766 -475.615508)
		(width 0.09525)
		(layer "F.Cu")
		(net "SAS2X28_DRIVE_RX_N_B5")
	)
	(segment
		(start 38.250114 -468.88019)
		(end 37.011864 -468.88019)
		(width 0.09525)
		(layer "F.Cu")
		(net "SAS2X28_DRIVE_RX_N_A5")
	)
	(segment
		(start 36.72586 -469.346788)
		(end 34.449258 -469.346788)
		(width 0.09525)
		(layer "F.Cu")
		(net "SAS2X28_DRIVE_RX_N_A5")
	)
	(segment
		(start 36.82746 -469.064594)
		(end 36.82746 -469.245188)
		(width 0.09525)
		(layer "F.Cu")
		(net "SAS2X28_DRIVE_RX_N_A5")
	)
	(arc
		(start 37.011864 -468.88019)
		(mid 36.941364 -468.894178)
		(end 36.881562 -468.934038)
		(width 0.09525)
		(layer "F.Cu")
		(net "SAS2X28_DRIVE_RX_N_A5")
	)
	(arc
		(start 36.82746 -469.245188)
		(mid 36.797702 -469.31703)
		(end 36.72586 -469.346788)
		(width 0.09525)
		(layer "F.Cu")
		(net "SAS2X28_DRIVE_RX_N_A5")
	)
	(arc
		(start 34.449258 -469.346788)
		(mid 33.928938 -469.24329)
		(end 33.487868 -468.948516)
		(width 0.09525)
		(layer "F.Cu")
		(net "SAS2X28_DRIVE_RX_N_A5")
	)
	(arc
		(start 36.881562 -468.934038)
		(mid 36.841538 -468.993938)
		(end 36.82746 -469.064594)
		(width 0.09525)
		(layer "F.Cu")
		(net "SAS2X28_DRIVE_RX_N_A5")
	)
	(segment
		(start 9.347454 -455.2315)
		(end 9.0551 -455.2315)
		(width 0.111252)
		(layer "F.Cu")
		(net "SAS_EXP_A_PWR3")
	)
	(segment
		(start 10.718546 -455.2315)
		(end 9.740138 -455.2315)
		(width 0.111252)
		(layer "F.Cu")
		(net "SAS_EXP_A_PWR3")
	)
	(segment
		(start 6.858 -456.501246)
		(end 3.193542 -456.501246)
		(width 0.111252)
		(layer "F.Cu")
		(net "SAS_EXP_A_PWR3")
	)
	(segment
		(start 9.740138 -455.2315)
		(end 9.735312 -455.226674)
		(width 0.111252)
		(layer "F.Cu")
		(net "SAS_EXP_A_PWR3")
	)
	(segment
		(start 8.382 -455.9046)
		(end 7.454646 -455.9046)
		(width 0.111252)
		(layer "F.Cu")
		(net "SAS_EXP_A_PWR3")
	)
	(segment
		(start 195.579746 -186.1947)
		(end 196.659246 -185.1152)
		(width 0.111252)
		(layer "F.Cu")
		(net "SAS_EXP_A_PWR3")
	)
	(segment
		(start 9.735312 -455.226674)
		(end 9.35228 -455.226674)
		(width 0.111252)
		(layer "F.Cu")
		(net "SAS_EXP_A_PWR3")
	)
	(segment
		(start 196.362574 -184.755028)
		(end 194.804284 -184.755028)
		(width 0.111252)
		(layer "F.Cu")
		(net "SAS_EXP_A_PWR3")
	)
	(segment
		(start 196.659246 -185.1152)
		(end 196.659246 -185.0517)
		(width 0.111252)
		(layer "F.Cu")
		(net "SAS_EXP_A_PWR3")
	)
	(segment
		(start 9.35228 -455.226674)
		(end 9.347454 -455.2315)
		(width 0.111252)
		(layer "F.Cu")
		(net "SAS_EXP_A_PWR3")
	)
	(segment
		(start 196.659246 -185.0517)
		(end 196.362574 -184.755028)
		(width 0.111252)
		(layer "F.Cu")
		(net "SAS_EXP_A_PWR3")
	)
	(segment
		(start 9.0551 -455.2315)
		(end 8.382 -455.9046)
		(width 0.111252)
		(layer "F.Cu")
		(net "SAS_EXP_A_PWR3")
	)
	(segment
		(start 7.454646 -455.9046)
		(end 6.858 -456.501246)
		(width 0.111252)
		(layer "F.Cu")
		(net "SAS_EXP_A_PWR3")
	)
	(segment
		(start 3.193542 -456.501246)
		(end 3.19024 -456.504548)
		(width 0.111252)
		(layer "F.Cu")
		(net "SAS_EXP_A_PWR3")
	)
	(via
		(at 196.646546 -186.1947)
		(size 0.7112)
		(drill 0.3556)
		(layers "F.Cu" "B.Cu")
		(net "SAS_EXP_A_PWR3")
	)
	(via
		(at 195.579746 -186.1947)
		(size 0.5588)
		(drill 0.3048)
		(layers "F.Cu" "B.Cu")
		(net "SAS_EXP_A_PWR3")
	)
	(via
		(at 10.718546 -455.2315)
		(size 0.5588)
		(drill 0.3048)
		(layers "F.Cu" "B.Cu")
		(net "SAS_EXP_A_PWR3")
	)
	(segment
		(start 195.579746 -186.1947)
		(end 196.646546 -186.1947)
		(width 0.111252)
		(layer "B.Cu")
		(net "SAS_EXP_A_PWR3")
	)
	(segment
		(start 12.668504 -462.000346)
		(end 14.92377 -464.255612)
		(width 0.14605)
		(layer "In5.Cu")
		(net "SAS_EXP_A_PWR3")
	)
	(segment
		(start 14.92377 -464.255612)
		(end 15.469108 -464.255612)
		(width 0.14605)
		(layer "In5.Cu")
		(net "SAS_EXP_A_PWR3")
	)
	(segment
		(start 138.569954 -465.960714)
		(end 138.577828 -465.94141)
		(width 0.14605)
		(layer "In5.Cu")
		(net "SAS_EXP_A_PWR3")
	)
	(segment
		(start 219.95765 -384.534664)
		(end 220.370908 -384.12166)
		(width 0.14605)
		(layer "In5.Cu")
		(net "SAS_EXP_A_PWR3")
	)
	(segment
		(start 138.629644 -465.863432)
		(end 138.663934 -465.829142)
		(width 0.14605)
		(layer "In5.Cu")
		(net "SAS_EXP_A_PWR3")
	)
	(segment
		(start 12.668504 -458.537056)
		(end 12.668504 -462.000346)
		(width 0.14605)
		(layer "In5.Cu")
		(net "SAS_EXP_A_PWR3")
	)
	(segment
		(start 138.577828 -465.94141)
		(end 138.629644 -465.863432)
		(width 0.14605)
		(layer "In5.Cu")
		(net "SAS_EXP_A_PWR3")
	)
	(segment
		(start 195.328032 -195.597272)
		(end 195.328032 -186.446414)
		(width 0.14605)
		(layer "In5.Cu")
		(net "SAS_EXP_A_PWR3")
	)
	(segment
		(start 10.718546 -455.2315)
		(end 11.372596 -455.88555)
		(width 0.14605)
		(layer "In5.Cu")
		(net "SAS_EXP_A_PWR3")
	)
	(segment
		(start 20.772374 -466.963252)
		(end 21.595842 -466.139784)
		(width 0.14605)
		(layer "In5.Cu")
		(net "SAS_EXP_A_PWR3")
	)
	(segment
		(start 11.372596 -457.241148)
		(end 12.668504 -458.537056)
		(width 0.14605)
		(layer "In5.Cu")
		(net "SAS_EXP_A_PWR3")
	)
	(segment
		(start 138.663934 -465.829142)
		(end 219.95765 -384.535172)
		(width 0.14605)
		(layer "In5.Cu")
		(net "SAS_EXP_A_PWR3")
	)
	(segment
		(start 195.328032 -186.446414)
		(end 195.579746 -186.1947)
		(width 0.14605)
		(layer "In5.Cu")
		(net "SAS_EXP_A_PWR3")
	)
	(segment
		(start 220.370908 -384.12166)
		(end 229.459028 -375.03354)
		(width 0.14605)
		(layer "In5.Cu")
		(net "SAS_EXP_A_PWR3")
	)
	(segment
		(start 138.390884 -466.139784)
		(end 138.569954 -465.960714)
		(width 0.14605)
		(layer "In5.Cu")
		(net "SAS_EXP_A_PWR3")
	)
	(segment
		(start 21.595842 -466.139784)
		(end 138.390884 -466.139784)
		(width 0.14605)
		(layer "In5.Cu")
		(net "SAS_EXP_A_PWR3")
	)
	(segment
		(start 229.459028 -229.728268)
		(end 195.328032 -195.597272)
		(width 0.14605)
		(layer "In5.Cu")
		(net "SAS_EXP_A_PWR3")
	)
	(segment
		(start 15.469108 -464.255612)
		(end 18.176748 -466.963252)
		(width 0.14605)
		(layer "In5.Cu")
		(net "SAS_EXP_A_PWR3")
	)
	(segment
		(start 219.95765 -384.535172)
		(end 219.95765 -384.534664)
		(width 0.14605)
		(layer "In5.Cu")
		(net "SAS_EXP_A_PWR3")
	)
	(segment
		(start 229.459028 -375.03354)
		(end 229.459028 -229.728268)
		(width 0.14605)
		(layer "In5.Cu")
		(net "SAS_EXP_A_PWR3")
	)
	(segment
		(start 11.372596 -455.88555)
		(end 11.372596 -457.241148)
		(width 0.14605)
		(layer "In5.Cu")
		(net "SAS_EXP_A_PWR3")
	)
	(segment
		(start 18.176748 -466.963252)
		(end 20.772374 -466.963252)
		(width 0.14605)
		(layer "In5.Cu")
		(net "SAS_EXP_A_PWR3")
	)
	(via
		(at 40.004746 -229.7557)
		(size 0.7112)
		(drill 0.4064)
		(layers "F.Cu" "B.Cu")
		(net "5V_PRE_12")
	)
	(via
		(at 22.732746 -226.5807)
		(size 0.7112)
		(drill 0.3556)
		(layers "F.Cu" "B.Cu")
		(net "5V_PRE_12")
	)
	(via
		(at 40.004746 -230.8987)
		(size 0.7112)
		(drill 0.4064)
		(layers "F.Cu" "B.Cu")
		(net "5V_PRE_12")
	)
	(via
		(at 23.748746 -226.5807)
		(size 0.7112)
		(drill 0.4064)
		(layers "F.Cu" "B.Cu")
		(net "5V_PRE_12")
	)
	(via
		(at 24.764746 -226.7077)
		(size 0.7112)
		(drill 0.4064)
		(layers "F.Cu" "B.Cu")
		(net "5V_PRE_12")
	)
	(segment
		(start 23.748746 -226.5807)
		(end 22.732746 -226.5807)
		(width 0.508)
		(layer "B.Cu")
		(net "5V_PRE_12")
	)
	(segment
		(start 224.414588 -63.390018)
		(end 224.411286 -63.386716)
		(width 0.09525)
		(layer "F.Cu")
		(net "SAS2X28_DRIVE_RX_N_B4")
	)
	(segment
		(start 225.399854 -63.390018)
		(end 224.414588 -63.390018)
		(width 0.09525)
		(layer "F.Cu")
		(net "SAS2X28_DRIVE_RX_N_B4")
	)
	(segment
		(start 223.939354 -63.607442)
		(end 218.85656 -63.607442)
		(width 0.09525)
		(layer "F.Cu")
		(net "SAS2X28_DRIVE_RX_N_B4")
	)
	(arc
		(start 224.17659 -63.509144)
		(mid 224.067745 -63.581872)
		(end 223.939354 -63.607442)
		(width 0.09525)
		(layer "F.Cu")
		(net "SAS2X28_DRIVE_RX_N_B4")
	)
	(arc
		(start 224.411286 -63.386716)
		(mid 224.317389 -63.405393)
		(end 224.237804 -63.458598)
		(width 0.09525)
		(layer "F.Cu")
		(net "SAS2X28_DRIVE_RX_N_B4")
	)
	(arc
		(start 218.85656 -63.607442)
		(mid 218.525005 -63.541492)
		(end 218.243912 -63.353696)
		(width 0.09525)
		(layer "F.Cu")
		(net "SAS2X28_DRIVE_RX_N_B4")
	)
	(arc
		(start 224.237804 -63.458598)
		(mid 224.205997 -63.482418)
		(end 224.17659 -63.509144)
		(width 0.09525)
		(layer "F.Cu")
		(net "SAS2X28_DRIVE_RX_N_B4")
	)
	(segment
		(start 221.750128 -57.272936)
		(end 221.76105 -57.254648)
		(width 0.09525)
		(layer "F.Cu")
		(net "SAS2X28_DRIVE_RX_N_A4")
	)
	(segment
		(start 221.804738 -57.167526)
		(end 221.82328 -57.122568)
		(width 0.09525)
		(layer "F.Cu")
		(net "SAS2X28_DRIVE_RX_N_A4")
	)
	(segment
		(start 218.243912 -57.130696)
		(end 218.477084 -57.130696)
		(width 0.09525)
		(layer "F.Cu")
		(net "SAS2X28_DRIVE_RX_N_A4")
	)
	(segment
		(start 219.151708 -57.410096)
		(end 221.495874 -57.410096)
		(width 0.09525)
		(layer "F.Cu")
		(net "SAS2X28_DRIVE_RX_N_A4")
	)
	(segment
		(start 221.880938 -57.036462)
		(end 221.8944 -57.023)
		(width 0.09525)
		(layer "F.Cu")
		(net "SAS2X28_DRIVE_RX_N_A4")
	)
	(segment
		(start 222.239586 -56.879998)
		(end 223.249998 -56.879998)
		(width 0.09525)
		(layer "F.Cu")
		(net "SAS2X28_DRIVE_RX_N_A4")
	)
	(arc
		(start 218.814396 -57.270396)
		(mid 218.969156 -57.373803)
		(end 219.151708 -57.410096)
		(width 0.09525)
		(layer "F.Cu")
		(net "SAS2X28_DRIVE_RX_N_A4")
	)
	(arc
		(start 221.82328 -57.122568)
		(mid 221.847857 -57.076664)
		(end 221.880938 -57.036462)
		(width 0.09525)
		(layer "F.Cu")
		(net "SAS2X28_DRIVE_RX_N_A4")
	)
	(arc
		(start 221.76105 -57.254648)
		(mid 221.784474 -57.211879)
		(end 221.804738 -57.167526)
		(width 0.09525)
		(layer "F.Cu")
		(net "SAS2X28_DRIVE_RX_N_A4")
	)
	(arc
		(start 221.495874 -57.410096)
		(mid 221.61203 -57.386991)
		(end 221.710504 -57.321196)
		(width 0.09525)
		(layer "F.Cu")
		(net "SAS2X28_DRIVE_RX_N_A4")
	)
	(arc
		(start 221.8944 -57.023)
		(mid 222.052773 -56.917179)
		(end 222.239586 -56.879998)
		(width 0.09525)
		(layer "F.Cu")
		(net "SAS2X28_DRIVE_RX_N_A4")
	)
	(arc
		(start 221.710504 -57.321196)
		(mid 221.732124 -57.298549)
		(end 221.750128 -57.272936)
		(width 0.09525)
		(layer "F.Cu")
		(net "SAS2X28_DRIVE_RX_N_A4")
	)
	(arc
		(start 218.477084 -57.130696)
		(mid 218.659629 -57.167006)
		(end 218.814396 -57.270396)
		(width 0.09525)
		(layer "F.Cu")
		(net "SAS2X28_DRIVE_RX_N_A4")
	)
	(segment
		(start 9.568942 -453.496426)
		(end 7.49808 -453.496426)
		(width 0.111252)
		(layer "F.Cu")
		(net "SAS_EXP_A_PWR8")
	)
	(segment
		(start 7.489952 -453.504554)
		(end 3.19024 -453.504554)
		(width 0.111252)
		(layer "F.Cu")
		(net "SAS_EXP_A_PWR8")
	)
	(segment
		(start 9.675876 -453.60336)
		(end 9.568942 -453.496426)
		(width 0.111252)
		(layer "F.Cu")
		(net "SAS_EXP_A_PWR8")
	)
	(segment
		(start 83.083146 -188.8617)
		(end 82.105246 -188.8617)
		(width 0.111252)
		(layer "F.Cu")
		(net "SAS_EXP_A_PWR8")
	)
	(segment
		(start 84.137246 -190.2587)
		(end 83.883246 -190.5127)
		(width 0.111252)
		(layer "F.Cu")
		(net "SAS_EXP_A_PWR8")
	)
	(segment
		(start 83.883246 -190.5127)
		(end 83.565746 -190.5127)
		(width 0.111252)
		(layer "F.Cu")
		(net "SAS_EXP_A_PWR8")
	)
	(segment
		(start 7.49808 -453.496426)
		(end 7.489952 -453.504554)
		(width 0.111252)
		(layer "F.Cu")
		(net "SAS_EXP_A_PWR8")
	)
	(segment
		(start 83.565746 -190.5127)
		(end 83.248246 -190.1952)
		(width 0.111252)
		(layer "F.Cu")
		(net "SAS_EXP_A_PWR8")
	)
	(segment
		(start 84.137246 -189.2427)
		(end 84.137246 -190.2587)
		(width 0.111252)
		(layer "F.Cu")
		(net "SAS_EXP_A_PWR8")
	)
	(segment
		(start 83.210146 -188.9887)
		(end 83.083146 -188.8617)
		(width 0.111252)
		(layer "F.Cu")
		(net "SAS_EXP_A_PWR8")
	)
	(segment
		(start 83.248246 -188.9887)
		(end 83.210146 -188.9887)
		(width 0.111252)
		(layer "F.Cu")
		(net "SAS_EXP_A_PWR8")
	)
	(segment
		(start 83.248246 -190.1952)
		(end 83.248246 -188.9887)
		(width 0.111252)
		(layer "F.Cu")
		(net "SAS_EXP_A_PWR8")
	)
	(via
		(at 83.883246 -190.5127)
		(size 0.7112)
		(drill 0.3556)
		(layers "F.Cu" "B.Cu")
		(net "SAS_EXP_A_PWR8")
	)
	(via
		(at 10.4648 -443.7507)
		(size 0.5588)
		(drill 0.3048)
		(layers "F.Cu" "B.Cu")
		(net "SAS_EXP_A_PWR8")
	)
	(via
		(at 9.675876 -453.60336)
		(size 0.5588)
		(drill 0.3048)
		(layers "F.Cu" "B.Cu")
		(net "SAS_EXP_A_PWR8")
	)
	(via
		(at 83.248246 -188.9887)
		(size 0.5588)
		(drill 0.3048)
		(layers "F.Cu" "B.Cu")
		(net "SAS_EXP_A_PWR8")
	)
	(segment
		(start 9.189212 -444.353188)
		(end 9.189212 -452.355712)
		(width 0.14605)
		(layer "In2.Cu")
		(net "SAS_EXP_A_PWR8")
	)
	(segment
		(start 10.4648 -443.7507)
		(end 9.7917 -443.7507)
		(width 0.14605)
		(layer "In2.Cu")
		(net "SAS_EXP_A_PWR8")
	)
	(segment
		(start 9.189212 -452.355712)
		(end 9.675876 -452.84263)
		(width 0.14605)
		(layer "In2.Cu")
		(net "SAS_EXP_A_PWR8")
	)
	(segment
		(start 9.675876 -452.84263)
		(end 9.675876 -453.60336)
		(width 0.14605)
		(layer "In2.Cu")
		(net "SAS_EXP_A_PWR8")
	)
	(segment
		(start 9.7917 -443.7507)
		(end 9.189212 -444.353188)
		(width 0.14605)
		(layer "In2.Cu")
		(net "SAS_EXP_A_PWR8")
	)
	(segment
		(start 17.786096 -449.126102)
		(end 76.275438 -449.126102)
		(width 0.14605)
		(layer "In5.Cu")
		(net "SAS_EXP_A_PWR8")
	)
	(segment
		(start 12.683744 -444.160148)
		(end 17.570196 -449.0466)
		(width 0.14605)
		(layer "In5.Cu")
		(net "SAS_EXP_A_PWR8")
	)
	(segment
		(start 90.973402 -196.713856)
		(end 83.248246 -188.9887)
		(width 0.14605)
		(layer "In5.Cu")
		(net "SAS_EXP_A_PWR8")
	)
	(segment
		(start 11.622786 -444.160148)
		(end 12.683744 -444.160148)
		(width 0.14605)
		(layer "In5.Cu")
		(net "SAS_EXP_A_PWR8")
	)
	(segment
		(start 17.706594 -449.0466)
		(end 17.786096 -449.126102)
		(width 0.14605)
		(layer "In5.Cu")
		(net "SAS_EXP_A_PWR8")
	)
	(segment
		(start 17.570196 -449.0466)
		(end 17.706594 -449.0466)
		(width 0.14605)
		(layer "In5.Cu")
		(net "SAS_EXP_A_PWR8")
	)
	(segment
		(start 90.174318 -435.384702)
		(end 90.973402 -434.585618)
		(width 0.14605)
		(layer "In5.Cu")
		(net "SAS_EXP_A_PWR8")
	)
	(segment
		(start 90.016838 -435.384702)
		(end 90.174318 -435.384702)
		(width 0.14605)
		(layer "In5.Cu")
		(net "SAS_EXP_A_PWR8")
	)
	(segment
		(start 90.973402 -434.585618)
		(end 90.973402 -196.713856)
		(width 0.14605)
		(layer "In5.Cu")
		(net "SAS_EXP_A_PWR8")
	)
	(segment
		(start 11.213338 -443.7507)
		(end 11.622786 -444.160148)
		(width 0.14605)
		(layer "In5.Cu")
		(net "SAS_EXP_A_PWR8")
	)
	(segment
		(start 76.275438 -449.126102)
		(end 90.016838 -435.384702)
		(width 0.14605)
		(layer "In5.Cu")
		(net "SAS_EXP_A_PWR8")
	)
	(segment
		(start 10.4648 -443.7507)
		(end 11.213338 -443.7507)
		(width 0.14605)
		(layer "In5.Cu")
		(net "SAS_EXP_A_PWR8")
	)
	(via
		(at 59.055 -211.963)
		(size 0.7112)
		(drill 0.3556)
		(layers "F.Cu" "B.Cu")
		(net "P12V_HDD12")
	)
	(via
		(at 39.623746 -218.1987)
		(size 0.7112)
		(drill 0.4064)
		(layers "F.Cu" "B.Cu")
		(net "P12V_HDD12")
	)
	(via
		(at 23.827232 -216.424002)
		(size 0.7112)
		(drill 0.4064)
		(layers "F.Cu" "B.Cu")
		(net "P12V_HDD12")
	)
	(via
		(at 23.876254 -217.65133)
		(size 0.7112)
		(drill 0.4064)
		(layers "F.Cu" "B.Cu")
		(net "P12V_HDD12")
	)
	(via
		(at 41.655746 -219.2147)
		(size 0.7112)
		(drill 0.4064)
		(layers "F.Cu" "B.Cu")
		(net "P12V_HDD12")
	)
	(via
		(at 40.639746 -219.2147)
		(size 0.7112)
		(drill 0.4064)
		(layers "F.Cu" "B.Cu")
		(net "P12V_HDD12")
	)
	(via
		(at 24.8412 -216.3572)
		(size 0.7112)
		(drill 0.4064)
		(layers "F.Cu" "B.Cu")
		(net "P12V_HDD12")
	)
	(via
		(at 22.86 -217.043)
		(size 0.7112)
		(drill 0.3556)
		(layers "F.Cu" "B.Cu")
		(net "P12V_HDD12")
	)
	(via
		(at 39.623746 -219.2147)
		(size 0.7112)
		(drill 0.4064)
		(layers "F.Cu" "B.Cu")
		(net "P12V_HDD12")
	)
	(via
		(at 24.892254 -217.6653)
		(size 0.7112)
		(drill 0.4064)
		(layers "F.Cu" "B.Cu")
		(net "P12V_HDD12")
	)
	(segment
		(start 23.82393 -216.4207)
		(end 23.4823 -216.4207)
		(width 0.508)
		(layer "B.Cu")
		(net "P12V_HDD12")
	)
	(segment
		(start 23.4823 -216.4207)
		(end 22.86 -217.043)
		(width 0.508)
		(layer "B.Cu")
		(net "P12V_HDD12")
	)
	(segment
		(start 23.827232 -216.424002)
		(end 23.82393 -216.4207)
		(width 0.508)
		(layer "B.Cu")
		(net "P12V_HDD12")
	)
	(via
		(at 25.755346 -328.3077)
		(size 0.5588)
		(drill 0.3048)
		(layers "F.Cu" "B.Cu")
		(net "5V_PRE_11")
	)
	(via
		(at 26.796746 -328.3077)
		(size 0.7112)
		(drill 0.3556)
		(layers "F.Cu" "B.Cu")
		(net "5V_PRE_11")
	)
	(segment
		(start 25.755346 -328.3077)
		(end 26.796746 -328.3077)
		(width 0.508)
		(layer "B.Cu")
		(net "5V_PRE_11")
	)
	(segment
		(start 27.50312 -345.889326)
		(end 27.596338 -345.796108)
		(width 0.09525)
		(layer "F.Cu")
		(net "SAS2X28_A_HDD11_RX_-")
	)
	(segment
		(start 27.324812 -345.935808)
		(end 27.390598 -345.935808)
		(width 0.09525)
		(layer "F.Cu")
		(net "SAS2X28_A_HDD11_RX_-")
	)
	(segment
		(start 27.93365 -345.656408)
		(end 28.273756 -345.656408)
		(width 0.09525)
		(layer "F.Cu")
		(net "SAS2X28_A_HDD11_RX_-")
	)
	(via
		(at 28.701746 -345.8337)
		(size 0.5588)
		(drill 0.3048)
		(layers "F.Cu" "B.Cu")
		(net "SAS2X28_A_HDD11_RX_-")
	)
	(arc
		(start 27.390598 -345.935808)
		(mid 27.4515 -345.923788)
		(end 27.50312 -345.889326)
		(width 0.09525)
		(layer "F.Cu")
		(net "SAS2X28_A_HDD11_RX_-")
	)
	(arc
		(start 27.596338 -345.796108)
		(mid 27.751098 -345.692701)
		(end 27.93365 -345.656408)
		(width 0.09525)
		(layer "F.Cu")
		(net "SAS2X28_A_HDD11_RX_-")
	)
	(arc
		(start 28.273756 -345.656408)
		(mid 28.505387 -345.702482)
		(end 28.701746 -345.8337)
		(width 0.09525)
		(layer "F.Cu")
		(net "SAS2X28_A_HDD11_RX_-")
	)
	(segment
		(start 4.800346 -346.498418)
		(end 2.811526 -346.498418)
		(width 0.09525)
		(layer "B.Cu")
		(net "SAS2X28_A_HDD11_RX_-")
	)
	(segment
		(start 23.785576 -346.161868)
		(end 23.784052 -346.160344)
		(width 0.09525)
		(layer "B.Cu")
		(net "SAS2X28_A_HDD11_RX_-")
	)
	(segment
		(start 23.784052 -346.160344)
		(end 5.621782 -346.160344)
		(width 0.09525)
		(layer "B.Cu")
		(net "SAS2X28_A_HDD11_RX_-")
	)
	(segment
		(start 4.80187 -346.499942)
		(end 4.800346 -346.498418)
		(width 0.09525)
		(layer "B.Cu")
		(net "SAS2X28_A_HDD11_RX_-")
	)
	(segment
		(start 28.272486 -345.6559)
		(end 25.703022 -345.6559)
		(width 0.09525)
		(layer "B.Cu")
		(net "SAS2X28_A_HDD11_RX_-")
	)
	(segment
		(start 24.481536 -346.161868)
		(end 23.785576 -346.161868)
		(width 0.09525)
		(layer "B.Cu")
		(net "SAS2X28_A_HDD11_RX_-")
	)
	(arc
		(start 25.703022 -345.6559)
		(mid 25.469738 -345.702303)
		(end 25.271984 -345.834462)
		(width 0.09525)
		(layer "B.Cu")
		(net "SAS2X28_A_HDD11_RX_-")
	)
	(arc
		(start 5.307838 -346.290392)
		(mid 5.075698 -346.445503)
		(end 4.80187 -346.499942)
		(width 0.09525)
		(layer "B.Cu")
		(net "SAS2X28_A_HDD11_RX_-")
	)
	(arc
		(start 25.271984 -345.834462)
		(mid 24.909323 -346.076784)
		(end 24.481536 -346.161868)
		(width 0.09525)
		(layer "B.Cu")
		(net "SAS2X28_A_HDD11_RX_-")
	)
	(arc
		(start 5.621782 -346.160344)
		(mid 5.451874 -346.194141)
		(end 5.307838 -346.290392)
		(width 0.09525)
		(layer "B.Cu")
		(net "SAS2X28_A_HDD11_RX_-")
	)
	(arc
		(start 28.701746 -345.8337)
		(mid 28.5048 -345.702105)
		(end 28.272486 -345.6559)
		(width 0.09525)
		(layer "B.Cu")
		(net "SAS2X28_A_HDD11_RX_-")
	)
	(segment
		(start 224.693988 -166.390066)
		(end 224.690686 -166.386764)
		(width 0.09525)
		(layer "F.Cu")
		(net "SAS2X28_DRIVE_RX_N_B3")
	)
	(segment
		(start 224.087182 -166.6367)
		(end 218.922346 -166.6367)
		(width 0.09525)
		(layer "F.Cu")
		(net "SAS2X28_DRIVE_RX_N_B3")
	)
	(segment
		(start 218.365324 -166.405814)
		(end 218.299284 -166.340028)
		(width 0.09525)
		(layer "F.Cu")
		(net "SAS2X28_DRIVE_RX_N_B3")
	)
	(segment
		(start 225.399854 -166.390066)
		(end 224.693988 -166.390066)
		(width 0.09525)
		(layer "F.Cu")
		(net "SAS2X28_DRIVE_RX_N_B3")
	)
	(arc
		(start 224.690686 -166.386764)
		(mid 224.496866 -166.425317)
		(end 224.332546 -166.5351)
		(width 0.09525)
		(layer "F.Cu")
		(net "SAS2X28_DRIVE_RX_N_B3")
	)
	(arc
		(start 218.922346 -166.6367)
		(mid 218.62088 -166.576641)
		(end 218.365324 -166.405814)
		(width 0.09525)
		(layer "F.Cu")
		(net "SAS2X28_DRIVE_RX_N_B3")
	)
	(arc
		(start 224.332546 -166.5351)
		(mid 224.219972 -166.61032)
		(end 224.087182 -166.6367)
		(width 0.09525)
		(layer "F.Cu")
		(net "SAS2X28_DRIVE_RX_N_B3")
	)
	(segment
		(start 3.193542 -452.501254)
		(end 3.19024 -452.504556)
		(width 0.111252)
		(layer "F.Cu")
		(net "SAS_EXP_A_PWR9")
	)
	(segment
		(start 9.449054 -452.501254)
		(end 3.193542 -452.501254)
		(width 0.111252)
		(layer "F.Cu")
		(net "SAS_EXP_A_PWR9")
	)
	(segment
		(start 82.717386 -85.499956)
		(end 81.723992 -85.499956)
		(width 0.111252)
		(layer "F.Cu")
		(net "SAS_EXP_A_PWR9")
	)
	(segment
		(start 83.755992 -85.626956)
		(end 83.669632 -85.713316)
		(width 0.111252)
		(layer "F.Cu")
		(net "SAS_EXP_A_PWR9")
	)
	(segment
		(start 82.930746 -85.713316)
		(end 82.717386 -85.499956)
		(width 0.111252)
		(layer "F.Cu")
		(net "SAS_EXP_A_PWR9")
	)
	(segment
		(start 11.734546 -452.8947)
		(end 9.8425 -452.8947)
		(width 0.111252)
		(layer "F.Cu")
		(net "SAS_EXP_A_PWR9")
	)
	(segment
		(start 9.8425 -452.8947)
		(end 9.449054 -452.501254)
		(width 0.111252)
		(layer "F.Cu")
		(net "SAS_EXP_A_PWR9")
	)
	(segment
		(start 83.669632 -85.713316)
		(end 82.930746 -85.713316)
		(width 0.111252)
		(layer "F.Cu")
		(net "SAS_EXP_A_PWR9")
	)
	(via
		(at 11.734546 -452.8947)
		(size 0.5588)
		(drill 0.3048)
		(layers "F.Cu" "B.Cu")
		(net "SAS_EXP_A_PWR9")
	)
	(via
		(at 15.849346 -451.1167)
		(size 0.7112)
		(drill 0.3556)
		(layers "F.Cu" "B.Cu")
		(net "SAS_EXP_A_PWR9")
	)
	(via
		(at 82.930746 -85.713316)
		(size 0.5588)
		(drill 0.3048)
		(layers "F.Cu" "B.Cu")
		(net "SAS_EXP_A_PWR9")
	)
	(via
		(at 18.8976 -451.6374)
		(size 0.5588)
		(drill 0.3048)
		(layers "F.Cu" "B.Cu")
		(net "SAS_EXP_A_PWR9")
	)
	(segment
		(start 11.734546 -452.8947)
		(end 12.267946 -452.8947)
		(width 0.111252)
		(layer "B.Cu")
		(net "SAS_EXP_A_PWR9")
	)
	(segment
		(start 14.045946 -451.1167)
		(end 15.849346 -451.1167)
		(width 0.111252)
		(layer "B.Cu")
		(net "SAS_EXP_A_PWR9")
	)
	(segment
		(start 12.267946 -452.8947)
		(end 14.045946 -451.1167)
		(width 0.111252)
		(layer "B.Cu")
		(net "SAS_EXP_A_PWR9")
	)
	(segment
		(start 18.8976 -451.6374)
		(end 18.3769 -451.1167)
		(width 0.111252)
		(layer "B.Cu")
		(net "SAS_EXP_A_PWR9")
	)
	(segment
		(start 18.3769 -451.1167)
		(end 15.849346 -451.1167)
		(width 0.111252)
		(layer "B.Cu")
		(net "SAS_EXP_A_PWR9")
	)
	(segment
		(start 99.764596 -104.053132)
		(end 99.764596 -159.97047)
		(width 0.14605)
		(layer "In5.Cu")
		(net "SAS_EXP_A_PWR9")
	)
	(segment
		(start 82.930746 -85.713316)
		(end 99.669346 -102.451916)
		(width 0.14605)
		(layer "In5.Cu")
		(net "SAS_EXP_A_PWR9")
	)
	(segment
		(start 87.660226 -451.6374)
		(end 18.8976 -451.6374)
		(width 0.14605)
		(layer "In5.Cu")
		(net "SAS_EXP_A_PWR9")
	)
	(segment
		(start 99.761294 -160.371028)
		(end 99.793298 -160.403032)
		(width 0.14605)
		(layer "In5.Cu")
		(net "SAS_EXP_A_PWR9")
	)
	(segment
		(start 99.793298 -160.403032)
		(end 99.793298 -439.504328)
		(width 0.14605)
		(layer "In5.Cu")
		(net "SAS_EXP_A_PWR9")
	)
	(segment
		(start 99.761294 -159.973772)
		(end 99.761294 -160.371028)
		(width 0.14605)
		(layer "In5.Cu")
		(net "SAS_EXP_A_PWR9")
	)
	(segment
		(start 99.669346 -103.957882)
		(end 99.764596 -104.053132)
		(width 0.14605)
		(layer "In5.Cu")
		(net "SAS_EXP_A_PWR9")
	)
	(segment
		(start 99.669346 -102.451916)
		(end 99.669346 -103.957882)
		(width 0.14605)
		(layer "In5.Cu")
		(net "SAS_EXP_A_PWR9")
	)
	(segment
		(start 99.793298 -439.504328)
		(end 87.660226 -451.6374)
		(width 0.14605)
		(layer "In5.Cu")
		(net "SAS_EXP_A_PWR9")
	)
	(segment
		(start 99.764596 -159.97047)
		(end 99.761294 -159.973772)
		(width 0.14605)
		(layer "In5.Cu")
		(net "SAS_EXP_A_PWR9")
	)
	(via
		(at 39.496746 -226.3267)
		(size 0.7112)
		(drill 0.4064)
		(layers "F.Cu" "B.Cu")
		(net "P5V_HDD12")
	)
	(via
		(at 51.562 -233.172)
		(size 0.7112)
		(drill 0.3556)
		(layers "F.Cu" "B.Cu")
		(net "P5V_HDD12")
	)
	(via
		(at 39.496746 -227.5967)
		(size 0.7112)
		(drill 0.4064)
		(layers "F.Cu" "B.Cu")
		(net "P5V_HDD12")
	)
	(via
		(at 41.528746 -227.7237)
		(size 0.7112)
		(drill 0.4064)
		(layers "F.Cu" "B.Cu")
		(net "P5V_HDD12")
	)
	(via
		(at 24.8666 -224.1296)
		(size 0.7112)
		(drill 0.4064)
		(layers "F.Cu" "B.Cu")
		(net "P5V_HDD12")
	)
	(via
		(at 23.79726 -225.333306)
		(size 0.7112)
		(drill 0.4064)
		(layers "F.Cu" "B.Cu")
		(net "P5V_HDD12")
	)
	(via
		(at 22.605746 -224.1677)
		(size 0.7112)
		(drill 0.3556)
		(layers "F.Cu" "B.Cu")
		(net "P5V_HDD12")
	)
	(via
		(at 23.8506 -224.1296)
		(size 0.7112)
		(drill 0.4064)
		(layers "F.Cu" "B.Cu")
		(net "P5V_HDD12")
	)
	(via
		(at 24.8158 -225.3996)
		(size 0.7112)
		(drill 0.4064)
		(layers "F.Cu" "B.Cu")
		(net "P5V_HDD12")
	)
	(via
		(at 40.502586 -227.740464)
		(size 0.7112)
		(drill 0.4064)
		(layers "F.Cu" "B.Cu")
		(net "P5V_HDD12")
	)
	(segment
		(start 23.8125 -224.1677)
		(end 22.605746 -224.1677)
		(width 0.508)
		(layer "B.Cu")
		(net "P5V_HDD12")
	)
	(segment
		(start 23.8506 -224.1296)
		(end 23.8125 -224.1677)
		(width 0.508)
		(layer "B.Cu")
		(net "P5V_HDD12")
	)
	(via
		(at 23.875746 -432.5747)
		(size 0.5588)
		(drill 0.3048)
		(layers "F.Cu" "B.Cu")
		(net "5V_PRE_10")
	)
	(via
		(at 22.859746 -432.5747)
		(size 0.7112)
		(drill 0.3556)
		(layers "F.Cu" "B.Cu")
		(net "5V_PRE_10")
	)
	(segment
		(start 23.875746 -432.5747)
		(end 22.859746 -432.5747)
		(width 0.508)
		(layer "B.Cu")
		(net "5V_PRE_10")
	)
	(segment
		(start 27.340814 -345.107768)
		(end 27.441906 -345.20886)
		(width 0.09525)
		(layer "F.Cu")
		(net "SAS2X28_A_HDD11_RX_+")
	)
	(segment
		(start 27.324812 -345.046808)
		(end 27.324812 -345.06916)
		(width 0.09525)
		(layer "F.Cu")
		(net "SAS2X28_A_HDD11_RX_+")
	)
	(segment
		(start 28.55976 -345.112086)
		(end 28.55976 -344.981784)
		(width 0.09525)
		(layer "F.Cu")
		(net "SAS2X28_A_HDD11_RX_+")
	)
	(segment
		(start 28.5242 -345.147646)
		(end 28.55976 -345.112086)
		(width 0.09525)
		(layer "F.Cu")
		(net "SAS2X28_A_HDD11_RX_+")
	)
	(segment
		(start 27.725116 -345.326208)
		(end 28.093162 -345.326208)
		(width 0.09525)
		(layer "F.Cu")
		(net "SAS2X28_A_HDD11_RX_+")
	)
	(via
		(at 28.55976 -344.981784)
		(size 0.5588)
		(drill 0.3048)
		(layers "F.Cu" "B.Cu")
		(net "SAS2X28_A_HDD11_RX_+")
	)
	(arc
		(start 27.441906 -345.20886)
		(mid 27.57183 -345.295735)
		(end 27.725116 -345.326208)
		(width 0.09525)
		(layer "F.Cu")
		(net "SAS2X28_A_HDD11_RX_+")
	)
	(arc
		(start 27.324812 -345.06916)
		(mid 27.328984 -345.090044)
		(end 27.340814 -345.107768)
		(width 0.09525)
		(layer "F.Cu")
		(net "SAS2X28_A_HDD11_RX_+")
	)
	(arc
		(start 28.093162 -345.326208)
		(mid 28.326446 -345.279805)
		(end 28.5242 -345.147646)
		(width 0.09525)
		(layer "F.Cu")
		(net "SAS2X28_A_HDD11_RX_+")
	)
	(segment
		(start 28.521914 -344.997532)
		(end 28.372308 -345.147138)
		(width 0.09525)
		(layer "B.Cu")
		(net "SAS2X28_A_HDD11_RX_+")
	)
	(segment
		(start 27.94127 -345.3257)
		(end 25.703022 -345.3257)
		(width 0.09525)
		(layer "B.Cu")
		(net "SAS2X28_A_HDD11_RX_+")
	)
	(segment
		(start 4.83108 -345.49842)
		(end 2.811526 -345.49842)
		(width 0.09525)
		(layer "B.Cu")
		(net "SAS2X28_A_HDD11_RX_+")
	)
	(segment
		(start 24.57323 -345.830144)
		(end 5.62991 -345.830144)
		(width 0.09525)
		(layer "B.Cu")
		(net "SAS2X28_A_HDD11_RX_+")
	)
	(segment
		(start 25.038304 -345.600782)
		(end 24.975566 -345.66352)
		(width 0.09525)
		(layer "B.Cu")
		(net "SAS2X28_A_HDD11_RX_+")
	)
	(segment
		(start 4.832604 -345.499944)
		(end 4.83108 -345.49842)
		(width 0.09525)
		(layer "B.Cu")
		(net "SAS2X28_A_HDD11_RX_+")
	)
	(arc
		(start 5.62991 -345.830144)
		(mid 5.49548 -345.803404)
		(end 5.381498 -345.727274)
		(width 0.09525)
		(layer "B.Cu")
		(net "SAS2X28_A_HDD11_RX_+")
	)
	(arc
		(start 28.55976 -344.981784)
		(mid 28.539265 -344.985879)
		(end 28.521914 -344.997532)
		(width 0.09525)
		(layer "B.Cu")
		(net "SAS2X28_A_HDD11_RX_+")
	)
	(arc
		(start 5.381498 -345.727274)
		(mid 5.129663 -345.559003)
		(end 4.832604 -345.499944)
		(width 0.09525)
		(layer "B.Cu")
		(net "SAS2X28_A_HDD11_RX_+")
	)
	(arc
		(start 25.703022 -345.3257)
		(mid 25.343322 -345.397155)
		(end 25.038304 -345.600782)
		(width 0.09525)
		(layer "B.Cu")
		(net "SAS2X28_A_HDD11_RX_+")
	)
	(arc
		(start 24.975566 -345.66352)
		(mid 24.790973 -345.786861)
		(end 24.57323 -345.830144)
		(width 0.09525)
		(layer "B.Cu")
		(net "SAS2X28_A_HDD11_RX_+")
	)
	(arc
		(start 28.372308 -345.147138)
		(mid 28.174546 -345.279278)
		(end 27.94127 -345.3257)
		(width 0.09525)
		(layer "B.Cu")
		(net "SAS2X28_A_HDD11_RX_+")
	)
	(segment
		(start 223.249998 -159.880046)
		(end 221.887796 -159.880046)
		(width 0.09525)
		(layer "F.Cu")
		(net "SAS2X28_DRIVE_RX_N_A3")
	)
	(segment
		(start 221.474792 -160.346644)
		(end 218.820746 -160.346644)
		(width 0.09525)
		(layer "F.Cu")
		(net "SAS2X28_DRIVE_RX_N_A3")
	)
	(segment
		(start 221.699328 -160.100518)
		(end 221.699328 -160.122108)
		(width 0.09525)
		(layer "F.Cu")
		(net "SAS2X28_DRIVE_RX_N_A3")
	)
	(segment
		(start 221.854522 -159.88665)
		(end 221.837504 -159.893762)
		(width 0.09525)
		(layer "F.Cu")
		(net "SAS2X28_DRIVE_RX_N_A3")
	)
	(arc
		(start 221.633542 -160.280858)
		(mid 221.560707 -160.329525)
		(end 221.474792 -160.346644)
		(width 0.09525)
		(layer "F.Cu")
		(net "SAS2X28_DRIVE_RX_N_A3")
	)
	(arc
		(start 221.887796 -159.880046)
		(mid 221.870826 -159.881679)
		(end 221.854522 -159.88665)
		(width 0.09525)
		(layer "F.Cu")
		(net "SAS2X28_DRIVE_RX_N_A3")
	)
	(arc
		(start 221.837504 -159.893762)
		(mid 221.737051 -159.976179)
		(end 221.699328 -160.100518)
		(width 0.09525)
		(layer "F.Cu")
		(net "SAS2X28_DRIVE_RX_N_A3")
	)
	(arc
		(start 221.699328 -160.122108)
		(mid 221.682236 -160.208034)
		(end 221.633542 -160.280858)
		(width 0.09525)
		(layer "F.Cu")
		(net "SAS2X28_DRIVE_RX_N_A3")
	)
	(arc
		(start 218.820746 -160.346644)
		(mid 218.535861 -160.286695)
		(end 218.299284 -160.117028)
		(width 0.09525)
		(layer "F.Cu")
		(net "SAS2X28_DRIVE_RX_N_A3")
	)
	(segment
		(start 224.217738 -269.468092)
		(end 224.141538 -269.544292)
		(width 0.09525)
		(layer "F.Cu")
		(net "SAS2X28_DRIVE_RX_N_B2")
	)
	(segment
		(start 225.399854 -269.390114)
		(end 224.417382 -269.390114)
		(width 0.09525)
		(layer "F.Cu")
		(net "SAS2X28_DRIVE_RX_N_B2")
	)
	(segment
		(start 224.417382 -269.390114)
		(end 224.41408 -269.386812)
		(width 0.09525)
		(layer "F.Cu")
		(net "SAS2X28_DRIVE_RX_N_B2")
	)
	(segment
		(start 223.954594 -269.621762)
		(end 218.581732 -269.621762)
		(width 0.09525)
		(layer "F.Cu")
		(net "SAS2X28_DRIVE_RX_N_B2")
	)
	(arc
		(start 224.141538 -269.544292)
		(mid 224.055767 -269.601602)
		(end 223.954594 -269.621762)
		(width 0.09525)
		(layer "F.Cu")
		(net "SAS2X28_DRIVE_RX_N_B2")
	)
	(arc
		(start 224.41408 -269.386812)
		(mid 224.307839 -269.407945)
		(end 224.217738 -269.468092)
		(width 0.09525)
		(layer "F.Cu")
		(net "SAS2X28_DRIVE_RX_N_B2")
	)
	(arc
		(start 218.581732 -269.621762)
		(mid 218.378969 -269.58143)
		(end 218.207082 -269.466568)
		(width 0.09525)
		(layer "F.Cu")
		(net "SAS2X28_DRIVE_RX_N_B2")
	)
	(segment
		(start 8.200898 -455.488548)
		(end 9.067546 -454.6219)
		(width 0.111252)
		(layer "F.Cu")
		(net "SAS_EXP_A_PWR4")
	)
	(segment
		(start 196.404738 -82.9437)
		(end 196.309742 -83.038696)
		(width 0.111252)
		(layer "F.Cu")
		(net "SAS_EXP_A_PWR4")
	)
	(segment
		(start 196.182742 -82.911696)
		(end 195.002912 -82.911696)
		(width 0.111252)
		(layer "F.Cu")
		(net "SAS_EXP_A_PWR4")
	)
	(segment
		(start 9.067546 -454.6219)
		(end 9.575546 -454.6219)
		(width 0.111252)
		(layer "F.Cu")
		(net "SAS_EXP_A_PWR4")
	)
	(segment
		(start 7.26948 -455.501248)
		(end 7.28218 -455.488548)
		(width 0.111252)
		(layer "F.Cu")
		(net "SAS_EXP_A_PWR4")
	)
	(segment
		(start 3.193542 -455.501248)
		(end 7.26948 -455.501248)
		(width 0.111252)
		(layer "F.Cu")
		(net "SAS_EXP_A_PWR4")
	)
	(segment
		(start 197.167246 -82.9437)
		(end 196.404738 -82.9437)
		(width 0.111252)
		(layer "F.Cu")
		(net "SAS_EXP_A_PWR4")
	)
	(segment
		(start 7.28218 -455.488548)
		(end 8.200898 -455.488548)
		(width 0.111252)
		(layer "F.Cu")
		(net "SAS_EXP_A_PWR4")
	)
	(segment
		(start 196.309742 -83.038696)
		(end 196.182742 -82.911696)
		(width 0.111252)
		(layer "F.Cu")
		(net "SAS_EXP_A_PWR4")
	)
	(segment
		(start 3.19024 -455.50455)
		(end 3.193542 -455.501248)
		(width 0.111252)
		(layer "F.Cu")
		(net "SAS_EXP_A_PWR4")
	)
	(via
		(at 196.309742 -83.978496)
		(size 0.7112)
		(drill 0.3556)
		(layers "F.Cu" "B.Cu")
		(net "SAS_EXP_A_PWR4")
	)
	(via
		(at 9.575546 -454.6219)
		(size 0.5588)
		(drill 0.3048)
		(layers "F.Cu" "B.Cu")
		(net "SAS_EXP_A_PWR4")
	)
	(via
		(at 196.309742 -83.038696)
		(size 0.5588)
		(drill 0.3048)
		(layers "F.Cu" "B.Cu")
		(net "SAS_EXP_A_PWR4")
	)
	(segment
		(start 196.309742 -83.038696)
		(end 196.309742 -83.978496)
		(width 0.111252)
		(layer "B.Cu")
		(net "SAS_EXP_A_PWR4")
	)
	(segment
		(start 230.811578 -139.39774)
		(end 195.20281 -103.788972)
		(width 0.14605)
		(layer "In5.Cu")
		(net "SAS_EXP_A_PWR4")
	)
	(segment
		(start 24.693118 -467.655148)
		(end 25.090374 -467.655148)
		(width 0.14605)
		(layer "In5.Cu")
		(net "SAS_EXP_A_PWR4")
	)
	(segment
		(start 195.20281 -85.785452)
		(end 196.309742 -84.67852)
		(width 0.14605)
		(layer "In5.Cu")
		(net "SAS_EXP_A_PWR4")
	)
	(segment
		(start 25.090374 -467.655148)
		(end 25.597866 -468.16264)
		(width 0.14605)
		(layer "In5.Cu")
		(net "SAS_EXP_A_PWR4")
	)
	(segment
		(start 140.200126 -468.16264)
		(end 230.811578 -377.551188)
		(width 0.14605)
		(layer "In5.Cu")
		(net "SAS_EXP_A_PWR4")
	)
	(segment
		(start 14.908276 -465.608162)
		(end 17.615916 -468.315802)
		(width 0.14605)
		(layer "In5.Cu")
		(net "SAS_EXP_A_PWR4")
	)
	(segment
		(start 11.315954 -459.210156)
		(end 11.315954 -462.561178)
		(width 0.14605)
		(layer "In5.Cu")
		(net "SAS_EXP_A_PWR4")
	)
	(segment
		(start 196.309742 -84.67852)
		(end 196.309742 -83.038696)
		(width 0.14605)
		(layer "In5.Cu")
		(net "SAS_EXP_A_PWR4")
	)
	(segment
		(start 14.362938 -465.608162)
		(end 14.908276 -465.608162)
		(width 0.14605)
		(layer "In5.Cu")
		(net "SAS_EXP_A_PWR4")
	)
	(segment
		(start 230.811578 -377.551188)
		(end 230.811578 -139.39774)
		(width 0.14605)
		(layer "In5.Cu")
		(net "SAS_EXP_A_PWR4")
	)
	(segment
		(start 9.39546 -457.289662)
		(end 11.315954 -459.210156)
		(width 0.14605)
		(layer "In5.Cu")
		(net "SAS_EXP_A_PWR4")
	)
	(segment
		(start 9.575546 -454.6219)
		(end 9.064244 -455.133202)
		(width 0.14605)
		(layer "In5.Cu")
		(net "SAS_EXP_A_PWR4")
	)
	(segment
		(start 25.597866 -468.16264)
		(end 140.200126 -468.16264)
		(width 0.14605)
		(layer "In5.Cu")
		(net "SAS_EXP_A_PWR4")
	)
	(segment
		(start 24.032464 -468.315802)
		(end 24.693118 -467.655148)
		(width 0.14605)
		(layer "In5.Cu")
		(net "SAS_EXP_A_PWR4")
	)
	(segment
		(start 9.064244 -455.133202)
		(end 9.064244 -456.071224)
		(width 0.14605)
		(layer "In5.Cu")
		(net "SAS_EXP_A_PWR4")
	)
	(segment
		(start 9.064244 -456.071224)
		(end 9.39546 -456.40244)
		(width 0.14605)
		(layer "In5.Cu")
		(net "SAS_EXP_A_PWR4")
	)
	(segment
		(start 9.39546 -456.40244)
		(end 9.39546 -457.289662)
		(width 0.14605)
		(layer "In5.Cu")
		(net "SAS_EXP_A_PWR4")
	)
	(segment
		(start 195.20281 -103.788972)
		(end 195.20281 -85.785452)
		(width 0.14605)
		(layer "In5.Cu")
		(net "SAS_EXP_A_PWR4")
	)
	(segment
		(start 11.315954 -462.561178)
		(end 14.362938 -465.608162)
		(width 0.14605)
		(layer "In5.Cu")
		(net "SAS_EXP_A_PWR4")
	)
	(segment
		(start 17.615916 -468.315802)
		(end 24.032464 -468.315802)
		(width 0.14605)
		(layer "In5.Cu")
		(net "SAS_EXP_A_PWR4")
	)
	(via
		(at 53.974746 -75.1967)
		(size 0.7112)
		(drill 0.3556)
		(layers "F.Cu" "B.Cu")
		(net "5V_PRE_9")
	)
	(segment
		(start 221.825058 -263.060942)
		(end 221.638876 -263.247124)
		(width 0.09525)
		(layer "F.Cu")
		(net "SAS2X28_DRIVE_RX_N_A2")
	)
	(segment
		(start 223.249998 -262.880094)
		(end 223.244918 -262.875014)
		(width 0.09525)
		(layer "F.Cu")
		(net "SAS2X28_DRIVE_RX_N_A2")
	)
	(segment
		(start 223.244918 -262.875014)
		(end 222.27413 -262.875014)
		(width 0.09525)
		(layer "F.Cu")
		(net "SAS2X28_DRIVE_RX_N_A2")
	)
	(segment
		(start 218.468956 -263.116568)
		(end 218.207082 -263.116568)
		(width 0.09525)
		(layer "F.Cu")
		(net "SAS2X28_DRIVE_RX_N_A2")
	)
	(segment
		(start 221.27972 -263.395968)
		(end 219.14358 -263.395968)
		(width 0.09525)
		(layer "F.Cu")
		(net "SAS2X28_DRIVE_RX_N_A2")
	)
	(arc
		(start 222.27413 -262.875014)
		(mid 222.031112 -262.923335)
		(end 221.825058 -263.060942)
		(width 0.09525)
		(layer "F.Cu")
		(net "SAS2X28_DRIVE_RX_N_A2")
	)
	(arc
		(start 219.14358 -263.395968)
		(mid 218.961035 -263.359658)
		(end 218.806268 -263.256268)
		(width 0.09525)
		(layer "F.Cu")
		(net "SAS2X28_DRIVE_RX_N_A2")
	)
	(arc
		(start 221.638876 -263.247124)
		(mid 221.474108 -263.357282)
		(end 221.27972 -263.395968)
		(width 0.09525)
		(layer "F.Cu")
		(net "SAS2X28_DRIVE_RX_N_A2")
	)
	(arc
		(start 218.806268 -263.256268)
		(mid 218.651508 -263.152861)
		(end 218.468956 -263.116568)
		(width 0.09525)
		(layer "F.Cu")
		(net "SAS2X28_DRIVE_RX_N_A2")
	)
	(segment
		(start 218.607894 -372.33352)
		(end 218.586558 -372.312184)
		(width 0.09525)
		(layer "F.Cu")
		(net "SAS2X28_DRIVE_RX_N_B1")
	)
	(segment
		(start 224.414842 -372.390162)
		(end 224.41154 -372.38686)
		(width 0.09525)
		(layer "F.Cu")
		(net "SAS2X28_DRIVE_RX_N_B1")
	)
	(segment
		(start 223.844866 -372.621556)
		(end 219.303346 -372.621556)
		(width 0.09525)
		(layer "F.Cu")
		(net "SAS2X28_DRIVE_RX_N_B1")
	)
	(segment
		(start 225.399854 -372.390162)
		(end 224.414842 -372.390162)
		(width 0.09525)
		(layer "F.Cu")
		(net "SAS2X28_DRIVE_RX_N_B1")
	)
	(arc
		(start 219.303346 -372.621556)
		(mid 218.926981 -372.546692)
		(end 218.607894 -372.33352)
		(width 0.09525)
		(layer "F.Cu")
		(net "SAS2X28_DRIVE_RX_N_B1")
	)
	(arc
		(start 224.219008 -372.466616)
		(mid 224.04735 -372.581314)
		(end 223.844866 -372.621556)
		(width 0.09525)
		(layer "F.Cu")
		(net "SAS2X28_DRIVE_RX_N_B1")
	)
	(arc
		(start 224.41154 -372.38686)
		(mid 224.30734 -372.407587)
		(end 224.219008 -372.466616)
		(width 0.09525)
		(layer "F.Cu")
		(net "SAS2X28_DRIVE_RX_N_B1")
	)
	(via
		(at 53.974746 -178.1937)
		(size 0.7112)
		(drill 0.3556)
		(layers "F.Cu" "B.Cu")
		(net "5V_PRE_8")
	)
	(segment
		(start 223.968564 -475.621604)
		(end 219.95765 -475.621604)
		(width 0.09525)
		(layer "F.Cu")
		(net "SAS2X28_DRIVE_RX_N_B0")
	)
	(segment
		(start 225.399854 -475.39021)
		(end 225.396552 -475.386908)
		(width 0.09525)
		(layer "F.Cu")
		(net "SAS2X28_DRIVE_RX_N_B0")
	)
	(segment
		(start 225.396552 -475.386908)
		(end 224.427288 -475.386908)
		(width 0.09525)
		(layer "F.Cu")
		(net "SAS2X28_DRIVE_RX_N_B0")
	)
	(segment
		(start 224.207832 -475.47784)
		(end 224.131632 -475.55404)
		(width 0.09525)
		(layer "F.Cu")
		(net "SAS2X28_DRIVE_RX_N_B0")
	)
	(arc
		(start 224.427288 -475.386908)
		(mid 224.308508 -475.410535)
		(end 224.207832 -475.47784)
		(width 0.09525)
		(layer "F.Cu")
		(net "SAS2X28_DRIVE_RX_N_B0")
	)
	(arc
		(start 224.131632 -475.55404)
		(mid 224.056816 -475.604031)
		(end 223.968564 -475.621604)
		(width 0.09525)
		(layer "F.Cu")
		(net "SAS2X28_DRIVE_RX_N_B0")
	)
	(arc
		(start 219.95765 -475.621604)
		(mid 219.48875 -475.528334)
		(end 219.091256 -475.262702)
		(width 0.09525)
		(layer "F.Cu")
		(net "SAS2X28_DRIVE_RX_N_B0")
	)
	(segment
		(start 221.741746 -366.065816)
		(end 221.741746 -366.19434)
		(width 0.09525)
		(layer "F.Cu")
		(net "SAS2X28_DRIVE_RX_N_A1")
	)
	(segment
		(start 223.249998 -365.880142)
		(end 221.92742 -365.880142)
		(width 0.09525)
		(layer "F.Cu")
		(net "SAS2X28_DRIVE_RX_N_A1")
	)
	(segment
		(start 221.589346 -366.34674)
		(end 219.455746 -366.34674)
		(width 0.09525)
		(layer "F.Cu")
		(net "SAS2X28_DRIVE_RX_N_A1")
	)
	(segment
		(start 218.628468 -366.004094)
		(end 218.586558 -365.962184)
		(width 0.09525)
		(layer "F.Cu")
		(net "SAS2X28_DRIVE_RX_N_A1")
	)
	(arc
		(start 221.92742 -365.880142)
		(mid 221.856351 -365.894261)
		(end 221.796102 -365.934498)
		(width 0.09525)
		(layer "F.Cu")
		(net "SAS2X28_DRIVE_RX_N_A1")
	)
	(arc
		(start 221.796102 -365.934498)
		(mid 221.755898 -365.994761)
		(end 221.741746 -366.065816)
		(width 0.09525)
		(layer "F.Cu")
		(net "SAS2X28_DRIVE_RX_N_A1")
	)
	(arc
		(start 219.455746 -366.34674)
		(mid 219.008035 -366.257685)
		(end 218.628468 -366.004094)
		(width 0.09525)
		(layer "F.Cu")
		(net "SAS2X28_DRIVE_RX_N_A1")
	)
	(arc
		(start 221.741746 -366.19434)
		(mid 221.716469 -366.277813)
		(end 221.649544 -366.333786)
		(width 0.09525)
		(layer "F.Cu")
		(net "SAS2X28_DRIVE_RX_N_A1")
	)
	(arc
		(start 221.649036 -366.334294)
		(mid 221.619817 -366.343508)
		(end 221.589346 -366.34674)
		(width 0.09525)
		(layer "F.Cu")
		(net "SAS2X28_DRIVE_RX_N_A1")
	)
	(arc
		(start 221.649544 -366.333786)
		(mid 221.64929 -366.33404)
		(end 221.649036 -366.334294)
		(width 0.09525)
		(layer "F.Cu")
		(net "SAS2X28_DRIVE_RX_N_A1")
	)
	(segment
		(start 3.193542 -451.501256)
		(end 3.19024 -451.504558)
		(width 0.111252)
		(layer "F.Cu")
		(net "SAS_EXP_A_PWR14")
	)
	(segment
		(start 96.202246 -13.4747)
		(end 96.329246 -13.6017)
		(width 0.111252)
		(layer "F.Cu")
		(net "SAS_EXP_A_PWR14")
	)
	(segment
		(start 97.027746 -13.6017)
		(end 98.488246 -13.6017)
		(width 0.111252)
		(layer "F.Cu")
		(net "SAS_EXP_A_PWR14")
	)
	(segment
		(start 11.937746 -452.0057)
		(end 11.433302 -451.501256)
		(width 0.111252)
		(layer "F.Cu")
		(net "SAS_EXP_A_PWR14")
	)
	(segment
		(start 11.433302 -451.501256)
		(end 3.193542 -451.501256)
		(width 0.111252)
		(layer "F.Cu")
		(net "SAS_EXP_A_PWR14")
	)
	(segment
		(start 96.329246 -13.6017)
		(end 97.027746 -13.6017)
		(width 0.111252)
		(layer "F.Cu")
		(net "SAS_EXP_A_PWR14")
	)
	(via
		(at 96.120712 -12.984226)
		(size 0.7112)
		(drill 0.3556)
		(layers "F.Cu" "B.Cu")
		(net "SAS_EXP_A_PWR14")
	)
	(via
		(at 11.937746 -452.0057)
		(size 0.5588)
		(drill 0.3048)
		(layers "F.Cu" "B.Cu")
		(net "SAS_EXP_A_PWR14")
	)
	(via
		(at 97.027746 -13.6017)
		(size 0.5588)
		(drill 0.3048)
		(layers "F.Cu" "B.Cu")
		(net "SAS_EXP_A_PWR14")
	)
	(via
		(at 20.345146 -461.5815)
		(size 0.5588)
		(drill 0.3048)
		(layers "F.Cu" "B.Cu")
		(net "SAS_EXP_A_PWR14")
	)
	(segment
		(start 97.027746 -13.5509)
		(end 96.461072 -12.984226)
		(width 0.111252)
		(layer "B.Cu")
		(net "SAS_EXP_A_PWR14")
	)
	(segment
		(start 96.461072 -12.984226)
		(end 96.120712 -12.984226)
		(width 0.111252)
		(layer "B.Cu")
		(net "SAS_EXP_A_PWR14")
	)
	(segment
		(start 97.027746 -13.6017)
		(end 97.027746 -13.5509)
		(width 0.111252)
		(layer "B.Cu")
		(net "SAS_EXP_A_PWR14")
	)
	(segment
		(start 9.603994 -465.996528)
		(end 9.884918 -466.277452)
		(width 0.14605)
		(layer "In2.Cu")
		(net "SAS_EXP_A_PWR14")
	)
	(segment
		(start 13.1826 -453.1868)
		(end 13.1826 -462.020666)
		(width 0.14605)
		(layer "In2.Cu")
		(net "SAS_EXP_A_PWR14")
	)
	(segment
		(start 11.937746 -452.0057)
		(end 12.0015 -452.0057)
		(width 0.14605)
		(layer "In2.Cu")
		(net "SAS_EXP_A_PWR14")
	)
	(segment
		(start 16.034766 -461.5815)
		(end 20.345146 -461.5815)
		(width 0.14605)
		(layer "In2.Cu")
		(net "SAS_EXP_A_PWR14")
	)
	(segment
		(start 12.0015 -452.0057)
		(end 13.1826 -453.1868)
		(width 0.14605)
		(layer "In2.Cu")
		(net "SAS_EXP_A_PWR14")
	)
	(segment
		(start 9.884918 -466.277452)
		(end 11.338814 -466.277452)
		(width 0.14605)
		(layer "In2.Cu")
		(net "SAS_EXP_A_PWR14")
	)
	(segment
		(start 9.603994 -465.599272)
		(end 9.603994 -465.996528)
		(width 0.14605)
		(layer "In2.Cu")
		(net "SAS_EXP_A_PWR14")
	)
	(segment
		(start 13.1826 -462.020666)
		(end 9.603994 -465.599272)
		(width 0.14605)
		(layer "In2.Cu")
		(net "SAS_EXP_A_PWR14")
	)
	(segment
		(start 11.338814 -466.277452)
		(end 16.034766 -461.5815)
		(width 0.14605)
		(layer "In2.Cu")
		(net "SAS_EXP_A_PWR14")
	)
	(segment
		(start 103.187246 -20.012406)
		(end 103.187246 -399.569432)
		(width 0.14605)
		(layer "In5.Cu")
		(net "SAS_EXP_A_PWR14")
	)
	(segment
		(start 88.003634 -454.6092)
		(end 87.913718 -454.6092)
		(width 0.14605)
		(layer "In5.Cu")
		(net "SAS_EXP_A_PWR14")
	)
	(segment
		(start 103.234998 -399.617184)
		(end 103.234998 -400.762216)
		(width 0.14605)
		(layer "In5.Cu")
		(net "SAS_EXP_A_PWR14")
	)
	(segment
		(start 103.155496 -19.980656)
		(end 103.187246 -20.012406)
		(width 0.14605)
		(layer "In5.Cu")
		(net "SAS_EXP_A_PWR14")
	)
	(segment
		(start 23.678896 -462.082896)
		(end 22.4536 -460.8576)
		(width 0.14605)
		(layer "In5.Cu")
		(net "SAS_EXP_A_PWR14")
	)
	(segment
		(start 103.1113 -439.456576)
		(end 103.1113 -439.501534)
		(width 0.14605)
		(layer "In5.Cu")
		(net "SAS_EXP_A_PWR14")
	)
	(segment
		(start 103.155496 -19.72945)
		(end 103.155496 -19.980656)
		(width 0.14605)
		(layer "In5.Cu")
		(net "SAS_EXP_A_PWR14")
	)
	(segment
		(start 97.027746 -13.6017)
		(end 103.155496 -19.72945)
		(width 0.14605)
		(layer "In5.Cu")
		(net "SAS_EXP_A_PWR14")
	)
	(segment
		(start 80.440022 -462.082896)
		(end 23.678896 -462.082896)
		(width 0.14605)
		(layer "In5.Cu")
		(net "SAS_EXP_A_PWR14")
	)
	(segment
		(start 103.187246 -439.38063)
		(end 103.1113 -439.456576)
		(width 0.14605)
		(layer "In5.Cu")
		(net "SAS_EXP_A_PWR14")
	)
	(segment
		(start 21.069046 -460.8576)
		(end 20.345146 -461.5815)
		(width 0.14605)
		(layer "In5.Cu")
		(net "SAS_EXP_A_PWR14")
	)
	(segment
		(start 22.4536 -460.8576)
		(end 21.069046 -460.8576)
		(width 0.14605)
		(layer "In5.Cu")
		(net "SAS_EXP_A_PWR14")
	)
	(segment
		(start 103.1113 -439.501534)
		(end 88.003634 -454.6092)
		(width 0.14605)
		(layer "In5.Cu")
		(net "SAS_EXP_A_PWR14")
	)
	(segment
		(start 103.187246 -399.569432)
		(end 103.234998 -399.617184)
		(width 0.14605)
		(layer "In5.Cu")
		(net "SAS_EXP_A_PWR14")
	)
	(segment
		(start 87.913718 -454.6092)
		(end 80.440022 -462.082896)
		(width 0.14605)
		(layer "In5.Cu")
		(net "SAS_EXP_A_PWR14")
	)
	(segment
		(start 103.234998 -400.762216)
		(end 103.187246 -400.809968)
		(width 0.14605)
		(layer "In5.Cu")
		(net "SAS_EXP_A_PWR14")
	)
	(segment
		(start 103.187246 -400.809968)
		(end 103.187246 -439.38063)
		(width 0.14605)
		(layer "In5.Cu")
		(net "SAS_EXP_A_PWR14")
	)
	(segment
		(start 76.771246 -23.037546)
		(end 76.7715 -23.0378)
		(width 0.111252)
		(layer "F.Cu")
		(net "HDD_PRSNT_NET14")
	)
	(segment
		(start 74.485246 -21.999702)
		(end 75.564746 -21.999702)
		(width 0.111252)
		(layer "F.Cu")
		(net "HDD_PRSNT_NET14")
	)
	(segment
		(start 24.482552 -23.154894)
		(end 21.7551 -23.154894)
		(width 0.111252)
		(layer "F.Cu")
		(net "HDD_PRSNT_NET14")
	)
	(segment
		(start 72.9234 -21.936202)
		(end 74.421746 -21.936202)
		(width 0.111252)
		(layer "F.Cu")
		(net "HDD_PRSNT_NET14")
	)
	(segment
		(start 72.119998 -21.936202)
		(end 72.9234 -21.936202)
		(width 0.111252)
		(layer "F.Cu")
		(net "HDD_PRSNT_NET14")
	)
	(segment
		(start 24.764746 -22.8727)
		(end 24.482552 -23.154894)
		(width 0.111252)
		(layer "F.Cu")
		(net "HDD_PRSNT_NET14")
	)
	(segment
		(start 21.7551 -23.154894)
		(end 21.75002 -23.149814)
		(width 0.111252)
		(layer "F.Cu")
		(net "HDD_PRSNT_NET14")
	)
	(segment
		(start 76.771246 -21.999702)
		(end 76.771246 -23.037546)
		(width 0.111252)
		(layer "F.Cu")
		(net "HDD_PRSNT_NET14")
	)
	(segment
		(start 74.421746 -21.936202)
		(end 74.485246 -21.999702)
		(width 0.111252)
		(layer "F.Cu")
		(net "HDD_PRSNT_NET14")
	)
	(segment
		(start 75.564746 -21.999702)
		(end 76.771246 -21.999702)
		(width 0.111252)
		(layer "F.Cu")
		(net "HDD_PRSNT_NET14")
	)
	(segment
		(start 71.8312 -22.225)
		(end 72.119998 -21.936202)
		(width 0.111252)
		(layer "F.Cu")
		(net "HDD_PRSNT_NET14")
	)
	(via
		(at 72.9234 -21.936202)
		(size 0.7112)
		(drill 0.3556)
		(layers "F.Cu" "B.Cu")
		(net "HDD_PRSNT_NET14")
	)
	(via
		(at 24.764746 -22.8727)
		(size 0.5588)
		(drill 0.3048)
		(layers "F.Cu" "B.Cu")
		(net "HDD_PRSNT_NET14")
	)
	(via
		(at 71.8312 -22.225)
		(size 0.5588)
		(drill 0.3048)
		(layers "F.Cu" "B.Cu")
		(net "HDD_PRSNT_NET14")
	)
	(segment
		(start 24.764746 -22.8727)
		(end 24.764746 -31.85795)
		(width 0.14605)
		(layer "In5.Cu")
		(net "HDD_PRSNT_NET14")
	)
	(segment
		(start 71.8312 -23.685246)
		(end 71.8312 -22.225)
		(width 0.14605)
		(layer "In5.Cu")
		(net "HDD_PRSNT_NET14")
	)
	(segment
		(start 58.927746 -36.5887)
		(end 71.8312 -23.685246)
		(width 0.14605)
		(layer "In5.Cu")
		(net "HDD_PRSNT_NET14")
	)
	(segment
		(start 29.495496 -36.5887)
		(end 58.927746 -36.5887)
		(width 0.14605)
		(layer "In5.Cu")
		(net "HDD_PRSNT_NET14")
	)
	(segment
		(start 24.764746 -31.85795)
		(end 29.495496 -36.5887)
		(width 0.14605)
		(layer "In5.Cu")
		(net "HDD_PRSNT_NET14")
	)
	(segment
		(start 27.706066 -441.980066)
		(end 27.787346 -441.898532)
		(width 0.09525)
		(layer "F.Cu")
		(net "SAS2X28_B_HDD10_RX_+")
	)
	(segment
		(start 26.733246 -441.8457)
		(end 26.77033 -441.88253)
		(width 0.09525)
		(layer "F.Cu")
		(net "SAS2X28_B_HDD10_RX_+")
	)
	(segment
		(start 27.787346 -441.898532)
		(end 27.787346 -441.8457)
		(width 0.09525)
		(layer "F.Cu")
		(net "SAS2X28_B_HDD10_RX_+")
	)
	(via
		(at 27.787346 -441.8457)
		(size 0.5588)
		(drill 0.3048)
		(layers "F.Cu" "B.Cu")
		(net "SAS2X28_B_HDD10_RX_+")
	)
	(arc
		(start 26.77033 -441.88253)
		(mid 27.038814 -442.062019)
		(end 27.355546 -442.1251)
		(width 0.09525)
		(layer "F.Cu")
		(net "SAS2X28_B_HDD10_RX_+")
	)
	(arc
		(start 27.355546 -442.1251)
		(mid 27.54524 -442.087461)
		(end 27.706066 -441.980066)
		(width 0.09525)
		(layer "F.Cu")
		(net "SAS2X28_B_HDD10_RX_+")
	)
	(segment
		(start 32.092646 -367.372646)
		(end 32.092646 -357.67137)
		(width 0.09525)
		(layer "B.Cu")
		(net "SAS2X28_B_HDD10_RX_+")
	)
	(segment
		(start 32.52216 -356.634542)
		(end 39.822374 -349.334328)
		(width 0.09525)
		(layer "B.Cu")
		(net "SAS2X28_B_HDD10_RX_+")
	)
	(segment
		(start 34.801556 -195.247514)
		(end 34.801556 -189.712854)
		(width 0.09525)
		(layer "B.Cu")
		(net "SAS2X28_B_HDD10_RX_+")
	)
	(segment
		(start 27.787346 -441.8457)
		(end 27.787346 -441.884054)
		(width 0.09525)
		(layer "B.Cu")
		(net "SAS2X28_B_HDD10_RX_+")
	)
	(segment
		(start 45.496226 -206.356966)
		(end 35.094926 -195.955666)
		(width 0.09525)
		(layer "B.Cu")
		(net "SAS2X28_B_HDD10_RX_+")
	)
	(segment
		(start 26.923746 -442.0997)
		(end 26.822146 -442.0997)
		(width 0.09525)
		(layer "B.Cu")
		(net "SAS2X28_B_HDD10_RX_+")
	)
	(segment
		(start 34.417254 -188.784992)
		(end 34.417254 -188.784738)
		(width 0.09525)
		(layer "B.Cu")
		(net "SAS2X28_B_HDD10_RX_+")
	)
	(segment
		(start 4.999482 -159.498792)
		(end 2.811526 -159.498792)
		(width 0.09525)
		(layer "B.Cu")
		(net "SAS2X28_B_HDD10_RX_+")
	)
	(segment
		(start 34.417254 -188.784738)
		(end 16.611854 -170.979338)
		(width 0.09525)
		(layer "B.Cu")
		(net "SAS2X28_B_HDD10_RX_+")
	)
	(segment
		(start 13.906246 -159.830516)
		(end 5.798312 -159.830516)
		(width 0.09525)
		(layer "B.Cu")
		(net "SAS2X28_B_HDD10_RX_+")
	)
	(segment
		(start 40.421814 -303.680622)
		(end 45.641514 -298.460922)
		(width 0.09525)
		(layer "B.Cu")
		(net "SAS2X28_B_HDD10_RX_+")
	)
	(segment
		(start 5.001006 -159.500316)
		(end 4.999482 -159.498792)
		(width 0.09525)
		(layer "B.Cu")
		(net "SAS2X28_B_HDD10_RX_+")
	)
	(segment
		(start 28.32989 -371.751098)
		(end 31.65729 -368.423698)
		(width 0.09525)
		(layer "B.Cu")
		(net "SAS2X28_B_HDD10_RX_+")
	)
	(segment
		(start 26.304494 -429.948848)
		(end 27.54884 -428.704502)
		(width 0.09525)
		(layer "B.Cu")
		(net "SAS2X28_B_HDD10_RX_+")
	)
	(segment
		(start 27.888946 -427.88332)
		(end 27.888946 -372.815612)
		(width 0.09525)
		(layer "B.Cu")
		(net "SAS2X28_B_HDD10_RX_+")
	)
	(segment
		(start 45.973746 -297.65879)
		(end 45.973746 -207.509872)
		(width 0.09525)
		(layer "B.Cu")
		(net "SAS2X28_B_HDD10_RX_+")
	)
	(segment
		(start 25.971246 -441.404248)
		(end 25.971246 -430.753266)
		(width 0.09525)
		(layer "B.Cu")
		(net "SAS2X28_B_HDD10_RX_+")
	)
	(segment
		(start 16.128746 -169.81297)
		(end 16.128746 -161.767012)
		(width 0.09525)
		(layer "B.Cu")
		(net "SAS2X28_B_HDD10_RX_+")
	)
	(segment
		(start 40.055546 -348.771464)
		(end 40.055546 -304.564796)
		(width 0.09525)
		(layer "B.Cu")
		(net "SAS2X28_B_HDD10_RX_+")
	)
	(arc
		(start 27.888946 -372.815612)
		(mid 28.003542 -372.239498)
		(end 28.32989 -371.751098)
		(width 0.09525)
		(layer "B.Cu")
		(net "SAS2X28_B_HDD10_RX_+")
	)
	(arc
		(start 39.822374 -349.334328)
		(mid 39.994927 -349.076084)
		(end 40.055546 -348.771464)
		(width 0.09525)
		(layer "B.Cu")
		(net "SAS2X28_B_HDD10_RX_+")
	)
	(arc
		(start 16.128746 -161.767012)
		(mid 15.996729 -161.10332)
		(end 15.620746 -160.5407)
		(width 0.09525)
		(layer "B.Cu")
		(net "SAS2X28_B_HDD10_RX_+")
	)
	(arc
		(start 40.055546 -304.564796)
		(mid 40.15073 -304.086273)
		(end 40.421814 -303.680622)
		(width 0.09525)
		(layer "B.Cu")
		(net "SAS2X28_B_HDD10_RX_+")
	)
	(arc
		(start 45.973746 -207.509872)
		(mid 45.849705 -206.885896)
		(end 45.496226 -206.356966)
		(width 0.09525)
		(layer "B.Cu")
		(net "SAS2X28_B_HDD10_RX_+")
	)
	(arc
		(start 31.65729 -368.423698)
		(mid 31.979504 -367.941471)
		(end 32.092646 -367.372646)
		(width 0.09525)
		(layer "B.Cu")
		(net "SAS2X28_B_HDD10_RX_+")
	)
	(arc
		(start 5.798312 -159.830516)
		(mid 5.510887 -159.773344)
		(end 5.267198 -159.610552)
		(width 0.09525)
		(layer "B.Cu")
		(net "SAS2X28_B_HDD10_RX_+")
	)
	(arc
		(start 35.094926 -195.955666)
		(mid 34.877833 -195.630763)
		(end 34.801556 -195.247514)
		(width 0.09525)
		(layer "B.Cu")
		(net "SAS2X28_B_HDD10_RX_+")
	)
	(arc
		(start 5.267198 -159.610552)
		(mid 5.145068 -159.528947)
		(end 5.001006 -159.500316)
		(width 0.09525)
		(layer "B.Cu")
		(net "SAS2X28_B_HDD10_RX_+")
	)
	(arc
		(start 45.641514 -298.460922)
		(mid 45.887418 -298.092901)
		(end 45.973746 -297.65879)
		(width 0.09525)
		(layer "B.Cu")
		(net "SAS2X28_B_HDD10_RX_+")
	)
	(arc
		(start 34.801556 -189.712854)
		(mid 34.701741 -189.210671)
		(end 34.417254 -188.784992)
		(width 0.09525)
		(layer "B.Cu")
		(net "SAS2X28_B_HDD10_RX_+")
	)
	(arc
		(start 26.822146 -442.0997)
		(mid 26.454432 -442.026557)
		(end 26.142696 -441.818268)
		(width 0.09525)
		(layer "B.Cu")
		(net "SAS2X28_B_HDD10_RX_+")
	)
	(arc
		(start 27.54884 -428.704502)
		(mid 27.800555 -428.32774)
		(end 27.888946 -427.88332)
		(width 0.09525)
		(layer "B.Cu")
		(net "SAS2X28_B_HDD10_RX_+")
	)
	(arc
		(start 16.611854 -170.979338)
		(mid 16.254289 -170.444204)
		(end 16.128746 -169.81297)
		(width 0.09525)
		(layer "B.Cu")
		(net "SAS2X28_B_HDD10_RX_+")
	)
	(arc
		(start 25.971246 -430.753266)
		(mid 26.057846 -430.3179)
		(end 26.304494 -429.948848)
		(width 0.09525)
		(layer "B.Cu")
		(net "SAS2X28_B_HDD10_RX_+")
	)
	(arc
		(start 15.620746 -160.5407)
		(mid 14.834127 -160.015098)
		(end 13.906246 -159.830516)
		(width 0.09525)
		(layer "B.Cu")
		(net "SAS2X28_B_HDD10_RX_+")
	)
	(arc
		(start 26.142696 -441.818268)
		(mid 26.015773 -441.628314)
		(end 25.971246 -441.404248)
		(width 0.09525)
		(layer "B.Cu")
		(net "SAS2X28_B_HDD10_RX_+")
	)
	(arc
		(start 32.092646 -357.67137)
		(mid 32.204265 -357.110225)
		(end 32.52216 -356.634542)
		(width 0.09525)
		(layer "B.Cu")
		(net "SAS2X28_B_HDD10_RX_+")
	)
	(arc
		(start 27.787346 -441.884054)
		(mid 27.657607 -442.136847)
		(end 27.376628 -442.178694)
		(width 0.09525)
		(layer "B.Cu")
		(net "SAS2X28_B_HDD10_RX_+")
	)
	(arc
		(start 27.376628 -442.178694)
		(mid 27.153221 -442.1218)
		(end 26.923746 -442.0997)
		(width 0.09525)
		(layer "B.Cu")
		(net "SAS2X28_B_HDD10_RX_+")
	)
	(via
		(at 53.593746 -279.5397)
		(size 0.7112)
		(drill 0.3556)
		(layers "F.Cu" "B.Cu")
		(net "5V_PRE_7")
	)
	(segment
		(start 34.464244 -131.410202)
		(end 34.416746 -131.4577)
		(width 0.111252)
		(layer "F.Cu")
		(net "HDD_PRSNT_NET13")
	)
	(segment
		(start 35.369246 -131.473702)
		(end 35.305746 -131.410202)
		(width 0.111252)
		(layer "F.Cu")
		(net "HDD_PRSNT_NET13")
	)
	(segment
		(start 35.305746 -131.410202)
		(end 34.464244 -131.410202)
		(width 0.111252)
		(layer "F.Cu")
		(net "HDD_PRSNT_NET13")
	)
	(segment
		(start 27.304746 -126.2507)
		(end 27.208988 -126.154942)
		(width 0.111252)
		(layer "F.Cu")
		(net "HDD_PRSNT_NET13")
	)
	(segment
		(start 34.416746 -133.12902)
		(end 34.3662 -133.179566)
		(width 0.111252)
		(layer "F.Cu")
		(net "HDD_PRSNT_NET13")
	)
	(segment
		(start 34.368994 -133.18236)
		(end 34.3662 -133.179566)
		(width 0.111252)
		(layer "F.Cu")
		(net "HDD_PRSNT_NET13")
	)
	(segment
		(start 37.655246 -131.473702)
		(end 36.448746 -131.473702)
		(width 0.111252)
		(layer "F.Cu")
		(net "HDD_PRSNT_NET13")
	)
	(segment
		(start 21.7551 -126.154942)
		(end 21.75002 -126.149862)
		(width 0.111252)
		(layer "F.Cu")
		(net "HDD_PRSNT_NET13")
	)
	(segment
		(start 36.448746 -131.473702)
		(end 35.369246 -131.473702)
		(width 0.111252)
		(layer "F.Cu")
		(net "HDD_PRSNT_NET13")
	)
	(segment
		(start 27.208988 -126.154942)
		(end 21.7551 -126.154942)
		(width 0.111252)
		(layer "F.Cu")
		(net "HDD_PRSNT_NET13")
	)
	(segment
		(start 34.416746 -131.4577)
		(end 34.416746 -133.12902)
		(width 0.111252)
		(layer "F.Cu")
		(net "HDD_PRSNT_NET13")
	)
	(segment
		(start 34.544 -134.3025)
		(end 34.368994 -134.127494)
		(width 0.111252)
		(layer "F.Cu")
		(net "HDD_PRSNT_NET13")
	)
	(segment
		(start 34.368994 -134.127494)
		(end 34.368994 -133.18236)
		(width 0.111252)
		(layer "F.Cu")
		(net "HDD_PRSNT_NET13")
	)
	(via
		(at 34.416746 -131.4577)
		(size 0.5588)
		(drill 0.3048)
		(layers "F.Cu" "B.Cu")
		(net "HDD_PRSNT_NET13")
	)
	(via
		(at 34.3662 -133.179566)
		(size 0.7112)
		(drill 0.3556)
		(layers "F.Cu" "B.Cu")
		(net "HDD_PRSNT_NET13")
	)
	(via
		(at 27.304746 -126.2507)
		(size 0.5588)
		(drill 0.3048)
		(layers "F.Cu" "B.Cu")
		(net "HDD_PRSNT_NET13")
	)
	(segment
		(start 28.189682 -126.2507)
		(end 27.304746 -126.2507)
		(width 0.14605)
		(layer "In5.Cu")
		(net "HDD_PRSNT_NET13")
	)
	(segment
		(start 33.400746 -131.4577)
		(end 33.000696 -131.05765)
		(width 0.14605)
		(layer "In5.Cu")
		(net "HDD_PRSNT_NET13")
	)
	(segment
		(start 32.996632 -131.05765)
		(end 28.189682 -126.2507)
		(width 0.14605)
		(layer "In5.Cu")
		(net "HDD_PRSNT_NET13")
	)
	(segment
		(start 33.000696 -131.05765)
		(end 32.996632 -131.05765)
		(width 0.14605)
		(layer "In5.Cu")
		(net "HDD_PRSNT_NET13")
	)
	(segment
		(start 34.416746 -131.4577)
		(end 33.400746 -131.4577)
		(width 0.14605)
		(layer "In5.Cu")
		(net "HDD_PRSNT_NET13")
	)
	(segment
		(start 28.940506 -436.90794)
		(end 29.781246 -436.90794)
		(width 0.111252)
		(layer "F.Cu")
		(net "SAS2X28_B_HDD10_FLT")
	)
	(segment
		(start 28.812744 -437.035702)
		(end 28.940506 -436.90794)
		(width 0.111252)
		(layer "F.Cu")
		(net "SAS2X28_B_HDD10_FLT")
	)
	(segment
		(start 3.19405 -141.500352)
		(end 3.192526 -141.498828)
		(width 0.111252)
		(layer "F.Cu")
		(net "SAS2X28_B_HDD10_FLT")
	)
	(segment
		(start 27.749246 -437.035702)
		(end 27.749246 -438.3532)
		(width 0.111252)
		(layer "F.Cu")
		(net "SAS2X28_B_HDD10_FLT")
	)
	(segment
		(start 28.590748 -437.035702)
		(end 28.812744 -437.035702)
		(width 0.111252)
		(layer "F.Cu")
		(net "SAS2X28_B_HDD10_FLT")
	)
	(segment
		(start 28.590748 -438.172098)
		(end 28.590748 -437.035702)
		(width 0.111252)
		(layer "F.Cu")
		(net "SAS2X28_B_HDD10_FLT")
	)
	(segment
		(start 28.409646 -438.3532)
		(end 28.590748 -438.172098)
		(width 0.111252)
		(layer "F.Cu")
		(net "SAS2X28_B_HDD10_FLT")
	)
	(segment
		(start 7.603998 -141.500352)
		(end 3.19405 -141.500352)
		(width 0.111252)
		(layer "F.Cu")
		(net "SAS2X28_B_HDD10_FLT")
	)
	(segment
		(start 7.619746 -141.5161)
		(end 7.603998 -141.500352)
		(width 0.111252)
		(layer "F.Cu")
		(net "SAS2X28_B_HDD10_FLT")
	)
	(segment
		(start 27.749246 -438.3532)
		(end 28.409646 -438.3532)
		(width 0.111252)
		(layer "F.Cu")
		(net "SAS2X28_B_HDD10_FLT")
	)
	(via
		(at 7.619746 -141.5161)
		(size 0.5588)
		(drill 0.3048)
		(layers "F.Cu" "B.Cu")
		(net "SAS2X28_B_HDD10_FLT")
	)
	(via
		(at 27.749246 -438.3532)
		(size 0.7112)
		(drill 0.3556)
		(layers "F.Cu" "B.Cu")
		(net "SAS2X28_B_HDD10_FLT")
	)
	(via
		(at 28.590748 -437.035702)
		(size 0.5588)
		(drill 0.3048)
		(layers "F.Cu" "B.Cu")
		(net "SAS2X28_B_HDD10_FLT")
	)
	(via
		(at 95.9866 -432.7652)
		(size 0.5588)
		(drill 0.3048)
		(layers "F.Cu" "B.Cu")
		(net "SAS2X28_B_HDD10_FLT")
	)
	(segment
		(start 30.5816 -435.04485)
		(end 28.590748 -437.035702)
		(width 0.14605)
		(layer "In2.Cu")
		(net "SAS2X28_B_HDD10_FLT")
	)
	(segment
		(start 32.222694 -432.484276)
		(end 30.5816 -434.12537)
		(width 0.14605)
		(layer "In2.Cu")
		(net "SAS2X28_B_HDD10_FLT")
	)
	(segment
		(start 30.5816 -434.12537)
		(end 30.5816 -435.04485)
		(width 0.14605)
		(layer "In2.Cu")
		(net "SAS2X28_B_HDD10_FLT")
	)
	(segment
		(start 77.701648 -426.748448)
		(end 37.913818 -426.748448)
		(width 0.14605)
		(layer "In2.Cu")
		(net "SAS2X28_B_HDD10_FLT")
	)
	(segment
		(start 83.7184 -432.7652)
		(end 77.701648 -426.748448)
		(width 0.14605)
		(layer "In2.Cu")
		(net "SAS2X28_B_HDD10_FLT")
	)
	(segment
		(start 95.9866 -432.7652)
		(end 83.7184 -432.7652)
		(width 0.14605)
		(layer "In2.Cu")
		(net "SAS2X28_B_HDD10_FLT")
	)
	(segment
		(start 32.222694 -432.439572)
		(end 32.222694 -432.484276)
		(width 0.14605)
		(layer "In2.Cu")
		(net "SAS2X28_B_HDD10_FLT")
	)
	(segment
		(start 37.913818 -426.748448)
		(end 32.222694 -432.439572)
		(width 0.14605)
		(layer "In2.Cu")
		(net "SAS2X28_B_HDD10_FLT")
	)
	(segment
		(start 96.884998 -431.866802)
		(end 95.9866 -432.7652)
		(width 0.14605)
		(layer "In5.Cu")
		(net "SAS2X28_B_HDD10_FLT")
	)
	(segment
		(start 8.596884 -139.153392)
		(end 8.596884 -136.641078)
		(width 0.14605)
		(layer "In5.Cu")
		(net "SAS2X28_B_HDD10_FLT")
	)
	(segment
		(start 88.403938 -97.685098)
		(end 96.884998 -106.166158)
		(width 0.14605)
		(layer "In5.Cu")
		(net "SAS2X28_B_HDD10_FLT")
	)
	(segment
		(start 8.883904 -136.354058)
		(end 8.883904 -134.059676)
		(width 0.14605)
		(layer "In5.Cu")
		(net "SAS2X28_B_HDD10_FLT")
	)
	(segment
		(start 8.883904 -134.059676)
		(end 10.233152 -132.710428)
		(width 0.14605)
		(layer "In5.Cu")
		(net "SAS2X28_B_HDD10_FLT")
	)
	(segment
		(start 9.794748 -130.147568)
		(end 9.794748 -108.663994)
		(width 0.14605)
		(layer "In5.Cu")
		(net "SAS2X28_B_HDD10_FLT")
	)
	(segment
		(start 20.773644 -97.685098)
		(end 88.403938 -97.685098)
		(width 0.14605)
		(layer "In5.Cu")
		(net "SAS2X28_B_HDD10_FLT")
	)
	(segment
		(start 10.233152 -132.710428)
		(end 10.233152 -130.585972)
		(width 0.14605)
		(layer "In5.Cu")
		(net "SAS2X28_B_HDD10_FLT")
	)
	(segment
		(start 9.794748 -108.663994)
		(end 20.773644 -97.685098)
		(width 0.14605)
		(layer "In5.Cu")
		(net "SAS2X28_B_HDD10_FLT")
	)
	(segment
		(start 7.619746 -141.5161)
		(end 7.619746 -140.13053)
		(width 0.14605)
		(layer "In5.Cu")
		(net "SAS2X28_B_HDD10_FLT")
	)
	(segment
		(start 96.884998 -106.166158)
		(end 96.884998 -431.866802)
		(width 0.14605)
		(layer "In5.Cu")
		(net "SAS2X28_B_HDD10_FLT")
	)
	(segment
		(start 7.619746 -140.13053)
		(end 8.596884 -139.153392)
		(width 0.14605)
		(layer "In5.Cu")
		(net "SAS2X28_B_HDD10_FLT")
	)
	(segment
		(start 10.233152 -130.585972)
		(end 9.794748 -130.147568)
		(width 0.14605)
		(layer "In5.Cu")
		(net "SAS2X28_B_HDD10_FLT")
	)
	(segment
		(start 8.596884 -136.641078)
		(end 8.883904 -136.354058)
		(width 0.14605)
		(layer "In5.Cu")
		(net "SAS2X28_B_HDD10_FLT")
	)
	(via
		(at 53.721 -384.048)
		(size 0.7112)
		(drill 0.3556)
		(layers "F.Cu" "B.Cu")
		(net "5V_PRE_6")
	)
	(segment
		(start 39.489126 -233.3117)
		(end 39.870126 -232.9307)
		(width 0.111252)
		(layer "F.Cu")
		(net "HDD_PRSNT_NET12")
	)
	(segment
		(start 23.968456 -229.15499)
		(end 21.7551 -229.15499)
		(width 0.111252)
		(layer "F.Cu")
		(net "HDD_PRSNT_NET12")
	)
	(segment
		(start 39.870126 -232.9307)
		(end 40.171624 -232.629202)
		(width 0.111252)
		(layer "F.Cu")
		(net "HDD_PRSNT_NET12")
	)
	(segment
		(start 41.211246 -232.692702)
		(end 42.290746 -232.692702)
		(width 0.111252)
		(layer "F.Cu")
		(net "HDD_PRSNT_NET12")
	)
	(segment
		(start 41.147746 -232.629202)
		(end 41.211246 -232.692702)
		(width 0.111252)
		(layer "F.Cu")
		(net "HDD_PRSNT_NET12")
	)
	(segment
		(start 38.988746 -233.3117)
		(end 39.489126 -233.3117)
		(width 0.111252)
		(layer "F.Cu")
		(net "HDD_PRSNT_NET12")
	)
	(segment
		(start 40.171624 -232.629202)
		(end 41.147746 -232.629202)
		(width 0.111252)
		(layer "F.Cu")
		(net "HDD_PRSNT_NET12")
	)
	(segment
		(start 21.7551 -229.15499)
		(end 21.75002 -229.14991)
		(width 0.111252)
		(layer "F.Cu")
		(net "HDD_PRSNT_NET12")
	)
	(segment
		(start 43.053 -233.9213)
		(end 43.4975 -234.3658)
		(width 0.111252)
		(layer "F.Cu")
		(net "HDD_PRSNT_NET12")
	)
	(segment
		(start 43.497246 -232.692702)
		(end 43.053 -233.136948)
		(width 0.111252)
		(layer "F.Cu")
		(net "HDD_PRSNT_NET12")
	)
	(segment
		(start 42.290746 -232.692702)
		(end 43.497246 -232.692702)
		(width 0.111252)
		(layer "F.Cu")
		(net "HDD_PRSNT_NET12")
	)
	(segment
		(start 24.129746 -228.9937)
		(end 23.968456 -229.15499)
		(width 0.111252)
		(layer "F.Cu")
		(net "HDD_PRSNT_NET12")
	)
	(segment
		(start 43.053 -233.136948)
		(end 43.053 -233.9213)
		(width 0.111252)
		(layer "F.Cu")
		(net "HDD_PRSNT_NET12")
	)
	(via
		(at 24.129746 -228.9937)
		(size 0.5588)
		(drill 0.3048)
		(layers "F.Cu" "B.Cu")
		(net "HDD_PRSNT_NET12")
	)
	(via
		(at 38.988746 -233.3117)
		(size 0.5588)
		(drill 0.3048)
		(layers "F.Cu" "B.Cu")
		(net "HDD_PRSNT_NET12")
	)
	(via
		(at 39.870126 -232.9307)
		(size 0.7112)
		(drill 0.3556)
		(layers "F.Cu" "B.Cu")
		(net "HDD_PRSNT_NET12")
	)
	(segment
		(start 28.447746 -233.3117)
		(end 38.988746 -233.3117)
		(width 0.14605)
		(layer "In5.Cu")
		(net "HDD_PRSNT_NET12")
	)
	(segment
		(start 24.129746 -228.9937)
		(end 28.447746 -233.3117)
		(width 0.14605)
		(layer "In5.Cu")
		(net "HDD_PRSNT_NET12")
	)
	(segment
		(start 20.827746 -467.3727)
		(end 19.393916 -467.3727)
		(width 0.111252)
		(layer "F.Cu")
		(net "DRIVE_ACT_10")
	)
	(segment
		(start 18.668746 -466.8012)
		(end 18.668746 -467.3727)
		(width 0.111252)
		(layer "F.Cu")
		(net "DRIVE_ACT_10")
	)
	(segment
		(start 17.389348 -468.150702)
		(end 17.259046 -468.0204)
		(width 0.111252)
		(layer "F.Cu")
		(net "DRIVE_ACT_10")
	)
	(segment
		(start 18.795746 -467.4997)
		(end 18.795746 -468.150702)
		(width 0.111252)
		(layer "F.Cu")
		(net "DRIVE_ACT_10")
	)
	(segment
		(start 18.732246 -466.7377)
		(end 18.668746 -466.8012)
		(width 0.111252)
		(layer "F.Cu")
		(net "DRIVE_ACT_10")
	)
	(segment
		(start 18.795746 -468.150702)
		(end 17.389348 -468.150702)
		(width 0.111252)
		(layer "F.Cu")
		(net "DRIVE_ACT_10")
	)
	(segment
		(start 18.758916 -466.7377)
		(end 18.732246 -466.7377)
		(width 0.111252)
		(layer "F.Cu")
		(net "DRIVE_ACT_10")
	)
	(segment
		(start 21.208746 -467.7537)
		(end 20.827746 -467.3727)
		(width 0.111252)
		(layer "F.Cu")
		(net "DRIVE_ACT_10")
	)
	(segment
		(start 18.668746 -467.3727)
		(end 18.795746 -467.4997)
		(width 0.111252)
		(layer "F.Cu")
		(net "DRIVE_ACT_10")
	)
	(segment
		(start 19.393916 -467.3727)
		(end 18.758916 -466.7377)
		(width 0.111252)
		(layer "F.Cu")
		(net "DRIVE_ACT_10")
	)
	(via
		(at 21.208746 -467.7537)
		(size 0.7112)
		(drill 0.3556)
		(layers "F.Cu" "B.Cu")
		(net "DRIVE_ACT_10")
	)
	(via
		(at 54.609746 -486.1687)
		(size 0.7112)
		(drill 0.3556)
		(layers "F.Cu" "B.Cu")
		(net "5V_PRE_5")
	)
	(via
		(at 54.609746 -485.0257)
		(size 0.5588)
		(drill 0.3048)
		(layers "F.Cu" "B.Cu")
		(net "5V_PRE_5")
	)
	(segment
		(start 54.609746 -485.0257)
		(end 54.609746 -486.1687)
		(width 0.508)
		(layer "B.Cu")
		(net "5V_PRE_5")
	)
	(segment
		(start 28.638246 -329.89012)
		(end 28.638246 -329.720702)
		(width 0.111252)
		(layer "F.Cu")
		(net "HDD_PRSNT_NET11")
	)
	(segment
		(start 31.0388 -334.137)
		(end 31.0388 -332.676754)
		(width 0.111252)
		(layer "F.Cu")
		(net "HDD_PRSNT_NET11")
	)
	(segment
		(start 30.880812 -332.518766)
		(end 30.880812 -332.511908)
		(width 0.111252)
		(layer "F.Cu")
		(net "HDD_PRSNT_NET11")
	)
	(segment
		(start 31.6357 -334.7339)
		(end 31.0388 -334.137)
		(width 0.111252)
		(layer "F.Cu")
		(net "HDD_PRSNT_NET11")
	)
	(segment
		(start 26.923746 -333.0067)
		(end 25.11679 -333.0067)
		(width 0.111252)
		(layer "F.Cu")
		(net "HDD_PRSNT_NET11")
	)
	(segment
		(start 26.288746 -329.657202)
		(end 26.352246 -329.720702)
		(width 0.111252)
		(layer "F.Cu")
		(net "HDD_PRSNT_NET11")
	)
	(segment
		(start 25.5778 -329.907646)
		(end 25.828244 -329.657202)
		(width 0.111252)
		(layer "F.Cu")
		(net "HDD_PRSNT_NET11")
	)
	(segment
		(start 30.880812 -332.511908)
		(end 30.773878 -332.404974)
		(width 0.111252)
		(layer "F.Cu")
		(net "HDD_PRSNT_NET11")
	)
	(segment
		(start 31.0388 -332.676754)
		(end 30.880812 -332.518766)
		(width 0.111252)
		(layer "F.Cu")
		(net "HDD_PRSNT_NET11")
	)
	(segment
		(start 27.431746 -329.720702)
		(end 28.638246 -329.720702)
		(width 0.111252)
		(layer "F.Cu")
		(net "HDD_PRSNT_NET11")
	)
	(segment
		(start 30.773878 -332.404974)
		(end 29.941774 -332.404974)
		(width 0.111252)
		(layer "F.Cu")
		(net "HDD_PRSNT_NET11")
	)
	(segment
		(start 26.352246 -329.720702)
		(end 27.431746 -329.720702)
		(width 0.111252)
		(layer "F.Cu")
		(net "HDD_PRSNT_NET11")
	)
	(segment
		(start 29.8196 -331.071474)
		(end 28.638246 -329.89012)
		(width 0.111252)
		(layer "F.Cu")
		(net "HDD_PRSNT_NET11")
	)
	(segment
		(start 29.8196 -332.2828)
		(end 29.8196 -331.071474)
		(width 0.111252)
		(layer "F.Cu")
		(net "HDD_PRSNT_NET11")
	)
	(segment
		(start 26.923746 -333.0067)
		(end 25.5778 -331.660754)
		(width 0.111252)
		(layer "F.Cu")
		(net "HDD_PRSNT_NET11")
	)
	(segment
		(start 29.941774 -332.404974)
		(end 29.8196 -332.2828)
		(width 0.111252)
		(layer "F.Cu")
		(net "HDD_PRSNT_NET11")
	)
	(segment
		(start 21.7551 -332.155038)
		(end 21.75002 -332.149958)
		(width 0.111252)
		(layer "F.Cu")
		(net "HDD_PRSNT_NET11")
	)
	(segment
		(start 25.828244 -329.657202)
		(end 26.288746 -329.657202)
		(width 0.111252)
		(layer "F.Cu")
		(net "HDD_PRSNT_NET11")
	)
	(segment
		(start 24.265128 -332.155038)
		(end 21.7551 -332.155038)
		(width 0.111252)
		(layer "F.Cu")
		(net "HDD_PRSNT_NET11")
	)
	(segment
		(start 25.5778 -331.660754)
		(end 25.5778 -329.907646)
		(width 0.111252)
		(layer "F.Cu")
		(net "HDD_PRSNT_NET11")
	)
	(segment
		(start 25.11679 -333.0067)
		(end 24.265128 -332.155038)
		(width 0.111252)
		(layer "F.Cu")
		(net "HDD_PRSNT_NET11")
	)
	(segment
		(start 31.6357 -335.2546)
		(end 31.6357 -334.7339)
		(width 0.111252)
		(layer "F.Cu")
		(net "HDD_PRSNT_NET11")
	)
	(via
		(at 26.923746 -333.0067)
		(size 0.7112)
		(drill 0.3556)
		(layers "F.Cu" "B.Cu")
		(net "HDD_PRSNT_NET11")
	)
	(segment
		(start 8.444484 -413.14624)
		(end 8.742426 -413.14624)
		(width 0.09525)
		(layer "F.Cu")
		(net "SAS2X28_A_HDD10_RX_+")
	)
	(segment
		(start 16.420846 -421.599868)
		(end 16.420846 -455.913236)
		(width 0.09525)
		(layer "F.Cu")
		(net "SAS2X28_A_HDD10_RX_+")
	)
	(segment
		(start 21.855938 -458.534516)
		(end 28.647898 -451.742556)
		(width 0.09525)
		(layer "F.Cu")
		(net "SAS2X28_A_HDD10_RX_+")
	)
	(segment
		(start 27.905202 -448.3481)
		(end 27.78379 -448.3481)
		(width 0.09525)
		(layer "F.Cu")
		(net "SAS2X28_A_HDD10_RX_+")
	)
	(segment
		(start 9.025128 -413.263334)
		(end 15.75562 -419.993826)
		(width 0.09525)
		(layer "F.Cu")
		(net "SAS2X28_A_HDD10_RX_+")
	)
	(segment
		(start 28.930346 -451.059804)
		(end 28.930346 -449.373244)
		(width 0.09525)
		(layer "F.Cu")
		(net "SAS2X28_A_HDD10_RX_+")
	)
	(segment
		(start 19.303746 -459.1177)
		(end 20.406868 -459.1177)
		(width 0.09525)
		(layer "F.Cu")
		(net "SAS2X28_A_HDD10_RX_+")
	)
	(segment
		(start 8.296402 -413.557974)
		(end 8.296402 -413.294322)
		(width 0.09525)
		(layer "F.Cu")
		(net "SAS2X28_A_HDD10_RX_+")
	)
	(segment
		(start 28.647898 -448.690492)
		(end 28.587954 -448.630548)
		(width 0.09525)
		(layer "F.Cu")
		(net "SAS2X28_A_HDD10_RX_+")
	)
	(segment
		(start 17.24787 -457.90993)
		(end 17.855946 -458.518006)
		(width 0.09525)
		(layer "F.Cu")
		(net "SAS2X28_A_HDD10_RX_+")
	)
	(via
		(at 8.296402 -413.557974)
		(size 0.5588)
		(drill 0.3048)
		(layers "F.Cu" "B.Cu")
		(net "SAS2X28_A_HDD10_RX_+")
	)
	(arc
		(start 8.742426 -413.14624)
		(mid 8.895421 -413.176673)
		(end 9.025128 -413.263334)
		(width 0.09525)
		(layer "F.Cu")
		(net "SAS2X28_A_HDD10_RX_+")
	)
	(arc
		(start 17.855946 -458.518006)
		(mid 18.520202 -458.961848)
		(end 19.303746 -459.1177)
		(width 0.09525)
		(layer "F.Cu")
		(net "SAS2X28_A_HDD10_RX_+")
	)
	(arc
		(start 8.296402 -413.294322)
		(mid 8.339774 -413.189612)
		(end 8.444484 -413.14624)
		(width 0.09525)
		(layer "F.Cu")
		(net "SAS2X28_A_HDD10_RX_+")
	)
	(arc
		(start 28.930346 -449.373244)
		(mid 28.856988 -449.003796)
		(end 28.647898 -448.690492)
		(width 0.09525)
		(layer "F.Cu")
		(net "SAS2X28_A_HDD10_RX_+")
	)
	(arc
		(start 16.420846 -455.913236)
		(mid 16.635842 -456.993801)
		(end 17.24787 -457.90993)
		(width 0.09525)
		(layer "F.Cu")
		(net "SAS2X28_A_HDD10_RX_+")
	)
	(arc
		(start 20.446746 -459.118208)
		(mid 21.20939 -458.966509)
		(end 21.855938 -458.534516)
		(width 0.09525)
		(layer "F.Cu")
		(net "SAS2X28_A_HDD10_RX_+")
	)
	(arc
		(start 20.406868 -459.1177)
		(mid 20.426806 -459.118053)
		(end 20.446746 -459.118208)
		(width 0.09525)
		(layer "F.Cu")
		(net "SAS2X28_A_HDD10_RX_+")
	)
	(arc
		(start 15.75562 -419.993826)
		(mid 16.247973 -420.730684)
		(end 16.420846 -421.599868)
		(width 0.09525)
		(layer "F.Cu")
		(net "SAS2X28_A_HDD10_RX_+")
	)
	(arc
		(start 28.647898 -451.742556)
		(mid 28.857014 -451.429263)
		(end 28.930346 -451.059804)
		(width 0.09525)
		(layer "F.Cu")
		(net "SAS2X28_A_HDD10_RX_+")
	)
	(arc
		(start 28.587954 -448.630548)
		(mid 28.274661 -448.421432)
		(end 27.905202 -448.3481)
		(width 0.09525)
		(layer "F.Cu")
		(net "SAS2X28_A_HDD10_RX_+")
	)
	(arc
		(start 27.78379 -448.3481)
		(mid 27.478656 -448.27415)
		(end 27.241246 -448.0687)
		(width 0.09525)
		(layer "F.Cu")
		(net "SAS2X28_A_HDD10_RX_+")
	)
	(segment
		(start 4.717288 -409.500324)
		(end 4.715764 -409.4988)
		(width 0.09525)
		(layer "B.Cu")
		(net "SAS2X28_A_HDD10_RX_+")
	)
	(segment
		(start 7.462012 -410.826712)
		(end 7.44601 -410.810964)
		(width 0.09525)
		(layer "B.Cu")
		(net "SAS2X28_A_HDD10_RX_+")
	)
	(segment
		(start 8.000746 -413.0167)
		(end 8.000746 -412.1277)
		(width 0.09525)
		(layer "B.Cu")
		(net "SAS2X28_A_HDD10_RX_+")
	)
	(segment
		(start 5.23875 -409.716224)
		(end 5.238496 -409.716224)
		(width 0.09525)
		(layer "B.Cu")
		(net "SAS2X28_A_HDD10_RX_+")
	)
	(segment
		(start 8.296402 -413.557974)
		(end 8.174482 -413.436054)
		(width 0.09525)
		(layer "B.Cu")
		(net "SAS2X28_A_HDD10_RX_+")
	)
	(segment
		(start 6.857746 -410.2227)
		(end 6.857746 -410.222446)
		(width 0.09525)
		(layer "B.Cu")
		(net "SAS2X28_A_HDD10_RX_+")
	)
	(segment
		(start 6.065266 -409.830524)
		(end 5.51434 -409.830524)
		(width 0.09525)
		(layer "B.Cu")
		(net "SAS2X28_A_HDD10_RX_+")
	)
	(segment
		(start 4.715764 -409.4988)
		(end 2.811526 -409.4988)
		(width 0.09525)
		(layer "B.Cu")
		(net "SAS2X28_A_HDD10_RX_+")
	)
	(segment
		(start 6.857746 -410.222446)
		(end 6.748272 -410.112972)
		(width 0.09525)
		(layer "B.Cu")
		(net "SAS2X28_A_HDD10_RX_+")
	)
	(segment
		(start 7.44601 -410.810964)
		(end 6.857746 -410.2227)
		(width 0.09525)
		(layer "B.Cu")
		(net "SAS2X28_A_HDD10_RX_+")
	)
	(arc
		(start 5.238496 -409.716224)
		(mid 4.999364 -409.556441)
		(end 4.717288 -409.500324)
		(width 0.09525)
		(layer "B.Cu")
		(net "SAS2X28_A_HDD10_RX_+")
	)
	(arc
		(start 8.174482 -413.436054)
		(mid 8.104565 -413.351973)
		(end 8.051292 -413.256476)
		(width 0.09525)
		(layer "B.Cu")
		(net "SAS2X28_A_HDD10_RX_+")
	)
	(arc
		(start 6.748272 -410.112972)
		(mid 6.448696 -409.909511)
		(end 6.095238 -409.830778)
		(width 0.09525)
		(layer "B.Cu")
		(net "SAS2X28_A_HDD10_RX_+")
	)
	(arc
		(start 5.51434 -409.830524)
		(mid 5.365189 -409.800762)
		(end 5.23875 -409.716224)
		(width 0.09525)
		(layer "B.Cu")
		(net "SAS2X28_A_HDD10_RX_+")
	)
	(arc
		(start 8.051292 -413.256476)
		(mid 8.013513 -413.139226)
		(end 8.000746 -413.0167)
		(width 0.09525)
		(layer "B.Cu")
		(net "SAS2X28_A_HDD10_RX_+")
	)
	(arc
		(start 8.000746 -412.1277)
		(mid 7.860788 -411.423615)
		(end 7.462012 -410.826712)
		(width 0.09525)
		(layer "B.Cu")
		(net "SAS2X28_A_HDD10_RX_+")
	)
	(arc
		(start 6.095238 -409.830778)
		(mid 6.080253 -409.830536)
		(end 6.065266 -409.830524)
		(width 0.09525)
		(layer "B.Cu")
		(net "SAS2X28_A_HDD10_RX_+")
	)
	(segment
		(start 28.955746 -432.463702)
		(end 27.812746 -432.463702)
		(width 0.111252)
		(layer "F.Cu")
		(net "HDD_PRSNT_NET10")
	)
	(segment
		(start 38.7604 -427.0121)
		(end 38.7604 -426.212)
		(width 0.111252)
		(layer "F.Cu")
		(net "HDD_PRSNT_NET10")
	)
	(segment
		(start 28.955746 -433.5907)
		(end 28.955746 -432.463702)
		(width 0.111252)
		(layer "F.Cu")
		(net "HDD_PRSNT_NET10")
	)
	(segment
		(start 23.491444 -435.150006)
		(end 26.304748 -432.336702)
		(width 0.111252)
		(layer "F.Cu")
		(net "HDD_PRSNT_NET10")
	)
	(segment
		(start 21.75002 -435.150006)
		(end 23.491444 -435.150006)
		(width 0.111252)
		(layer "F.Cu")
		(net "HDD_PRSNT_NET10")
	)
	(segment
		(start 30.860746 -433.8447)
		(end 30.759146 -433.9463)
		(width 0.111252)
		(layer "F.Cu")
		(net "HDD_PRSNT_NET10")
	)
	(segment
		(start 27.812746 -432.463702)
		(end 26.796746 -432.463702)
		(width 0.111252)
		(layer "F.Cu")
		(net "HDD_PRSNT_NET10")
	)
	(segment
		(start 31.151068 -432.877722)
		(end 31.151068 -433.554378)
		(width 0.111252)
		(layer "F.Cu")
		(net "HDD_PRSNT_NET10")
	)
	(segment
		(start 38.7604 -426.212)
		(end 38.768782 -426.203618)
		(width 0.111252)
		(layer "F.Cu")
		(net "HDD_PRSNT_NET10")
	)
	(segment
		(start 26.796746 -432.463702)
		(end 26.669746 -432.336702)
		(width 0.111252)
		(layer "F.Cu")
		(net "HDD_PRSNT_NET10")
	)
	(segment
		(start 26.304748 -432.336702)
		(end 26.669746 -432.336702)
		(width 0.111252)
		(layer "F.Cu")
		(net "HDD_PRSNT_NET10")
	)
	(segment
		(start 29.311346 -433.9463)
		(end 28.955746 -433.5907)
		(width 0.111252)
		(layer "F.Cu")
		(net "HDD_PRSNT_NET10")
	)
	(segment
		(start 31.151068 -433.554378)
		(end 30.860746 -433.8447)
		(width 0.111252)
		(layer "F.Cu")
		(net "HDD_PRSNT_NET10")
	)
	(segment
		(start 30.759146 -433.9463)
		(end 29.311346 -433.9463)
		(width 0.111252)
		(layer "F.Cu")
		(net "HDD_PRSNT_NET10")
	)
	(via
		(at 30.860746 -433.8447)
		(size 0.7112)
		(drill 0.3556)
		(layers "F.Cu" "B.Cu")
		(net "HDD_PRSNT_NET10")
	)
	(via
		(at 31.151068 -432.877722)
		(size 0.5588)
		(drill 0.3048)
		(layers "F.Cu" "B.Cu")
		(net "HDD_PRSNT_NET10")
	)
	(via
		(at 38.768782 -426.203618)
		(size 0.5588)
		(drill 0.3048)
		(layers "F.Cu" "B.Cu")
		(net "HDD_PRSNT_NET10")
	)
	(segment
		(start 38.768782 -426.203618)
		(end 37.549582 -426.203618)
		(width 0.14605)
		(layer "In2.Cu")
		(net "HDD_PRSNT_NET10")
	)
	(segment
		(start 37.549582 -426.203618)
		(end 31.151068 -432.602132)
		(width 0.14605)
		(layer "In2.Cu")
		(net "HDD_PRSNT_NET10")
	)
	(segment
		(start 31.151068 -432.602132)
		(end 31.151068 -432.877722)
		(width 0.14605)
		(layer "In2.Cu")
		(net "HDD_PRSNT_NET10")
	)
	(segment
		(start 6.1214 -162.160458)
		(end 5.47116 -162.160458)
		(width 0.09525)
		(layer "F.Cu")
		(net "SAS2X28_B_HDD10_TX_-")
	)
	(segment
		(start 21.640546 -444.2333)
		(end 21.640546 -444.207392)
		(width 0.09525)
		(layer "F.Cu")
		(net "SAS2X28_B_HDD10_TX_-")
	)
	(segment
		(start 4.650486 -162.50031)
		(end 4.648962 -162.498786)
		(width 0.09525)
		(layer "F.Cu")
		(net "SAS2X28_B_HDD10_TX_-")
	)
	(segment
		(start 20.952968 -444.5127)
		(end 21.208746 -444.5127)
		(width 0.09525)
		(layer "F.Cu")
		(net "SAS2X28_B_HDD10_TX_-")
	)
	(segment
		(start 4.648962 -162.498786)
		(end 3.192526 -162.498786)
		(width 0.09525)
		(layer "F.Cu")
		(net "SAS2X28_B_HDD10_TX_-")
	)
	(segment
		(start 20.648422 -444.346838)
		(end 20.715732 -444.414402)
		(width 0.09525)
		(layer "F.Cu")
		(net "SAS2X28_B_HDD10_TX_-")
	)
	(segment
		(start 6.748272 -162.459416)
		(end 6.681216 -162.39236)
		(width 0.09525)
		(layer "F.Cu")
		(net "SAS2X28_B_HDD10_TX_-")
	)
	(segment
		(start 19.600164 -444.210186)
		(end 20.3073 -444.210186)
		(width 0.09525)
		(layer "F.Cu")
		(net "SAS2X28_B_HDD10_TX_-")
	)
	(segment
		(start 21.5392 -444.375794)
		(end 21.611336 -444.303658)
		(width 0.09525)
		(layer "F.Cu")
		(net "SAS2X28_B_HDD10_TX_-")
	)
	(segment
		(start 20.3073 -444.210186)
		(end 20.310602 -444.206884)
		(width 0.09525)
		(layer "F.Cu")
		(net "SAS2X28_B_HDD10_TX_-")
	)
	(via
		(at 21.639276 -444.207392)
		(size 0.5588)
		(drill 0.3048)
		(layers "F.Cu" "B.Cu")
		(net "SAS2X28_B_HDD10_TX_-")
	)
	(via
		(at 6.748272 -162.459416)
		(size 0.5588)
		(drill 0.3048)
		(layers "F.Cu" "B.Cu")
		(net "SAS2X28_B_HDD10_TX_-")
	)
	(arc
		(start 20.310602 -444.206884)
		(mid 20.493438 -444.243252)
		(end 20.648422 -444.346838)
		(width 0.09525)
		(layer "F.Cu")
		(net "SAS2X28_B_HDD10_TX_-")
	)
	(arc
		(start 5.47116 -162.160458)
		(mid 5.320789 -162.190369)
		(end 5.193284 -162.27552)
		(width 0.09525)
		(layer "F.Cu")
		(net "SAS2X28_B_HDD10_TX_-")
	)
	(arc
		(start 21.611336 -444.303658)
		(mid 21.632959 -444.271392)
		(end 21.640546 -444.2333)
		(width 0.09525)
		(layer "F.Cu")
		(net "SAS2X28_B_HDD10_TX_-")
	)
	(arc
		(start 5.193284 -162.27552)
		(mid 4.944246 -162.441922)
		(end 4.650486 -162.50031)
		(width 0.09525)
		(layer "F.Cu")
		(net "SAS2X28_B_HDD10_TX_-")
	)
	(arc
		(start 6.681216 -162.39236)
		(mid 6.42437 -162.220741)
		(end 6.1214 -162.160458)
		(width 0.09525)
		(layer "F.Cu")
		(net "SAS2X28_B_HDD10_TX_-")
	)
	(arc
		(start 20.715732 -444.414402)
		(mid 20.824577 -444.48713)
		(end 20.952968 -444.5127)
		(width 0.09525)
		(layer "F.Cu")
		(net "SAS2X28_B_HDD10_TX_-")
	)
	(arc
		(start 21.640546 -444.207392)
		(mid 21.639911 -444.207387)
		(end 21.639276 -444.207392)
		(width 0.09525)
		(layer "F.Cu")
		(net "SAS2X28_B_HDD10_TX_-")
	)
	(arc
		(start 21.208746 -444.5127)
		(mid 21.387597 -444.477124)
		(end 21.5392 -444.375794)
		(width 0.09525)
		(layer "F.Cu")
		(net "SAS2X28_B_HDD10_TX_-")
	)
	(segment
		(start 33.531556 -195.697348)
		(end 33.531556 -190.207646)
		(width 0.09525)
		(layer "B.Cu")
		(net "SAS2X28_B_HDD10_TX_-")
	)
	(segment
		(start 24.701246 -435.638956)
		(end 24.701246 -435.353206)
		(width 0.09525)
		(layer "B.Cu")
		(net "SAS2X28_B_HDD10_TX_-")
	)
	(segment
		(start 31.25343 -356.10673)
		(end 38.67023 -348.68993)
		(width 0.09525)
		(layer "B.Cu")
		(net "SAS2X28_B_HDD10_TX_-")
	)
	(segment
		(start 26.986992 -371.297454)
		(end 30.251146 -368.0333)
		(width 0.09525)
		(layer "B.Cu")
		(net "SAS2X28_B_HDD10_TX_-")
	)
	(segment
		(start 23.488904 -444.125096)
		(end 24.515318 -443.098682)
		(width 0.09525)
		(layer "B.Cu")
		(net "SAS2X28_B_HDD10_TX_-")
	)
	(segment
		(start 22.069806 -444.3857)
		(end 22.859746 -444.3857)
		(width 0.09525)
		(layer "B.Cu")
		(net "SAS2X28_B_HDD10_TX_-")
	)
	(segment
		(start 15.430246 -171.9072)
		(end 15.4305 -171.906946)
		(width 0.09525)
		(layer "B.Cu")
		(net "SAS2X28_B_HDD10_TX_-")
	)
	(segment
		(start 44.331382 -206.988664)
		(end 33.879028 -196.53631)
		(width 0.09525)
		(layer "B.Cu")
		(net "SAS2X28_B_HDD10_TX_-")
	)
	(segment
		(start 25.15235 -429.30445)
		(end 26.218896 -428.237904)
		(width 0.09525)
		(layer "B.Cu")
		(net "SAS2X28_B_HDD10_TX_-")
	)
	(segment
		(start 26.415746 -398.510252)
		(end 26.415746 -372.676674)
		(width 0.09525)
		(layer "B.Cu")
		(net "SAS2X28_B_HDD10_TX_-")
	)
	(segment
		(start 26.183336 -400.761962)
		(end 26.183336 -400.476212)
		(width 0.09525)
		(layer "B.Cu")
		(net "SAS2X28_B_HDD10_TX_-")
	)
	(segment
		(start 14.782546 -170.34256)
		(end 14.782546 -163.672266)
		(width 0.09525)
		(layer "B.Cu")
		(net "SAS2X28_B_HDD10_TX_-")
	)
	(segment
		(start 38.785546 -348.4118)
		(end 38.785546 -304.16881)
		(width 0.09525)
		(layer "B.Cu")
		(net "SAS2X28_B_HDD10_TX_-")
	)
	(segment
		(start 26.415746 -400.011392)
		(end 26.415746 -399.725642)
		(width 0.09525)
		(layer "B.Cu")
		(net "SAS2X28_B_HDD10_TX_-")
	)
	(segment
		(start 24.701246 -440.142376)
		(end 24.701246 -439.856626)
		(width 0.09525)
		(layer "B.Cu")
		(net "SAS2X28_B_HDD10_TX_-")
	)
	(segment
		(start 33.146746 -189.6237)
		(end 15.430246 -171.9072)
		(width 0.09525)
		(layer "B.Cu")
		(net "SAS2X28_B_HDD10_TX_-")
	)
	(segment
		(start 24.468836 -434.888386)
		(end 24.468836 -434.602636)
		(width 0.09525)
		(layer "B.Cu")
		(net "SAS2X28_B_HDD10_TX_-")
	)
	(segment
		(start 24.468836 -437.890666)
		(end 24.468836 -437.604916)
		(width 0.09525)
		(layer "B.Cu")
		(net "SAS2X28_B_HDD10_TX_-")
	)
	(segment
		(start 33.39084 -189.86754)
		(end 33.146746 -189.6237)
		(width 0.09525)
		(layer "B.Cu")
		(net "SAS2X28_B_HDD10_TX_-")
	)
	(segment
		(start 24.701246 -442.64961)
		(end 24.701246 -441.357766)
		(width 0.09525)
		(layer "B.Cu")
		(net "SAS2X28_B_HDD10_TX_-")
	)
	(segment
		(start 13.1191 -162.160458)
		(end 7.47014 -162.160458)
		(width 0.09525)
		(layer "B.Cu")
		(net "SAS2X28_B_HDD10_TX_-")
	)
	(segment
		(start 39.244016 -303.061878)
		(end 44.489116 -297.816778)
		(width 0.09525)
		(layer "B.Cu")
		(net "SAS2X28_B_HDD10_TX_-")
	)
	(segment
		(start 26.415746 -427.762924)
		(end 26.415746 -401.226782)
		(width 0.09525)
		(layer "B.Cu")
		(net "SAS2X28_B_HDD10_TX_-")
	)
	(segment
		(start 30.822646 -366.653572)
		(end 30.822646 -357.14686)
		(width 0.09525)
		(layer "B.Cu")
		(net "SAS2X28_B_HDD10_TX_-")
	)
	(segment
		(start 38.785292 -348.411546)
		(end 38.785546 -348.4118)
		(width 0.09525)
		(layer "B.Cu")
		(net "SAS2X28_B_HDD10_TX_-")
	)
	(segment
		(start 26.183336 -399.260822)
		(end 26.183336 -398.975072)
		(width 0.09525)
		(layer "B.Cu")
		(net "SAS2X28_B_HDD10_TX_-")
	)
	(segment
		(start 44.703746 -297.298872)
		(end 44.703746 -207.88757)
		(width 0.09525)
		(layer "B.Cu")
		(net "SAS2X28_B_HDD10_TX_-")
	)
	(segment
		(start 24.468836 -440.892946)
		(end 24.468836 -440.607196)
		(width 0.09525)
		(layer "B.Cu")
		(net "SAS2X28_B_HDD10_TX_-")
	)
	(segment
		(start 24.701246 -434.137816)
		(end 24.701246 -430.393602)
		(width 0.09525)
		(layer "B.Cu")
		(net "SAS2X28_B_HDD10_TX_-")
	)
	(segment
		(start 24.468836 -439.391806)
		(end 24.468836 -439.106056)
		(width 0.09525)
		(layer "B.Cu")
		(net "SAS2X28_B_HDD10_TX_-")
	)
	(segment
		(start 24.701246 -438.641236)
		(end 24.701246 -438.355486)
		(width 0.09525)
		(layer "B.Cu")
		(net "SAS2X28_B_HDD10_TX_-")
	)
	(segment
		(start 24.701246 -437.140096)
		(end 24.701246 -436.854346)
		(width 0.09525)
		(layer "B.Cu")
		(net "SAS2X28_B_HDD10_TX_-")
	)
	(segment
		(start 24.468836 -436.389526)
		(end 24.468836 -436.103776)
		(width 0.09525)
		(layer "B.Cu")
		(net "SAS2X28_B_HDD10_TX_-")
	)
	(arc
		(start 26.218896 -428.237904)
		(mid 26.364615 -428.02001)
		(end 26.415746 -427.762924)
		(width 0.09525)
		(layer "B.Cu")
		(net "SAS2X28_B_HDD10_TX_-")
	)
	(arc
		(start 24.701246 -430.393602)
		(mid 24.818423 -429.804132)
		(end 25.15235 -429.30445)
		(width 0.09525)
		(layer "B.Cu")
		(net "SAS2X28_B_HDD10_TX_-")
	)
	(arc
		(start 24.701246 -439.856626)
		(mid 24.671449 -439.726308)
		(end 24.585168 -439.624216)
		(width 0.09525)
		(layer "B.Cu")
		(net "SAS2X28_B_HDD10_TX_-")
	)
	(arc
		(start 24.515318 -443.098682)
		(mid 24.652987 -442.892646)
		(end 24.701246 -442.64961)
		(width 0.09525)
		(layer "B.Cu")
		(net "SAS2X28_B_HDD10_TX_-")
	)
	(arc
		(start 26.299668 -400.994372)
		(mid 26.213269 -400.892298)
		(end 26.183336 -400.761962)
		(width 0.09525)
		(layer "B.Cu")
		(net "SAS2X28_B_HDD10_TX_-")
	)
	(arc
		(start 21.639276 -444.207392)
		(mid 21.836805 -444.339377)
		(end 22.069806 -444.3857)
		(width 0.09525)
		(layer "B.Cu")
		(net "SAS2X28_B_HDD10_TX_-")
	)
	(arc
		(start 14.782546 -163.672266)
		(mid 14.675532 -163.134921)
		(end 14.371066 -162.67938)
		(width 0.09525)
		(layer "B.Cu")
		(net "SAS2X28_B_HDD10_TX_-")
	)
	(arc
		(start 24.468836 -437.604916)
		(mid 24.498772 -437.474581)
		(end 24.585168 -437.372506)
		(width 0.09525)
		(layer "B.Cu")
		(net "SAS2X28_B_HDD10_TX_-")
	)
	(arc
		(start 44.703746 -207.88757)
		(mid 44.606976 -207.401076)
		(end 44.331382 -206.988664)
		(width 0.09525)
		(layer "B.Cu")
		(net "SAS2X28_B_HDD10_TX_-")
	)
	(arc
		(start 26.299668 -398.742662)
		(mid 26.385899 -398.640545)
		(end 26.415746 -398.510252)
		(width 0.09525)
		(layer "B.Cu")
		(net "SAS2X28_B_HDD10_TX_-")
	)
	(arc
		(start 24.585168 -436.621936)
		(mid 24.498769 -436.519862)
		(end 24.468836 -436.389526)
		(width 0.09525)
		(layer "B.Cu")
		(net "SAS2X28_B_HDD10_TX_-")
	)
	(arc
		(start 24.585168 -440.374786)
		(mid 24.671399 -440.272669)
		(end 24.701246 -440.142376)
		(width 0.09525)
		(layer "B.Cu")
		(net "SAS2X28_B_HDD10_TX_-")
	)
	(arc
		(start 24.468836 -436.103776)
		(mid 24.498772 -435.973441)
		(end 24.585168 -435.871366)
		(width 0.09525)
		(layer "B.Cu")
		(net "SAS2X28_B_HDD10_TX_-")
	)
	(arc
		(start 26.299668 -400.243802)
		(mid 26.385899 -400.141685)
		(end 26.415746 -400.011392)
		(width 0.09525)
		(layer "B.Cu")
		(net "SAS2X28_B_HDD10_TX_-")
	)
	(arc
		(start 30.251146 -368.0333)
		(mid 30.674066 -367.400261)
		(end 30.822646 -366.653572)
		(width 0.09525)
		(layer "B.Cu")
		(net "SAS2X28_B_HDD10_TX_-")
	)
	(arc
		(start 14.371066 -162.67938)
		(mid 13.796689 -162.295408)
		(end 13.1191 -162.160458)
		(width 0.09525)
		(layer "B.Cu")
		(net "SAS2X28_B_HDD10_TX_-")
	)
	(arc
		(start 22.859746 -444.3857)
		(mid 23.200243 -444.317971)
		(end 23.488904 -444.125096)
		(width 0.09525)
		(layer "B.Cu")
		(net "SAS2X28_B_HDD10_TX_-")
	)
	(arc
		(start 24.585168 -435.871366)
		(mid 24.671399 -435.769249)
		(end 24.701246 -435.638956)
		(width 0.09525)
		(layer "B.Cu")
		(net "SAS2X28_B_HDD10_TX_-")
	)
	(arc
		(start 38.785546 -304.16881)
		(mid 38.904758 -303.569782)
		(end 39.244016 -303.061878)
		(width 0.09525)
		(layer "B.Cu")
		(net "SAS2X28_B_HDD10_TX_-")
	)
	(arc
		(start 26.415746 -401.226782)
		(mid 26.385949 -401.096464)
		(end 26.299668 -400.994372)
		(width 0.09525)
		(layer "B.Cu")
		(net "SAS2X28_B_HDD10_TX_-")
	)
	(arc
		(start 33.531556 -190.207646)
		(mid 33.495039 -190.02359)
		(end 33.39084 -189.86754)
		(width 0.09525)
		(layer "B.Cu")
		(net "SAS2X28_B_HDD10_TX_-")
	)
	(arc
		(start 26.415746 -399.725642)
		(mid 26.385949 -399.595324)
		(end 26.299668 -399.493232)
		(width 0.09525)
		(layer "B.Cu")
		(net "SAS2X28_B_HDD10_TX_-")
	)
	(arc
		(start 44.489116 -297.816778)
		(mid 44.647994 -297.579189)
		(end 44.703746 -297.298872)
		(width 0.09525)
		(layer "B.Cu")
		(net "SAS2X28_B_HDD10_TX_-")
	)
	(arc
		(start 24.468836 -439.106056)
		(mid 24.498772 -438.975721)
		(end 24.585168 -438.873646)
		(width 0.09525)
		(layer "B.Cu")
		(net "SAS2X28_B_HDD10_TX_-")
	)
	(arc
		(start 24.585168 -438.123076)
		(mid 24.498769 -438.021002)
		(end 24.468836 -437.890666)
		(width 0.09525)
		(layer "B.Cu")
		(net "SAS2X28_B_HDD10_TX_-")
	)
	(arc
		(start 24.701246 -441.357766)
		(mid 24.671449 -441.227448)
		(end 24.585168 -441.125356)
		(width 0.09525)
		(layer "B.Cu")
		(net "SAS2X28_B_HDD10_TX_-")
	)
	(arc
		(start 7.47014 -162.160458)
		(mid 7.079487 -162.238164)
		(end 6.748272 -162.459416)
		(width 0.09525)
		(layer "B.Cu")
		(net "SAS2X28_B_HDD10_TX_-")
	)
	(arc
		(start 15.4305 -171.906946)
		(mid 14.950946 -171.189199)
		(end 14.782546 -170.34256)
		(width 0.09525)
		(layer "B.Cu")
		(net "SAS2X28_B_HDD10_TX_-")
	)
	(arc
		(start 24.585168 -438.873646)
		(mid 24.671399 -438.771529)
		(end 24.701246 -438.641236)
		(width 0.09525)
		(layer "B.Cu")
		(net "SAS2X28_B_HDD10_TX_-")
	)
	(arc
		(start 24.701246 -435.353206)
		(mid 24.671449 -435.222888)
		(end 24.585168 -435.120796)
		(width 0.09525)
		(layer "B.Cu")
		(net "SAS2X28_B_HDD10_TX_-")
	)
	(arc
		(start 33.879028 -196.53631)
		(mid 33.621858 -196.151378)
		(end 33.531556 -195.697348)
		(width 0.09525)
		(layer "B.Cu")
		(net "SAS2X28_B_HDD10_TX_-")
	)
	(arc
		(start 24.585168 -439.624216)
		(mid 24.498769 -439.522142)
		(end 24.468836 -439.391806)
		(width 0.09525)
		(layer "B.Cu")
		(net "SAS2X28_B_HDD10_TX_-")
	)
	(arc
		(start 24.585168 -434.370226)
		(mid 24.671399 -434.268109)
		(end 24.701246 -434.137816)
		(width 0.09525)
		(layer "B.Cu")
		(net "SAS2X28_B_HDD10_TX_-")
	)
	(arc
		(start 24.701246 -438.355486)
		(mid 24.671449 -438.225168)
		(end 24.585168 -438.123076)
		(width 0.09525)
		(layer "B.Cu")
		(net "SAS2X28_B_HDD10_TX_-")
	)
	(arc
		(start 30.822646 -357.14686)
		(mid 30.934545 -356.583926)
		(end 31.25343 -356.10673)
		(width 0.09525)
		(layer "B.Cu")
		(net "SAS2X28_B_HDD10_TX_-")
	)
	(arc
		(start 38.67023 -348.68993)
		(mid 38.755382 -348.562163)
		(end 38.785292 -348.411546)
		(width 0.09525)
		(layer "B.Cu")
		(net "SAS2X28_B_HDD10_TX_-")
	)
	(arc
		(start 24.701246 -436.854346)
		(mid 24.671449 -436.724028)
		(end 24.585168 -436.621936)
		(width 0.09525)
		(layer "B.Cu")
		(net "SAS2X28_B_HDD10_TX_-")
	)
	(arc
		(start 26.299668 -399.493232)
		(mid 26.213269 -399.391158)
		(end 26.183336 -399.260822)
		(width 0.09525)
		(layer "B.Cu")
		(net "SAS2X28_B_HDD10_TX_-")
	)
	(arc
		(start 26.183336 -398.975072)
		(mid 26.213272 -398.844737)
		(end 26.299668 -398.742662)
		(width 0.09525)
		(layer "B.Cu")
		(net "SAS2X28_B_HDD10_TX_-")
	)
	(arc
		(start 26.183336 -400.476212)
		(mid 26.213272 -400.345877)
		(end 26.299668 -400.243802)
		(width 0.09525)
		(layer "B.Cu")
		(net "SAS2X28_B_HDD10_TX_-")
	)
	(arc
		(start 24.468836 -440.607196)
		(mid 24.498772 -440.476861)
		(end 24.585168 -440.374786)
		(width 0.09525)
		(layer "B.Cu")
		(net "SAS2X28_B_HDD10_TX_-")
	)
	(arc
		(start 26.415746 -372.676674)
		(mid 26.564269 -371.930288)
		(end 26.986992 -371.297454)
		(width 0.09525)
		(layer "B.Cu")
		(net "SAS2X28_B_HDD10_TX_-")
	)
	(arc
		(start 24.585168 -441.125356)
		(mid 24.498769 -441.023282)
		(end 24.468836 -440.892946)
		(width 0.09525)
		(layer "B.Cu")
		(net "SAS2X28_B_HDD10_TX_-")
	)
	(arc
		(start 24.585168 -437.372506)
		(mid 24.671399 -437.270389)
		(end 24.701246 -437.140096)
		(width 0.09525)
		(layer "B.Cu")
		(net "SAS2X28_B_HDD10_TX_-")
	)
	(arc
		(start 24.468836 -434.602636)
		(mid 24.498772 -434.472301)
		(end 24.585168 -434.370226)
		(width 0.09525)
		(layer "B.Cu")
		(net "SAS2X28_B_HDD10_TX_-")
	)
	(arc
		(start 24.585168 -435.120796)
		(mid 24.498769 -435.018722)
		(end 24.468836 -434.888386)
		(width 0.09525)
		(layer "B.Cu")
		(net "SAS2X28_B_HDD10_TX_-")
	)
	(via
		(at 218.566746 -175.5267)
		(size 0.7112)
		(drill 0.3556)
		(layers "F.Cu" "B.Cu")
		(net "5V_PRE_3")
	)
	(segment
		(start 38.255194 -70.844918)
		(end 38.250114 -70.849998)
		(width 0.111252)
		(layer "F.Cu")
		(net "HDD_PRSNT_NET9")
	)
	(segment
		(start 54.021736 -72.990456)
		(end 55.117492 -72.990456)
		(width 0.111252)
		(layer "F.Cu")
		(net "HDD_PRSNT_NET9")
	)
	(segment
		(start 56.196992 -72.990456)
		(end 56.260492 -72.926956)
		(width 0.111252)
		(layer "F.Cu")
		(net "HDD_PRSNT_NET9")
	)
	(segment
		(start 55.117492 -72.990456)
		(end 56.196992 -72.990456)
		(width 0.111252)
		(layer "F.Cu")
		(net "HDD_PRSNT_NET9")
	)
	(segment
		(start 54.0004 -73.011792)
		(end 54.021736 -72.990456)
		(width 0.111252)
		(layer "F.Cu")
		(net "HDD_PRSNT_NET9")
	)
	(segment
		(start 57.466992 -72.926956)
		(end 57.466992 -72.492108)
		(width 0.111252)
		(layer "F.Cu")
		(net "HDD_PRSNT_NET9")
	)
	(segment
		(start 57.466992 -72.492108)
		(end 58.0771 -71.882)
		(width 0.111252)
		(layer "F.Cu")
		(net "HDD_PRSNT_NET9")
	)
	(segment
		(start 56.260492 -72.926956)
		(end 57.466992 -72.926956)
		(width 0.111252)
		(layer "F.Cu")
		(net "HDD_PRSNT_NET9")
	)
	(segment
		(start 53.994812 -73.011792)
		(end 54.0004 -73.011792)
		(width 0.111252)
		(layer "F.Cu")
		(net "HDD_PRSNT_NET9")
	)
	(segment
		(start 53.994812 -73.011792)
		(end 53.973476 -72.990456)
		(width 0.111252)
		(layer "F.Cu")
		(net "HDD_PRSNT_NET9")
	)
	(segment
		(start 53.973476 -72.990456)
		(end 52.714398 -72.990456)
		(width 0.111252)
		(layer "F.Cu")
		(net "HDD_PRSNT_NET9")
	)
	(segment
		(start 50.56886 -70.844918)
		(end 38.255194 -70.844918)
		(width 0.111252)
		(layer "F.Cu")
		(net "HDD_PRSNT_NET9")
	)
	(via
		(at 53.994812 -73.011792)
		(size 0.7112)
		(drill 0.3556)
		(layers "F.Cu" "B.Cu")
		(net "HDD_PRSNT_NET9")
	)
	(arc
		(start 52.714398 -72.990456)
		(mid 51.955746 -72.676212)
		(end 51.641502 -71.91756)
		(width 0.111252)
		(layer "F.Cu")
		(net "HDD_PRSNT_NET9")
	)
	(arc
		(start 51.641502 -71.91756)
		(mid 51.327332 -71.159088)
		(end 50.56886 -70.844918)
		(width 0.111252)
		(layer "F.Cu")
		(net "HDD_PRSNT_NET9")
	)
	(segment
		(start 20.503896 -445.010032)
		(end 20.507198 -445.00673)
		(width 0.09525)
		(layer "F.Cu")
		(net "SAS2X28_B_HDD10_TX_+")
	)
	(segment
		(start 20.954492 -444.8429)
		(end 21.12772 -444.8429)
		(width 0.09525)
		(layer "F.Cu")
		(net "SAS2X28_B_HDD10_TX_+")
	)
	(segment
		(start 6.748272 -161.5313)
		(end 6.681216 -161.598356)
		(width 0.09525)
		(layer "F.Cu")
		(net "SAS2X28_B_HDD10_TX_+")
	)
	(segment
		(start 4.667504 -161.500312)
		(end 4.66598 -161.498788)
		(width 0.09525)
		(layer "F.Cu")
		(net "SAS2X28_B_HDD10_TX_+")
	)
	(segment
		(start 4.66598 -161.498788)
		(end 3.192526 -161.498788)
		(width 0.09525)
		(layer "F.Cu")
		(net "SAS2X28_B_HDD10_TX_+")
	)
	(segment
		(start 19.600164 -445.010032)
		(end 20.503896 -445.010032)
		(width 0.09525)
		(layer "F.Cu")
		(net "SAS2X28_B_HDD10_TX_+")
	)
	(segment
		(start 6.1214 -161.830258)
		(end 5.464048 -161.830258)
		(width 0.09525)
		(layer "F.Cu")
		(net "SAS2X28_B_HDD10_TX_+")
	)
	(segment
		(start 20.752054 -444.945516)
		(end 20.784566 -444.913004)
		(width 0.09525)
		(layer "F.Cu")
		(net "SAS2X28_B_HDD10_TX_+")
	)
	(via
		(at 21.676614 -445.07023)
		(size 0.5588)
		(drill 0.3048)
		(layers "F.Cu" "B.Cu")
		(net "SAS2X28_B_HDD10_TX_+")
	)
	(via
		(at 6.748272 -161.5313)
		(size 0.5588)
		(drill 0.3048)
		(layers "F.Cu" "B.Cu")
		(net "SAS2X28_B_HDD10_TX_+")
	)
	(arc
		(start 5.19303 -161.71799)
		(mid 4.951917 -161.556883)
		(end 4.667504 -161.500312)
		(width 0.09525)
		(layer "F.Cu")
		(net "SAS2X28_B_HDD10_TX_+")
	)
	(arc
		(start 6.681216 -161.598356)
		(mid 6.42437 -161.769975)
		(end 6.1214 -161.830258)
		(width 0.09525)
		(layer "F.Cu")
		(net "SAS2X28_B_HDD10_TX_+")
	)
	(arc
		(start 5.464048 -161.830258)
		(mid 5.317371 -161.801082)
		(end 5.19303 -161.71799)
		(width 0.09525)
		(layer "F.Cu")
		(net "SAS2X28_B_HDD10_TX_+")
	)
	(arc
		(start 20.820888 -444.883286)
		(mid 20.884701 -444.8532)
		(end 20.954492 -444.8429)
		(width 0.09525)
		(layer "F.Cu")
		(net "SAS2X28_B_HDD10_TX_+")
	)
	(arc
		(start 21.12772 -444.8429)
		(mid 21.199656 -444.84617)
		(end 21.270976 -444.856108)
		(width 0.09525)
		(layer "F.Cu")
		(net "SAS2X28_B_HDD10_TX_+")
	)
	(arc
		(start 20.784566 -444.913004)
		(mid 20.801998 -444.897254)
		(end 20.820888 -444.883286)
		(width 0.09525)
		(layer "F.Cu")
		(net "SAS2X28_B_HDD10_TX_+")
	)
	(arc
		(start 20.507198 -445.00673)
		(mid 20.633403 -444.991228)
		(end 20.752054 -444.945516)
		(width 0.09525)
		(layer "F.Cu")
		(net "SAS2X28_B_HDD10_TX_+")
	)
	(arc
		(start 21.270976 -444.856108)
		(mid 21.489999 -444.932487)
		(end 21.676614 -445.07023)
		(width 0.09525)
		(layer "F.Cu")
		(net "SAS2X28_B_HDD10_TX_+")
	)
	(segment
		(start 33.861756 -190.207646)
		(end 33.861756 -195.697094)
		(width 0.09525)
		(layer "B.Cu")
		(net "SAS2X28_B_HDD10_TX_+")
	)
	(segment
		(start 22.859746 -444.7159)
		(end 22.275546 -444.7159)
		(width 0.09525)
		(layer "B.Cu")
		(net "SAS2X28_B_HDD10_TX_+")
	)
	(segment
		(start 7.47014 -161.830258)
		(end 13.118846 -161.830258)
		(width 0.09525)
		(layer "B.Cu")
		(net "SAS2X28_B_HDD10_TX_+")
	)
	(segment
		(start 44.722796 -298.050204)
		(end 39.477696 -303.295304)
		(width 0.09525)
		(layer "B.Cu")
		(net "SAS2X28_B_HDD10_TX_+")
	)
	(segment
		(start 45.033946 -207.887316)
		(end 45.033946 -297.299126)
		(width 0.09525)
		(layer "B.Cu")
		(net "SAS2X28_B_HDD10_TX_+")
	)
	(segment
		(start 33.380426 -189.39002)
		(end 33.62452 -189.63386)
		(width 0.09525)
		(layer "B.Cu")
		(net "SAS2X28_B_HDD10_TX_+")
	)
	(segment
		(start 15.663926 -171.67352)
		(end 33.380426 -189.39002)
		(width 0.09525)
		(layer "B.Cu")
		(net "SAS2X28_B_HDD10_TX_+")
	)
	(segment
		(start 38.903656 -348.92361)
		(end 31.486856 -356.34041)
		(width 0.09525)
		(layer "B.Cu")
		(net "SAS2X28_B_HDD10_TX_+")
	)
	(segment
		(start 31.152846 -357.14686)
		(end 31.152846 -366.653572)
		(width 0.09525)
		(layer "B.Cu")
		(net "SAS2X28_B_HDD10_TX_+")
	)
	(segment
		(start 21.858224 -444.88862)
		(end 21.676614 -445.07023)
		(width 0.09525)
		(layer "B.Cu")
		(net "SAS2X28_B_HDD10_TX_+")
	)
	(segment
		(start 30.484572 -368.26698)
		(end 27.220672 -371.53088)
		(width 0.09525)
		(layer "B.Cu")
		(net "SAS2X28_B_HDD10_TX_+")
	)
	(segment
		(start 34.112708 -196.302884)
		(end 44.565062 -206.755238)
		(width 0.09525)
		(layer "B.Cu")
		(net "SAS2X28_B_HDD10_TX_+")
	)
	(segment
		(start 15.112746 -163.672012)
		(end 15.112746 -170.342814)
		(width 0.09525)
		(layer "B.Cu")
		(net "SAS2X28_B_HDD10_TX_+")
	)
	(segment
		(start 25.031446 -430.393602)
		(end 25.031446 -442.650118)
		(width 0.09525)
		(layer "B.Cu")
		(net "SAS2X28_B_HDD10_TX_+")
	)
	(segment
		(start 26.745946 -372.676928)
		(end 26.745946 -427.763178)
		(width 0.09525)
		(layer "B.Cu")
		(net "SAS2X28_B_HDD10_TX_+")
	)
	(segment
		(start 24.748744 -443.332616)
		(end 23.722584 -444.358776)
		(width 0.09525)
		(layer "B.Cu")
		(net "SAS2X28_B_HDD10_TX_+")
	)
	(segment
		(start 26.452576 -428.47133)
		(end 25.385776 -429.53813)
		(width 0.09525)
		(layer "B.Cu")
		(net "SAS2X28_B_HDD10_TX_+")
	)
	(segment
		(start 39.115746 -304.169064)
		(end 39.115746 -348.411546)
		(width 0.09525)
		(layer "B.Cu")
		(net "SAS2X28_B_HDD10_TX_+")
	)
	(arc
		(start 39.115746 -348.411546)
		(mid 39.060623 -348.688668)
		(end 38.903656 -348.92361)
		(width 0.09525)
		(layer "B.Cu")
		(net "SAS2X28_B_HDD10_TX_+")
	)
	(arc
		(start 14.604746 -162.4457)
		(mid 14.980688 -163.008337)
		(end 15.112746 -163.672012)
		(width 0.09525)
		(layer "B.Cu")
		(net "SAS2X28_B_HDD10_TX_+")
	)
	(arc
		(start 45.033946 -297.299126)
		(mid 44.953089 -297.705623)
		(end 44.722796 -298.050204)
		(width 0.09525)
		(layer "B.Cu")
		(net "SAS2X28_B_HDD10_TX_+")
	)
	(arc
		(start 22.275546 -444.7159)
		(mid 22.219285 -444.718562)
		(end 22.163532 -444.726568)
		(width 0.09525)
		(layer "B.Cu")
		(net "SAS2X28_B_HDD10_TX_+")
	)
	(arc
		(start 44.565062 -206.755238)
		(mid 44.912091 -207.274653)
		(end 45.033946 -207.887316)
		(width 0.09525)
		(layer "B.Cu")
		(net "SAS2X28_B_HDD10_TX_+")
	)
	(arc
		(start 15.112746 -170.342814)
		(mid 15.255996 -171.062981)
		(end 15.663926 -171.67352)
		(width 0.09525)
		(layer "B.Cu")
		(net "SAS2X28_B_HDD10_TX_+")
	)
	(arc
		(start 22.163532 -444.726568)
		(mid 21.99872 -444.784696)
		(end 21.858224 -444.88862)
		(width 0.09525)
		(layer "B.Cu")
		(net "SAS2X28_B_HDD10_TX_+")
	)
	(arc
		(start 33.861756 -195.697094)
		(mid 33.926972 -196.024955)
		(end 34.112708 -196.302884)
		(width 0.09525)
		(layer "B.Cu")
		(net "SAS2X28_B_HDD10_TX_+")
	)
	(arc
		(start 33.62452 -189.63386)
		(mid 33.800202 -189.89716)
		(end 33.861756 -190.207646)
		(width 0.09525)
		(layer "B.Cu")
		(net "SAS2X28_B_HDD10_TX_+")
	)
	(arc
		(start 13.118846 -161.830258)
		(mid 13.922995 -161.990213)
		(end 14.604746 -162.4457)
		(width 0.09525)
		(layer "B.Cu")
		(net "SAS2X28_B_HDD10_TX_+")
	)
	(arc
		(start 6.748272 -161.5313)
		(mid 7.079468 -161.752598)
		(end 7.47014 -161.830258)
		(width 0.09525)
		(layer "B.Cu")
		(net "SAS2X28_B_HDD10_TX_+")
	)
	(arc
		(start 31.486856 -356.34041)
		(mid 31.239628 -356.710412)
		(end 31.152846 -357.14686)
		(width 0.09525)
		(layer "B.Cu")
		(net "SAS2X28_B_HDD10_TX_+")
	)
	(arc
		(start 27.220672 -371.53088)
		(mid 26.869336 -372.056691)
		(end 26.745946 -372.676928)
		(width 0.09525)
		(layer "B.Cu")
		(net "SAS2X28_B_HDD10_TX_+")
	)
	(arc
		(start 25.385776 -429.53813)
		(mid 25.12352 -429.930624)
		(end 25.031446 -430.393602)
		(width 0.09525)
		(layer "B.Cu")
		(net "SAS2X28_B_HDD10_TX_+")
	)
	(arc
		(start 39.477696 -303.295304)
		(mid 39.209834 -303.696188)
		(end 39.115746 -304.169064)
		(width 0.09525)
		(layer "B.Cu")
		(net "SAS2X28_B_HDD10_TX_+")
	)
	(arc
		(start 25.031446 -442.650118)
		(mid 24.957975 -443.019484)
		(end 24.748744 -443.332616)
		(width 0.09525)
		(layer "B.Cu")
		(net "SAS2X28_B_HDD10_TX_+")
	)
	(arc
		(start 31.152846 -366.653572)
		(mid 30.979163 -367.526734)
		(end 30.484572 -368.26698)
		(width 0.09525)
		(layer "B.Cu")
		(net "SAS2X28_B_HDD10_TX_+")
	)
	(arc
		(start 23.722584 -444.358776)
		(mid 23.326681 -444.623154)
		(end 22.859746 -444.7159)
		(width 0.09525)
		(layer "B.Cu")
		(net "SAS2X28_B_HDD10_TX_+")
	)
	(arc
		(start 26.745946 -427.763178)
		(mid 26.66971 -428.146444)
		(end 26.452576 -428.47133)
		(width 0.09525)
		(layer "B.Cu")
		(net "SAS2X28_B_HDD10_TX_+")
	)
	(via
		(at 218.948 -278.003)
		(size 0.7112)
		(drill 0.3556)
		(layers "F.Cu" "B.Cu")
		(net "5V_PRE_2")
	)
	(segment
		(start 3.19405 -391.50036)
		(end 3.192526 -391.498836)
		(width 0.111252)
		(layer "F.Cu")
		(net "SAS2X28_A_HDD10_FLT")
	)
	(segment
		(start 7.55904 -391.50036)
		(end 3.19405 -391.50036)
		(width 0.111252)
		(layer "F.Cu")
		(net "SAS2X28_A_HDD10_FLT")
	)
	(segment
		(start 28.828746 -436.2577)
		(end 29.781246 -436.2577)
		(width 0.111252)
		(layer "F.Cu")
		(net "SAS2X28_A_HDD10_FLT")
	)
	(segment
		(start 9.1186 -389.381746)
		(end 9.1186 -389.9408)
		(width 0.111252)
		(layer "F.Cu")
		(net "SAS2X28_A_HDD10_FLT")
	)
	(segment
		(start 28.639262 -436.068216)
		(end 28.828746 -436.2577)
		(width 0.111252)
		(layer "F.Cu")
		(net "SAS2X28_A_HDD10_FLT")
	)
	(segment
		(start 27.749246 -436.019702)
		(end 28.639262 -436.019702)
		(width 0.111252)
		(layer "F.Cu")
		(net "SAS2X28_A_HDD10_FLT")
	)
	(segment
		(start 28.639262 -436.019702)
		(end 28.639262 -436.068216)
		(width 0.111252)
		(layer "F.Cu")
		(net "SAS2X28_A_HDD10_FLT")
	)
	(segment
		(start 9.651746 -388.8486)
		(end 9.1186 -389.381746)
		(width 0.111252)
		(layer "F.Cu")
		(net "SAS2X28_A_HDD10_FLT")
	)
	(segment
		(start 9.1186 -389.9408)
		(end 7.55904 -391.50036)
		(width 0.111252)
		(layer "F.Cu")
		(net "SAS2X28_A_HDD10_FLT")
	)
	(via
		(at 9.651746 -388.8486)
		(size 0.5588)
		(drill 0.3048)
		(layers "F.Cu" "B.Cu")
		(net "SAS2X28_A_HDD10_FLT")
	)
	(via
		(at 29.590746 -436.0545)
		(size 0.7112)
		(drill 0.3556)
		(layers "F.Cu" "B.Cu")
		(net "SAS2X28_A_HDD10_FLT")
	)
	(via
		(at 28.639262 -436.019702)
		(size 0.5588)
		(drill 0.3048)
		(layers "F.Cu" "B.Cu")
		(net "SAS2X28_A_HDD10_FLT")
	)
	(segment
		(start 28.67406 -436.0545)
		(end 29.590746 -436.0545)
		(width 0.111252)
		(layer "B.Cu")
		(net "SAS2X28_A_HDD10_FLT")
	)
	(segment
		(start 28.639262 -436.019702)
		(end 28.67406 -436.0545)
		(width 0.111252)
		(layer "B.Cu")
		(net "SAS2X28_A_HDD10_FLT")
	)
	(segment
		(start 23.4696 -435.4576)
		(end 25.853898 -435.4576)
		(width 0.14605)
		(layer "In5.Cu")
		(net "SAS2X28_A_HDD10_FLT")
	)
	(segment
		(start 15.795752 -402.110956)
		(end 15.683992 -402.222716)
		(width 0.14605)
		(layer "In5.Cu")
		(net "SAS2X28_A_HDD10_FLT")
	)
	(segment
		(start 15.54099 -407.388314)
		(end 15.54099 -416.9156)
		(width 0.14605)
		(layer "In5.Cu")
		(net "SAS2X28_A_HDD10_FLT")
	)
	(segment
		(start 9.651746 -388.8486)
		(end 15.795752 -394.992606)
		(width 0.14605)
		(layer "In5.Cu")
		(net "SAS2X28_A_HDD10_FLT")
	)
	(segment
		(start 15.54099 -416.9156)
		(end 15.683992 -417.058602)
		(width 0.14605)
		(layer "In5.Cu")
		(net "SAS2X28_A_HDD10_FLT")
	)
	(segment
		(start 25.853898 -435.4576)
		(end 26.416 -436.019702)
		(width 0.14605)
		(layer "In5.Cu")
		(net "SAS2X28_A_HDD10_FLT")
	)
	(segment
		(start 26.416 -436.019702)
		(end 28.639262 -436.019702)
		(width 0.14605)
		(layer "In5.Cu")
		(net "SAS2X28_A_HDD10_FLT")
	)
	(segment
		(start 15.683992 -407.245312)
		(end 15.54099 -407.388314)
		(width 0.14605)
		(layer "In5.Cu")
		(net "SAS2X28_A_HDD10_FLT")
	)
	(segment
		(start 15.683992 -402.222716)
		(end 15.683992 -407.245312)
		(width 0.14605)
		(layer "In5.Cu")
		(net "SAS2X28_A_HDD10_FLT")
	)
	(segment
		(start 15.683992 -417.058602)
		(end 15.683992 -427.671992)
		(width 0.14605)
		(layer "In5.Cu")
		(net "SAS2X28_A_HDD10_FLT")
	)
	(segment
		(start 15.795752 -394.992606)
		(end 15.795752 -402.110956)
		(width 0.14605)
		(layer "In5.Cu")
		(net "SAS2X28_A_HDD10_FLT")
	)
	(segment
		(start 15.683992 -427.671992)
		(end 23.4696 -435.4576)
		(width 0.14605)
		(layer "In5.Cu")
		(net "SAS2X28_A_HDD10_FLT")
	)
	(segment
		(start 38.253416 -173.846744)
		(end 38.250114 -173.850046)
		(width 0.111252)
		(layer "F.Cu")
		(net "HDD_PRSNT_NET8")
	)
	(segment
		(start 57.467246 -176.1617)
		(end 57.467246 -175.133254)
		(width 0.111252)
		(layer "F.Cu")
		(net "HDD_PRSNT_NET8")
	)
	(segment
		(start 54.177946 -176.2252)
		(end 52.260246 -176.2252)
		(width 0.111252)
		(layer "F.Cu")
		(net "HDD_PRSNT_NET8")
	)
	(segment
		(start 55.117746 -176.2252)
		(end 56.197246 -176.2252)
		(width 0.111252)
		(layer "F.Cu")
		(net "HDD_PRSNT_NET8")
	)
	(segment
		(start 56.260746 -176.1617)
		(end 57.467246 -176.1617)
		(width 0.111252)
		(layer "F.Cu")
		(net "HDD_PRSNT_NET8")
	)
	(segment
		(start 56.197246 -176.2252)
		(end 56.260746 -176.1617)
		(width 0.111252)
		(layer "F.Cu")
		(net "HDD_PRSNT_NET8")
	)
	(segment
		(start 49.88179 -173.846744)
		(end 38.253416 -173.846744)
		(width 0.111252)
		(layer "F.Cu")
		(net "HDD_PRSNT_NET8")
	)
	(segment
		(start 54.177946 -176.2252)
		(end 55.117746 -176.2252)
		(width 0.111252)
		(layer "F.Cu")
		(net "HDD_PRSNT_NET8")
	)
	(segment
		(start 52.260246 -176.2252)
		(end 49.88179 -173.846744)
		(width 0.111252)
		(layer "F.Cu")
		(net "HDD_PRSNT_NET8")
	)
	(segment
		(start 57.467246 -175.133254)
		(end 57.4675 -175.133)
		(width 0.111252)
		(layer "F.Cu")
		(net "HDD_PRSNT_NET8")
	)
	(via
		(at 54.177946 -176.2252)
		(size 0.7112)
		(drill 0.3556)
		(layers "F.Cu" "B.Cu")
		(net "HDD_PRSNT_NET8")
	)
	(via
		(at 219.379546 -381.3175)
		(size 0.5588)
		(drill 0.3048)
		(layers "F.Cu" "B.Cu")
		(net "5V_PRE_1")
	)
	(via
		(at 220.095064 -380.627382)
		(size 0.7112)
		(drill 0.3556)
		(layers "F.Cu" "B.Cu")
		(net "5V_PRE_1")
	)
	(segment
		(start 219.379546 -381.3175)
		(end 220.069664 -380.627382)
		(width 0.508)
		(layer "B.Cu")
		(net "5V_PRE_1")
	)
	(segment
		(start 220.069664 -380.627382)
		(end 220.095064 -380.627382)
		(width 0.508)
		(layer "B.Cu")
		(net "5V_PRE_1")
	)
	(segment
		(start 57.023 -274.955)
		(end 57.023 -275.36267)
		(width 0.111252)
		(layer "F.Cu")
		(net "HDD_PRSNT_NET7")
	)
	(segment
		(start 54.0004 -276.850094)
		(end 55.235094 -276.850094)
		(width 0.111252)
		(layer "F.Cu")
		(net "HDD_PRSNT_NET7")
	)
	(segment
		(start 55.549546 -276.8727)
		(end 55.52694 -276.850094)
		(width 0.111252)
		(layer "F.Cu")
		(net "HDD_PRSNT_NET7")
	)
	(segment
		(start 57.5056 -275.9837)
		(end 56.6166 -276.8727)
		(width 0.111252)
		(layer "F.Cu")
		(net "HDD_PRSNT_NET7")
	)
	(segment
		(start 57.6072 -275.9837)
		(end 57.5056 -275.9837)
		(width 0.111252)
		(layer "F.Cu")
		(net "HDD_PRSNT_NET7")
	)
	(segment
		(start 55.52694 -276.850094)
		(end 55.235094 -276.850094)
		(width 0.111252)
		(layer "F.Cu")
		(net "HDD_PRSNT_NET7")
	)
	(segment
		(start 57.2262 -275.56587)
		(end 57.2262 -275.6027)
		(width 0.111252)
		(layer "F.Cu")
		(net "HDD_PRSNT_NET7")
	)
	(segment
		(start 54.0004 -276.850094)
		(end 38.250114 -276.850094)
		(width 0.111252)
		(layer "F.Cu")
		(net "HDD_PRSNT_NET7")
	)
	(segment
		(start 57.2262 -275.6027)
		(end 57.6072 -275.9837)
		(width 0.111252)
		(layer "F.Cu")
		(net "HDD_PRSNT_NET7")
	)
	(segment
		(start 57.023 -275.36267)
		(end 57.2262 -275.56587)
		(width 0.111252)
		(layer "F.Cu")
		(net "HDD_PRSNT_NET7")
	)
	(segment
		(start 56.6166 -276.8727)
		(end 55.549546 -276.8727)
		(width 0.111252)
		(layer "F.Cu")
		(net "HDD_PRSNT_NET7")
	)
	(segment
		(start 55.235094 -276.850094)
		(end 55.245 -276.86)
		(width 0.111252)
		(layer "F.Cu")
		(net "HDD_PRSNT_NET7")
	)
	(via
		(at 54.0004 -276.850094)
		(size 0.7112)
		(drill 0.3556)
		(layers "F.Cu" "B.Cu")
		(net "HDD_PRSNT_NET7")
	)
	(via
		(at 219.379546 -484.2383)
		(size 0.5588)
		(drill 0.3048)
		(layers "F.Cu" "B.Cu")
		(net "5V_PRE_0")
	)
	(via
		(at 219.379546 -483.2985)
		(size 0.7112)
		(drill 0.3556)
		(layers "F.Cu" "B.Cu")
		(net "5V_PRE_0")
	)
	(segment
		(start 219.379546 -483.2985)
		(end 219.379546 -484.2383)
		(width 0.508)
		(layer "B.Cu")
		(net "5V_PRE_0")
	)
	(segment
		(start 56.133746 -381.9017)
		(end 56.197246 -381.9017)
		(width 0.111252)
		(layer "F.Cu")
		(net "HDD_PRSNT_NET6")
	)
	(segment
		(start 55.117746 -381.9652)
		(end 56.070246 -381.9652)
		(width 0.111252)
		(layer "F.Cu")
		(net "HDD_PRSNT_NET6")
	)
	(segment
		(start 53.880766 -381.9652)
		(end 55.117746 -381.9652)
		(width 0.111252)
		(layer "F.Cu")
		(net "HDD_PRSNT_NET6")
	)
	(segment
		(start 53.826156 -382.01981)
		(end 53.584856 -382.01981)
		(width 0.111252)
		(layer "F.Cu")
		(net "HDD_PRSNT_NET6")
	)
	(segment
		(start 53.584856 -382.01981)
		(end 51.411886 -379.84684)
		(width 0.111252)
		(layer "F.Cu")
		(net "HDD_PRSNT_NET6")
	)
	(segment
		(start 56.197246 -381.9017)
		(end 57.276746 -380.8222)
		(width 0.111252)
		(layer "F.Cu")
		(net "HDD_PRSNT_NET6")
	)
	(segment
		(start 53.826156 -382.01981)
		(end 53.880766 -381.9652)
		(width 0.111252)
		(layer "F.Cu")
		(net "HDD_PRSNT_NET6")
	)
	(segment
		(start 56.070246 -381.9652)
		(end 56.133746 -381.9017)
		(width 0.111252)
		(layer "F.Cu")
		(net "HDD_PRSNT_NET6")
	)
	(segment
		(start 51.411886 -379.84684)
		(end 38.253416 -379.84684)
		(width 0.111252)
		(layer "F.Cu")
		(net "HDD_PRSNT_NET6")
	)
	(segment
		(start 38.253416 -379.84684)
		(end 38.250114 -379.850142)
		(width 0.111252)
		(layer "F.Cu")
		(net "HDD_PRSNT_NET6")
	)
	(segment
		(start 57.276746 -380.8222)
		(end 58.3311 -380.8222)
		(width 0.111252)
		(layer "F.Cu")
		(net "HDD_PRSNT_NET6")
	)
	(via
		(at 53.826156 -382.01981)
		(size 0.7112)
		(drill 0.3556)
		(layers "F.Cu" "B.Cu")
		(net "HDD_PRSNT_NET6")
	)
	(segment
		(start 49.161446 -145.35785)
		(end 49.161446 -146.27225)
		(width 0.508)
		(layer "F.Cu")
		(net "GND")
	)
	(segment
		(start 234.200446 -144.97685)
		(end 234.200446 -145.89125)
		(width 0.508)
		(layer "F.Cu")
		(net "GND")
	)
	(segment
		(start 21.166074 -237.40999)
		(end 21.332952 -237.243112)
		(width 0.381)
		(layer "F.Cu")
		(net "GND")
	)
	(segment
		(start 227.499926 -191.551814)
		(end 227.499926 -192.669922)
		(width 0.635)
		(layer "F.Cu")
		(net "GND")
	)
	(segment
		(start 248.144538 -271.498568)
		(end 252.501146 -271.498568)
		(width 0.635)
		(layer "F.Cu")
		(net "GND")
	)
	(segment
		(start 252.499622 -479.996754)
		(end 252.499622 -484.353362)
		(width 0.635)
		(layer "F.Cu")
		(net "GND")
	)
	(segment
		(start 206.4385 -379.5395)
		(end 206.3877 -379.4887)
		(width 0.508)
		(layer "F.Cu")
		(net "GND")
	)
	(segment
		(start 35.7632 -435.5592)
		(end 35.066986 -435.5592)
		(width 0.4064)
		(layer "F.Cu")
		(net "GND")
	)
	(segment
		(start 42.500042 -456.552046)
		(end 42.500042 -457.670154)
		(width 0.635)
		(layer "F.Cu")
		(net "GND")
	)
	(segment
		(start 40.835834 -192.669922)
		(end 42.500042 -192.669922)
		(width 0.635)
		(layer "F.Cu")
		(net "GND")
	)
	(segment
		(start 194.804284 -185.405268)
		(end 194.804284 -186.02833)
		(width 0.4064)
		(layer "F.Cu")
		(net "GND")
	)
	(segment
		(start 5.804154 -349.038926)
		(end 5.343144 -349.499936)
		(width 0.508)
		(layer "F.Cu")
		(net "GND")
	)
	(segment
		(start 3.19405 -346.499942)
		(end 3.192526 -346.498418)
		(width 0.508)
		(layer "F.Cu")
		(net "GND")
	)
	(segment
		(start 19.600164 -342.810084)
		(end 19.600164 -343.7636)
		(width 0.508)
		(layer "F.Cu")
		(net "GND")
	)
	(segment
		(start 227.499926 -89.669874)
		(end 229.164134 -89.669874)
		(width 0.635)
		(layer "F.Cu")
		(net "GND")
	)
	(segment
		(start 21.7551 -34.584894)
		(end 21.75002 -34.579814)
		(width 0.508)
		(layer "F.Cu")
		(net "GND")
	)
	(segment
		(start 43.829986 -207.221328)
		(end 43.829986 -208.372202)
		(width 0.4064)
		(layer "F.Cu")
		(net "GND")
	)
	(segment
		(start 5.395976 -409.52547)
		(end 5.37083 -409.500324)
		(width 0.508)
		(layer "F.Cu")
		(net "GND")
	)
	(segment
		(start 35.941 -180.594)
		(end 36.340034 -180.194966)
		(width 0.508)
		(layer "F.Cu")
		(net "GND")
	)
	(segment
		(start 40.513 -207.8355)
		(end 40.513 -206.9338)
		(width 0.508)
		(layer "F.Cu")
		(net "GND")
	)
	(segment
		(start 240.512346 -31.1277)
		(end 240.512346 -30.4165)
		(width 0.508)
		(layer "F.Cu")
		(net "GND")
	)
	(segment
		(start 5.968746 -370.9797)
		(end 5.4229 -371.525546)
		(width 0.508)
		(layer "F.Cu")
		(net "GND")
	)
	(segment
		(start 5.968746 -114.985546)
		(end 5.483606 -114.500406)
		(width 0.508)
		(layer "F.Cu")
		(net "GND")
	)
	(segment
		(start 43.9674 -122.7074)
		(end 44.651422 -123.391422)
		(width 0.4064)
		(layer "F.Cu")
		(net "GND")
	)
	(segment
		(start 57.66435 -173.6725)
		(end 57.66435 -172.256704)
		(width 0.508)
		(layer "F.Cu")
		(net "GND")
	)
	(segment
		(start 42.05605 -427.2407)
		(end 42.05605 -425.95165)
		(width 0.508)
		(layer "F.Cu")
		(net "GND")
	)
	(segment
		(start 5.483606 -100.499926)
		(end 3.19405 -100.499926)
		(width 0.508)
		(layer "F.Cu")
		(net "GND")
	)
	(segment
		(start 21.748242 -244.391688)
		(end 20.472908 -244.391688)
		(width 0.508)
		(layer "F.Cu")
		(net "GND")
	)
	(segment
		(start 5.421884 -125.500384)
		(end 3.19405 -125.500384)
		(width 0.508)
		(layer "F.Cu")
		(net "GND")
	)
	(segment
		(start 5.359146 -421.5003)
		(end 3.19405 -421.5003)
		(width 0.508)
		(layer "F.Cu")
		(net "GND")
	)
	(segment
		(start 5.483606 -172.50029)
		(end 3.19405 -172.50029)
		(width 0.508)
		(layer "F.Cu")
		(net "GND")
	)
	(segment
		(start 5.37083 -409.500324)
		(end 3.19405 -409.500324)
		(width 0.508)
		(layer "F.Cu")
		(net "GND")
	)
	(segment
		(start 57.276746 -184.4167)
		(end 58.635646 -184.4167)
		(width 0.508)
		(layer "F.Cu")
		(net "GND")
	)
	(segment
		(start 5.9944 -387.6802)
		(end 5.872734 -387.6802)
		(width 0.508)
		(layer "F.Cu")
		(net "GND")
	)
	(segment
		(start 5.610352 -418.500306)
		(end 3.19405 -418.500306)
		(width 0.508)
		(layer "F.Cu")
		(net "GND")
	)
	(segment
		(start 200.074022 -390.049512)
		(end 199.282558 -390.049512)
		(width 0.508)
		(layer "F.Cu")
		(net "GND")
	)
	(segment
		(start 3.19405 -375.500392)
		(end 3.192526 -375.498868)
		(width 0.508)
		(layer "F.Cu")
		(net "GND")
	)
	(segment
		(start 30.225746 -309.6387)
		(end 31.222188 -309.6387)
		(width 0.508)
		(layer "F.Cu")
		(net "GND")
	)
	(segment
		(start 40.835834 -398.670018)
		(end 42.500042 -398.670018)
		(width 0.635)
		(layer "F.Cu")
		(net "GND")
	)
	(segment
		(start 5.486654 -375.500392)
		(end 3.19405 -375.500392)
		(width 0.508)
		(layer "F.Cu")
		(net "GND")
	)
	(segment
		(start 225.399854 -62.589918)
		(end 223.82099 -62.589918)
		(width 0.381)
		(layer "F.Cu")
		(net "GND")
	)
	(segment
		(start 207.264 -379.5395)
		(end 206.4385 -379.5395)
		(width 0.508)
		(layer "F.Cu")
		(net "GND")
	)
	(segment
		(start 3.19405 -417.500308)
		(end 3.192526 -417.498784)
		(width 0.508)
		(layer "F.Cu")
		(net "GND")
	)
	(segment
		(start 19.600164 -338.009992)
		(end 19.600164 -337.143344)
		(width 0.508)
		(layer "F.Cu")
		(net "GND")
	)
	(segment
		(start 6.203442 -387.889242)
		(end 5.9944 -387.6802)
		(width 0.508)
		(layer "F.Cu")
		(net "GND")
	)
	(segment
		(start 5.69722 -353.499928)
		(end 3.19405 -353.499928)
		(width 0.508)
		(layer "F.Cu")
		(net "GND")
	)
	(segment
		(start 69.000878 -475.641924)
		(end 69.000878 -479.998532)
		(width 0.635)
		(layer "F.Cu")
		(net "GND")
	)
	(segment
		(start 5.82803 -393.500356)
		(end 3.19405 -393.500356)
		(width 0.508)
		(layer "F.Cu")
		(net "GND")
	)
	(segment
		(start 3.19405 -413.500316)
		(end 3.192526 -413.498792)
		(width 0.508)
		(layer "F.Cu")
		(net "GND")
	)
	(segment
		(start 23.5966 -16.796512)
		(end 23.588218 -16.804894)
		(width 0.508)
		(layer "F.Cu")
		(net "GND")
	)
	(segment
		(start 227.499926 -192.669922)
		(end 227.499926 -193.78803)
		(width 0.635)
		(layer "F.Cu")
		(net "GND")
	)
	(segment
		(start 38.245034 -484.11511)
		(end 38.250114 -484.12019)
		(width 0.508)
		(layer "F.Cu")
		(net "GND")
	)
	(segment
		(start 7.501128 -78.628494)
		(end 7.501128 -82.985102)
		(width 0.635)
		(layer "F.Cu")
		(net "GND")
	)
	(segment
		(start 3.19405 -172.50029)
		(end 3.192526 -172.498766)
		(width 0.508)
		(layer "F.Cu")
		(net "GND")
	)
	(segment
		(start 3.19405 -427.500288)
		(end 3.192526 -427.498764)
		(width 0.508)
		(layer "F.Cu")
		(net "GND")
	)
	(segment
		(start 5.483606 -126.500382)
		(end 3.19405 -126.500382)
		(width 0.508)
		(layer "F.Cu")
		(net "GND")
	)
	(segment
		(start 3.19405 -349.499936)
		(end 3.192526 -349.498412)
		(width 0.508)
		(layer "F.Cu")
		(net "GND")
	)
	(segment
		(start 31.1785 -282.829)
		(end 32.258 -282.829)
		(width 0.508)
		(layer "F.Cu")
		(net "GND")
	)
	(segment
		(start 69.000878 -170.998642)
		(end 73.357486 -170.998642)
		(width 0.635)
		(layer "F.Cu")
		(net "GND")
	)
	(segment
		(start 227.499926 -44.551854)
		(end 227.499926 -45.669962)
		(width 0.635)
		(layer "F.Cu")
		(net "GND")
	)
	(segment
		(start 11.175746 -499.9482)
		(end 11.175746 -500.0117)
		(width 0.508)
		(layer "F.Cu")
		(net "GND")
	)
	(segment
		(start 36.256976 -55.604918)
		(end 38.245034 -55.604918)
		(width 0.508)
		(layer "F.Cu")
		(net "GND")
	)
	(segment
		(start 225.835718 -354.670106)
		(end 227.499926 -354.670106)
		(width 0.635)
		(layer "F.Cu")
		(net "GND")
	)
	(segment
		(start 39.141654 -113.1697)
		(end 40.207946 -112.103408)
		(width 0.508)
		(layer "F.Cu")
		(net "GND")
	)
	(segment
		(start 251.56795 -414.92805)
		(end 252.196092 -414.299908)
		(width 0.508)
		(layer "F.Cu")
		(net "GND")
	)
	(segment
		(start 250.698 -414.2486)
		(end 251.916692 -413.029908)
		(width 0.508)
		(layer "F.Cu")
		(net "GND")
	)
	(segment
		(start 3.19405 -387.500368)
		(end 3.192526 -387.498844)
		(width 0.508)
		(layer "F.Cu")
		(net "GND")
	)
	(segment
		(start 3.192526 -103.498396)
		(end 3.19405 -103.49992)
		(width 0.508)
		(layer "F.Cu")
		(net "GND")
	)
	(segment
		(start 43.85564 -207.195674)
		(end 43.829986 -207.221328)
		(width 0.4064)
		(layer "F.Cu")
		(net "GND")
	)
	(segment
		(start 194.183 -289.191446)
		(end 194.183 -289.862006)
		(width 0.4064)
		(layer "F.Cu")
		(net "GND")
	)
	(segment
		(start 5.464048 -376.50039)
		(end 3.19405 -376.50039)
		(width 0.508)
		(layer "F.Cu")
		(net "GND")
	)
	(segment
		(start 3.19405 -368.500406)
		(end 3.192526 -368.498882)
		(width 0.508)
		(layer "F.Cu")
		(net "GND")
	)
	(segment
		(start 15.835884 -151.329898)
		(end 17.500092 -151.329898)
		(width 0.635)
		(layer "F.Cu")
		(net "GND")
	)
	(segment
		(start 5.968746 -110.985554)
		(end 5.483606 -110.500414)
		(width 0.508)
		(layer "F.Cu")
		(net "GND")
	)
	(segment
		(start 5.841746 -384.9497)
		(end 5.39242 -384.500374)
		(width 0.508)
		(layer "F.Cu")
		(net "GND")
	)
	(segment
		(start 221.098872 -261.677658)
		(end 221.171516 -261.605014)
		(width 0.508)
		(layer "F.Cu")
		(net "GND")
	)
	(segment
		(start 11.175746 -500.0117)
		(end 11.683746 -500.5197)
		(width 0.508)
		(layer "F.Cu")
		(net "GND")
	)
	(segment
		(start 223.249998 -55.609998)
		(end 221.436946 -55.609998)
		(width 0.508)
		(layer "F.Cu")
		(net "GND")
	)
	(segment
		(start 5.644134 -350.499934)
		(end 3.19405 -350.499934)
		(width 0.508)
		(layer "F.Cu")
		(net "GND")
	)
	(segment
		(start 8.826246 -157.231842)
		(end 8.883904 -157.2895)
		(width 0.508)
		(layer "F.Cu")
		(net "GND")
	)
	(segment
		(start 101.209094 -9.26846)
		(end 100.126546 -9.26846)
		(width 0.4064)
		(layer "F.Cu")
		(net "GND")
	)
	(segment
		(start 59.816746 -20.6502)
		(end 60.972446 -20.6502)
		(width 0.508)
		(layer "F.Cu")
		(net "GND")
	)
	(segment
		(start 3.19405 -409.500324)
		(end 3.192526 -409.4988)
		(width 0.508)
		(layer "F.Cu")
		(net "GND")
	)
	(segment
		(start 36.196524 -484.11511)
		(end 38.245034 -484.11511)
		(width 0.508)
		(layer "F.Cu")
		(net "GND")
	)
	(segment
		(start 3.19405 -122.50039)
		(end 3.192526 -122.498866)
		(width 0.508)
		(layer "F.Cu")
		(net "GND")
	)
	(segment
		(start 227.499926 -456.552046)
		(end 227.499926 -457.670154)
		(width 0.635)
		(layer "F.Cu")
		(net "GND")
	)
	(segment
		(start 21.7551 -24.424894)
		(end 21.75002 -24.419814)
		(width 0.508)
		(layer "F.Cu")
		(net "GND")
	)
	(segment
		(start 227.499926 -457.670154)
		(end 227.499926 -458.788262)
		(width 0.635)
		(layer "F.Cu")
		(net "GND")
	)
	(segment
		(start 5.841746 -381.0127)
		(end 5.329428 -380.500382)
		(width 0.508)
		(layer "F.Cu")
		(net "GND")
	)
	(segment
		(start 17.500092 -4.329938)
		(end 19.1643 -4.329938)
		(width 0.635)
		(layer "F.Cu")
		(net "GND")
	)
	(segment
		(start 211.58835 -377.5837)
		(end 212.28685 -377.5837)
		(width 0.508)
		(layer "F.Cu")
		(net "GND")
	)
	(segment
		(start 70.850506 -85.714586)
		(end 70.560946 -86.004146)
		(width 0.4064)
		(layer "F.Cu")
		(net "GND")
	)
	(segment
		(start 47.244 -418.202872)
		(end 47.599346 -418.558218)
		(width 0.4064)
		(layer "F.Cu")
		(net "GND")
	)
	(segment
		(start 87.716106 -15.74546)
		(end 88.328246 -15.74546)
		(width 0.4064)
		(layer "F.Cu")
		(net "GND")
	)
	(segment
		(start 221.448122 -467.60511)
		(end 223.244918 -467.60511)
		(width 0.508)
		(layer "F.Cu")
		(net "GND")
	)
	(segment
		(start 6.412738 -392.915648)
		(end 5.82803 -393.500356)
		(width 0.508)
		(layer "F.Cu")
		(net "GND")
	)
	(segment
		(start 3.19405 -130.500374)
		(end 3.192526 -130.49885)
		(width 0.508)
		(layer "F.Cu")
		(net "GND")
	)
	(segment
		(start 27.431746 -371.3607)
		(end 27.431746 -374.9167)
		(width 0.508)
		(layer "F.Cu")
		(net "GND")
	)
	(segment
		(start 23.588218 -426.265086)
		(end 21.7551 -426.265086)
		(width 0.508)
		(layer "F.Cu")
		(net "GND")
	)
	(segment
		(start 55.498746 -184.1627)
		(end 54.355746 -184.1627)
		(width 0.508)
		(layer "F.Cu")
		(net "GND")
	)
	(segment
		(start 5.968746 -118.985538)
		(end 5.483606 -118.500398)
		(width 0.508)
		(layer "F.Cu")
		(net "GND")
	)
	(segment
		(start 40.835834 -501.670066)
		(end 42.500042 -501.670066)
		(width 0.635)
		(layer "F.Cu")
		(net "GND")
	)
	(segment
		(start 3.19405 -176.500282)
		(end 3.192526 -176.498758)
		(width 0.508)
		(layer "F.Cu")
		(net "GND")
	)
	(segment
		(start 194.183 -289.862006)
		(end 194.106546 -289.93846)
		(width 0.4064)
		(layer "F.Cu")
		(net "GND")
	)
	(segment
		(start 5.483606 -110.500414)
		(end 3.19405 -110.500414)
		(width 0.508)
		(layer "F.Cu")
		(net "GND")
	)
	(segment
		(start 7.380986 -487.3752)
		(end 7.314946 -487.44124)
		(width 0.3048)
		(layer "F.Cu")
		(net "GND")
	)
	(segment
		(start 3.19405 -103.49992)
		(end 5.588762 -103.49992)
		(width 0.508)
		(layer "F.Cu")
		(net "GND")
	)
	(segment
		(start 227.499926 -501.670066)
		(end 227.499926 -502.788174)
		(width 0.635)
		(layer "F.Cu")
		(net "GND")
	)
	(segment
		(start 21.7551 -21.884894)
		(end 21.75002 -21.879814)
		(width 0.508)
		(layer "F.Cu")
		(net "GND")
	)
	(segment
		(start 191.204342 -496.512342)
		(end 191.135 -496.443)
		(width 0.4064)
		(layer "F.Cu")
		(net "GND")
	)
	(segment
		(start 5.511038 -367.500408)
		(end 3.19405 -367.500408)
		(width 0.508)
		(layer "F.Cu")
		(net "GND")
	)
	(segment
		(start 227.499926 -251.670058)
		(end 227.499926 -252.788166)
		(width 0.635)
		(layer "F.Cu")
		(net "GND")
	)
	(segment
		(start 17.500092 -151.329898)
		(end 17.500092 -152.448006)
		(width 0.635)
		(layer "F.Cu")
		(net "GND")
	)
	(segment
		(start 251.993908 -418.109908)
		(end 255.474978 -418.109908)
		(width 0.508)
		(layer "F.Cu")
		(net "GND")
	)
	(segment
		(start 5.943346 -112.978946)
		(end 5.421884 -113.500408)
		(width 0.508)
		(layer "F.Cu")
		(net "GND")
	)
	(segment
		(start 5.968746 -122.98553)
		(end 5.483606 -122.50039)
		(width 0.508)
		(layer "F.Cu")
		(net "GND")
	)
	(segment
		(start 15.835884 -416.33013)
		(end 17.500092 -416.33013)
		(width 0.635)
		(layer "F.Cu")
		(net "GND")
	)
	(segment
		(start 195.002912 -83.561936)
		(end 195.002912 -84.712556)
		(width 0.508)
		(layer "F.Cu")
		(net "GND")
	)
	(segment
		(start 6.600444 -176.500282)
		(end 3.19405 -176.500282)
		(width 0.508)
		(layer "F.Cu")
		(net "GND")
	)
	(segment
		(start 29.097986 -274.1422)
		(end 29.844746 -274.1422)
		(width 0.508)
		(layer "F.Cu")
		(net "GND")
	)
	(segment
		(start 17.500092 -48.32985)
		(end 17.500092 -49.447958)
		(width 0.635)
		(layer "F.Cu")
		(net "GND")
	)
	(segment
		(start 5.994146 -374.9929)
		(end 5.486654 -375.500392)
		(width 0.508)
		(layer "F.Cu")
		(net "GND")
	)
	(segment
		(start 38.738048 -371.590062)
		(end 38.734746 -371.58676)
		(width 0.381)
		(layer "F.Cu")
		(net "GND")
	)
	(segment
		(start 64.64427 -170.998642)
		(end 69.000878 -170.998642)
		(width 0.635)
		(layer "F.Cu")
		(net "GND")
	)
	(segment
		(start 42.500042 -500.551958)
		(end 42.500042 -501.670066)
		(width 0.635)
		(layer "F.Cu")
		(net "GND")
	)
	(segment
		(start 5.943346 -128.978914)
		(end 5.421884 -129.500376)
		(width 0.508)
		(layer "F.Cu")
		(net "GND")
	)
	(segment
		(start 3.19405 -167.5003)
		(end 3.192526 -167.498776)
		(width 0.508)
		(layer "F.Cu")
		(net "GND")
	)
	(segment
		(start 78.994 -191.7065)
		(end 79.9465 -191.7065)
		(width 0.508)
		(layer "F.Cu")
		(net "GND")
	)
	(segment
		(start 223.244918 -467.60511)
		(end 223.249998 -467.61019)
		(width 0.508)
		(layer "F.Cu")
		(net "GND")
	)
	(segment
		(start 5.421884 -109.500416)
		(end 3.19405 -109.500416)
		(width 0.508)
		(layer "F.Cu")
		(net "GND")
	)
	(segment
		(start 3.19024 -306.704746)
		(end 5.477002 -306.704746)
		(width 0.7112)
		(layer "F.Cu")
		(net "GND")
	)
	(segment
		(start 5.484368 -410.500322)
		(end 3.19405 -410.500322)
		(width 0.508)
		(layer "F.Cu")
		(net "GND")
	)
	(segment
		(start 207.264 -277.0505)
		(end 207.264 -276.606)
		(width 0.508)
		(layer "F.Cu")
		(net "GND")
	)
	(segment
		(start 41.147746 -233.518202)
		(end 41.147746 -233.9975)
		(width 0.508)
		(layer "F.Cu")
		(net "GND")
	)
	(segment
		(start 252.500892 -33.642046)
		(end 252.500892 -37.998654)
		(width 0.635)
		(layer "F.Cu")
		(net "GND")
	)
	(segment
		(start 69.000878 -166.642034)
		(end 69.000878 -170.998642)
		(width 0.635)
		(layer "F.Cu")
		(net "GND")
	)
	(segment
		(start 3.19405 -99.499928)
		(end 3.192526 -99.498404)
		(width 0.508)
		(layer "F.Cu")
		(net "GND")
	)
	(segment
		(start 23.58136 -433.885086)
		(end 21.7551 -433.885086)
		(width 0.508)
		(layer "F.Cu")
		(net "GND")
	)
	(segment
		(start 225.835718 -148.67001)
		(end 227.499926 -148.67001)
		(width 0.635)
		(layer "F.Cu")
		(net "GND")
	)
	(segment
		(start 5.8928 -307.120544)
		(end 5.8928 -307.1622)
		(width 0.7112)
		(layer "F.Cu")
		(net "GND")
	)
	(segment
		(start 225.835718 -251.670058)
		(end 227.499926 -251.670058)
		(width 0.635)
		(layer "F.Cu")
		(net "GND")
	)
	(segment
		(start 20.155408 -323.265038)
		(end 21.74494 -323.265038)
		(width 0.508)
		(layer "F.Cu")
		(net "GND")
	)
	(segment
		(start 42.500042 -294.551862)
		(end 42.500042 -295.66997)
		(width 0.635)
		(layer "F.Cu")
		(net "GND")
	)
	(segment
		(start 19.967702 -325.796656)
		(end 19.976084 -325.805038)
		(width 0.508)
		(layer "F.Cu")
		(net "GND")
	)
	(segment
		(start 83.819746 -495.877342)
		(end 83.819746 -495.6937)
		(width 0.4064)
		(layer "F.Cu")
		(net "GND")
	)
	(segment
		(start 5.53593 -159.500316)
		(end 3.19405 -159.500316)
		(width 0.508)
		(layer "F.Cu")
		(net "GND")
	)
	(segment
		(start 61.645546 -20.4597)
		(end 61.213746 -20.8915)
		(width 0.508)
		(layer "F.Cu")
		(net "GND")
	)
	(segment
		(start 6.044946 -383.0447)
		(end 5.58927 -383.500376)
		(width 0.508)
		(layer "F.Cu")
		(net "GND")
	)
	(segment
		(start 42.500042 -295.66997)
		(end 42.500042 -296.788078)
		(width 0.635)
		(layer "F.Cu")
		(net "GND")
	)
	(segment
		(start 41.516046 -133.3119)
		(end 41.516046 -132.4991)
		(width 0.508)
		(layer "F.Cu")
		(net "GND")
	)
	(segment
		(start 101.294946 -9.182608)
		(end 101.209094 -9.26846)
		(width 0.4064)
		(layer "F.Cu")
		(net "GND")
	)
	(segment
		(start 3.19405 -426.50029)
		(end 5.463794 -426.50029)
		(width 0.508)
		(layer "F.Cu")
		(net "GND")
	)
	(segment
		(start 5.588762 -103.49992)
		(end 5.9944 -103.094282)
		(width 0.508)
		(layer "F.Cu")
		(net "GND")
	)
	(segment
		(start 7.501128 -261.498588)
		(end 11.857736 -261.498588)
		(width 0.635)
		(layer "F.Cu")
		(net "GND")
	)
	(segment
		(start 69.000878 -273.998436)
		(end 73.357486 -273.998436)
		(width 0.635)
		(layer "F.Cu")
		(net "GND")
	)
	(segment
		(start 21.7551 -14.264894)
		(end 21.75002 -14.259814)
		(width 0.508)
		(layer "F.Cu")
		(net "GND")
	)
	(segment
		(start 227.499926 -148.67001)
		(end 229.164134 -148.67001)
		(width 0.635)
		(layer "F.Cu")
		(net "GND")
	)
	(segment
		(start 5.483606 -160.500314)
		(end 3.19405 -160.500314)
		(width 0.508)
		(layer "F.Cu")
		(net "GND")
	)
	(segment
		(start 238.645446 -43.58005)
		(end 238.645446 -44.49445)
		(width 0.508)
		(layer "F.Cu")
		(net "GND")
	)
	(segment
		(start 206.9465 -482.7905)
		(end 206.375 -482.219)
		(width 0.508)
		(layer "F.Cu")
		(net "GND")
	)
	(segment
		(start 38.245034 -51.794918)
		(end 38.250114 -51.799998)
		(width 0.508)
		(layer "F.Cu")
		(net "GND")
	)
	(segment
		(start 5.388864 -425.500292)
		(end 3.19405 -425.500292)
		(width 0.508)
		(layer "F.Cu")
		(net "GND")
	)
	(segment
		(start 38.254178 -77.195934)
		(end 39.5224 -77.195934)
		(width 0.508)
		(layer "F.Cu")
		(net "GND")
	)
	(segment
		(start 69.000878 -376.998484)
		(end 73.357486 -376.998484)
		(width 0.635)
		(layer "F.Cu")
		(net "GND")
	)
	(segment
		(start 20.009866 -330.876656)
		(end 20.018248 -330.885038)
		(width 0.508)
		(layer "F.Cu")
		(net "GND")
	)
	(segment
		(start 40.835834 -457.670154)
		(end 42.500042 -457.670154)
		(width 0.635)
		(layer "F.Cu")
		(net "GND")
	)
	(segment
		(start 5.483606 -130.500374)
		(end 3.19405 -130.500374)
		(width 0.508)
		(layer "F.Cu")
		(net "GND")
	)
	(segment
		(start 5.841746 -369.010946)
		(end 5.331206 -368.500406)
		(width 0.508)
		(layer "F.Cu")
		(net "GND")
	)
	(segment
		(start 3.19405 -164.500306)
		(end 3.192526 -164.498782)
		(width 0.508)
		(layer "F.Cu")
		(net "GND")
	)
	(segment
		(start 42.500042 -398.670018)
		(end 44.16425 -398.670018)
		(width 0.635)
		(layer "F.Cu")
		(net "GND")
	)
	(segment
		(start 17.500092 -48.32985)
		(end 19.1643 -48.32985)
		(width 0.635)
		(layer "F.Cu")
		(net "GND")
	)
	(segment
		(start 5.421884 -129.500376)
		(end 3.19405 -129.500376)
		(width 0.508)
		(layer "F.Cu")
		(net "GND")
	)
	(segment
		(start 5.968746 -360.933746)
		(end 5.535422 -360.500422)
		(width 0.508)
		(layer "F.Cu")
		(net "GND")
	)
	(segment
		(start 38.250114 -491.74019)
		(end 40.42664 -491.74019)
		(width 0.508)
		(layer "F.Cu")
		(net "GND")
	)
	(segment
		(start 3.192526 -426.498766)
		(end 3.19405 -426.50029)
		(width 0.508)
		(layer "F.Cu")
		(net "GND")
	)
	(segment
		(start 250.705366 -415.05505)
		(end 250.698 -415.047684)
		(width 0.508)
		(layer "F.Cu")
		(net "GND")
	)
	(segment
		(start 23.613364 -21.884894)
		(end 21.7551 -21.884894)
		(width 0.508)
		(layer "F.Cu")
		(net "GND")
	)
	(segment
		(start 227.499926 -354.670106)
		(end 227.499926 -355.788214)
		(width 0.635)
		(layer "F.Cu")
		(net "GND")
	)
	(segment
		(start 38.255194 -175.114966)
		(end 38.250114 -175.120046)
		(width 0.508)
		(layer "F.Cu")
		(net "GND")
	)
	(segment
		(start 5.692902 -387.500368)
		(end 3.19405 -387.500368)
		(width 0.508)
		(layer "F.Cu")
		(net "GND")
	)
	(segment
		(start 6.095746 -362.9787)
		(end 5.57403 -363.500416)
		(width 0.508)
		(layer "F.Cu")
		(net "GND")
	)
	(segment
		(start 64.64427 -67.998594)
		(end 69.000878 -67.998594)
		(width 0.635)
		(layer "F.Cu")
		(net "GND")
	)
	(segment
		(start 192.276984 -189.189106)
		(end 192.404746 -189.316868)
		(width 0.4064)
		(layer "F.Cu")
		(net "GND")
	)
	(segment
		(start 42.500042 -88.551766)
		(end 42.500042 -89.669874)
		(width 0.635)
		(layer "F.Cu")
		(net "GND")
	)
	(segment
		(start 223.82099 -62.589918)
		(end 223.489012 -62.921896)
		(width 0.381)
		(layer "F.Cu")
		(net "GND")
	)
	(segment
		(start 3.19405 -371.5004)
		(end 3.192526 -371.498876)
		(width 0.508)
		(layer "F.Cu")
		(net "GND")
	)
	(segment
		(start 26.161746 -300.3677)
		(end 26.161746 -301.7647)
		(width 0.508)
		(layer "F.Cu")
		(net "GND")
	)
	(segment
		(start 5.483606 -156.500322)
		(end 3.19405 -156.500322)
		(width 0.508)
		(layer "F.Cu")
		(net "GND")
	)
	(segment
		(start 5.483606 -122.50039)
		(end 3.19405 -122.50039)
		(width 0.508)
		(layer "F.Cu")
		(net "GND")
	)
	(segment
		(start 3.19405 -350.499934)
		(end 3.192526 -350.49841)
		(width 0.508)
		(layer "F.Cu")
		(net "GND")
	)
	(segment
		(start 35.779456 -265.40079)
		(end 35.79368 -265.415014)
		(width 0.508)
		(layer "F.Cu")
		(net "GND")
	)
	(segment
		(start 227.499926 -500.551958)
		(end 227.499926 -501.670066)
		(width 0.635)
		(layer "F.Cu")
		(net "GND")
	)
	(segment
		(start 5.943346 -162.978846)
		(end 5.421884 -163.500308)
		(width 0.508)
		(layer "F.Cu")
		(net "GND")
	)
	(segment
		(start 35.88766 -261.605014)
		(end 38.245034 -261.605014)
		(width 0.508)
		(layer "F.Cu")
		(net "GND")
	)
	(segment
		(start 3.19405 -410.500322)
		(end 3.192526 -410.498798)
		(width 0.508)
		(layer "F.Cu")
		(net "GND")
	)
	(segment
		(start 5.499354 -171.500292)
		(end 3.19405 -171.500292)
		(width 0.508)
		(layer "F.Cu")
		(net "GND")
	)
	(segment
		(start 20.018248 -333.425038)
		(end 21.74494 -333.425038)
		(width 0.508)
		(layer "F.Cu")
		(net "GND")
	)
	(segment
		(start 5.483606 -118.500398)
		(end 3.19405 -118.500398)
		(width 0.508)
		(layer "F.Cu")
		(net "GND")
	)
	(segment
		(start 7.501128 -261.498588)
		(end 7.501128 -265.855196)
		(width 0.635)
		(layer "F.Cu")
		(net "GND")
	)
	(segment
		(start 21.7551 -16.804894)
		(end 21.75002 -16.799814)
		(width 0.508)
		(layer "F.Cu")
		(net "GND")
	)
	(segment
		(start 39.98976 -72.116696)
		(end 39.987982 -72.114918)
		(width 0.508)
		(layer "F.Cu")
		(net "GND")
	)
	(segment
		(start 19.600164 -446.925446)
		(end 19.59991 -446.9257)
		(width 0.508)
		(layer "F.Cu")
		(net "GND")
	)
	(segment
		(start 60.00115 -479.5393)
		(end 60.00115 -478.31375)
		(width 0.508)
		(layer "F.Cu")
		(net "GND")
	)
	(segment
		(start 40.207946 -112.103408)
		(end 40.207946 -111.295942)
		(width 0.508)
		(layer "F.Cu")
		(net "GND")
	)
	(segment
		(start 3.19405 -360.500422)
		(end 3.192526 -360.498898)
		(width 0.508)
		(layer "F.Cu")
		(net "GND")
	)
	(segment
		(start 3.192526 -177.498756)
		(end 3.19405 -177.50028)
		(width 0.508)
		(layer "F.Cu")
		(net "GND")
	)
	(segment
		(start 26.695146 -370.6241)
		(end 27.431746 -371.3607)
		(width 0.508)
		(layer "F.Cu")
		(net "GND")
	)
	(segment
		(start 3.19405 -118.500398)
		(end 3.192526 -118.498874)
		(width 0.508)
		(layer "F.Cu")
		(net "GND")
	)
	(segment
		(start 38.245034 -261.605014)
		(end 38.250114 -261.610094)
		(width 0.508)
		(layer "F.Cu")
		(net "GND")
	)
	(segment
		(start 252.500892 -37.998654)
		(end 256.8575 -37.998654)
		(width 0.635)
		(layer "F.Cu")
		(net "GND")
	)
	(segment
		(start 35.944048 -481.58019)
		(end 38.250114 -481.58019)
		(width 0.508)
		(layer "F.Cu")
		(net "GND")
	)
	(segment
		(start 29.781246 -435.60746)
		(end 29.781246 -434.87086)
		(width 0.4064)
		(layer "F.Cu")
		(net "GND")
	)
	(segment
		(start 38.250114 -77.199998)
		(end 38.254178 -77.195934)
		(width 0.508)
		(layer "F.Cu")
		(net "GND")
	)
	(segment
		(start 60.972446 -20.6502)
		(end 61.213746 -20.8915)
		(width 0.508)
		(layer "F.Cu")
		(net "GND")
	)
	(segment
		(start 87.248746 -15.2781)
		(end 87.716106 -15.74546)
		(width 0.4064)
		(layer "F.Cu")
		(net "GND")
	)
	(segment
		(start 42.500042 -191.551814)
		(end 42.500042 -192.669922)
		(width 0.635)
		(layer "F.Cu")
		(net "GND")
	)
	(segment
		(start 5.954268 -59.704732)
		(end 3.19024 -59.704732)
		(width 0.7112)
		(layer "F.Cu")
		(net "GND")
	)
	(segment
		(start 252.499622 -475.640146)
		(end 252.499622 -479.996754)
		(width 0.635)
		(layer "F.Cu")
		(net "GND")
	)
	(segment
		(start 194.156584 -187.279788)
		(end 194.156584 -186.917584)
		(width 0.4064)
		(layer "F.Cu")
		(net "GND")
	)
	(segment
		(start 43.421046 -133.3119)
		(end 43.421046 -133.465062)
		(width 0.508)
		(layer "F.Cu")
		(net "GND")
	)
	(segment
		(start 252.500892 -170.998642)
		(end 256.8575 -170.998642)
		(width 0.635)
		(layer "F.Cu")
		(net "GND")
	)
	(segment
		(start 5.968746 -420.8907)
		(end 5.359146 -421.5003)
		(width 0.508)
		(layer "F.Cu")
		(net "GND")
	)
	(segment
		(start 23.481284 -436.425086)
		(end 21.7551 -436.425086)
		(width 0.508)
		(layer "F.Cu")
		(net "GND")
	)
	(segment
		(start 5.364988 -346.499942)
		(end 3.19405 -346.499942)
		(width 0.508)
		(layer "F.Cu")
		(net "GND")
	)
	(segment
		(start 19.600164 -234.158282)
		(end 19.684746 -234.0737)
		(width 0.508)
		(layer "F.Cu")
		(net "GND")
	)
	(segment
		(start 5.841746 -143.6497)
		(end 5.692394 -143.500348)
		(width 0.508)
		(layer "F.Cu")
		(net "GND")
	)
	(segment
		(start 7.746746 -404.39594)
		(end 7.746746 -405.0665)
		(width 0.508)
		(layer "F.Cu")
		(net "GND")
	)
	(segment
		(start 5.292344 -422.500298)
		(end 3.19405 -422.500298)
		(width 0.508)
		(layer "F.Cu")
		(net "GND")
	)
	(segment
		(start 195.001388 -84.826856)
		(end 194.609212 -85.219032)
		(width 0.508)
		(layer "F.Cu")
		(net "GND")
	)
	(segment
		(start 227.499926 -251.670058)
		(end 229.164134 -251.670058)
		(width 0.635)
		(layer "F.Cu")
		(net "GND")
	)
	(segment
		(start 21.5265 -280.543)
		(end 20.447 -280.543)
		(width 0.508)
		(layer "F.Cu")
		(net "GND")
	)
	(segment
		(start 41.147746 -233.9975)
		(end 40.741346 -234.4039)
		(width 0.508)
		(layer "F.Cu")
		(net "GND")
	)
	(segment
		(start 23.613364 -24.424894)
		(end 21.7551 -24.424894)
		(width 0.508)
		(layer "F.Cu")
		(net "GND")
	)
	(segment
		(start 5.969 -59.69)
		(end 5.954268 -59.704732)
		(width 0.7112)
		(layer "F.Cu")
		(net "GND")
	)
	(segment
		(start 15.835884 -107.329986)
		(end 17.500092 -107.329986)
		(width 0.635)
		(layer "F.Cu")
		(net "GND")
	)
	(segment
		(start 5.35813 -413.500316)
		(end 3.19405 -413.500316)
		(width 0.508)
		(layer "F.Cu")
		(net "GND")
	)
	(segment
		(start 3.19405 -133.500368)
		(end 3.192526 -133.498844)
		(width 0.508)
		(layer "F.Cu")
		(net "GND")
	)
	(segment
		(start 80.01 -191.782954)
		(end 80.502506 -192.27546)
		(width 0.4064)
		(layer "F.Cu")
		(net "GND")
	)
	(segment
		(start 5.329428 -380.500382)
		(end 3.19405 -380.500382)
		(width 0.508)
		(layer "F.Cu")
		(net "GND")
	)
	(segment
		(start 19.84248 -428.805086)
		(end 21.74494 -428.805086)
		(width 0.508)
		(layer "F.Cu")
		(net "GND")
	)
	(segment
		(start 21.7551 -433.885086)
		(end 21.75002 -433.880006)
		(width 0.508)
		(layer "F.Cu")
		(net "GND")
	)
	(segment
		(start 42.500042 -295.66997)
		(end 44.16425 -295.66997)
		(width 0.635)
		(layer "F.Cu")
		(net "GND")
	)
	(segment
		(start 192.729612 -86.863936)
		(end 192.729612 -87.63)
		(width 0.508)
		(layer "F.Cu")
		(net "GND")
	)
	(segment
		(start 5.637022 -359.500424)
		(end 3.19405 -359.500424)
		(width 0.508)
		(layer "F.Cu")
		(net "GND")
	)
	(segment
		(start 221.446344 -364.60684)
		(end 221.448122 -364.605062)
		(width 0.508)
		(layer "F.Cu")
		(net "GND")
	)
	(segment
		(start 27.177746 -283.0957)
		(end 26.949146 -282.8671)
		(width 0.4064)
		(layer "F.Cu")
		(net "GND")
	)
	(segment
		(start 61.366146 -25.9207)
		(end 61.975746 -25.9207)
		(width 0.3556)
		(layer "F.Cu")
		(net "GND")
	)
	(segment
		(start 5.968746 -156.985462)
		(end 5.483606 -156.500322)
		(width 0.508)
		(layer "F.Cu")
		(net "GND")
	)
	(segment
		(start 250.698 -415.047684)
		(end 250.698 -414.2486)
		(width 0.508)
		(layer "F.Cu")
		(net "GND")
	)
	(segment
		(start 40.22979 -182.736744)
		(end 40.228012 -182.734966)
		(width 0.508)
		(layer "F.Cu")
		(net "GND")
	)
	(segment
		(start 49.784 -207.01)
		(end 48.056546 -208.737454)
		(width 0.4064)
		(layer "F.Cu")
		(net "GND")
	)
	(segment
		(start 40.835834 -45.669962)
		(end 42.500042 -45.669962)
		(width 0.635)
		(layer "F.Cu")
		(net "GND")
	)
	(segment
		(start 7.501128 -257.14198)
		(end 7.501128 -261.498588)
		(width 0.635)
		(layer "F.Cu")
		(net "GND")
	)
	(segment
		(start 21.74494 -325.805038)
		(end 21.75002 -325.799958)
		(width 0.508)
		(layer "F.Cu")
		(net "GND")
	)
	(segment
		(start 26.669746 -433.225702)
		(end 26.669746 -434.076602)
		(width 0.508)
		(layer "F.Cu")
		(net "GND")
	)
	(segment
		(start 40.835834 -148.67001)
		(end 42.500042 -148.67001)
		(width 0.635)
		(layer "F.Cu")
		(net "GND")
	)
	(segment
		(start 5.943346 -120.97893)
		(end 5.421884 -121.500392)
		(width 0.508)
		(layer "F.Cu")
		(net "GND")
	)
	(segment
		(start 21.7551 -436.425086)
		(end 21.75002 -436.420006)
		(width 0.508)
		(layer "F.Cu")
		(net "GND")
	)
	(segment
		(start 5.968746 -350.901)
		(end 5.968746 -350.824546)
		(width 0.508)
		(layer "F.Cu")
		(net "GND")
	)
	(segment
		(start 40.39997 -266.189968)
		(end 40.39997 -265.435842)
		(width 0.508)
		(layer "F.Cu")
		(net "GND")
	)
	(segment
		(start 20.009866 -333.416656)
		(end 20.018248 -333.425038)
		(width 0.508)
		(layer "F.Cu")
		(net "GND")
	)
	(segment
		(start 55.117746 -175.3362)
		(end 55.117746 -174.3837)
		(width 0.508)
		(layer "F.Cu")
		(net "GND")
	)
	(segment
		(start 28.447746 -300.3677)
		(end 28.447746 -301.7647)
		(width 0.508)
		(layer "F.Cu")
		(net "GND")
	)
	(segment
		(start 27.177746 -283.19984)
		(end 27.177746 -283.0957)
		(width 0.4064)
		(layer "F.Cu")
		(net "GND")
	)
	(segment
		(start 28.643072 -4.499864)
		(end 32.99968 -4.499864)
		(width 0.635)
		(layer "F.Cu")
		(net "GND")
	)
	(segment
		(start 5.943346 -116.978938)
		(end 5.421884 -117.5004)
		(width 0.508)
		(layer "F.Cu")
		(net "GND")
	)
	(segment
		(start 5.912358 -376.9487)
		(end 5.464048 -376.50039)
		(width 0.508)
		(layer "F.Cu")
		(net "GND")
	)
	(segment
		(start 17.500092 -107.329986)
		(end 17.500092 -108.448094)
		(width 0.635)
		(layer "F.Cu")
		(net "GND")
	)
	(segment
		(start 5.841746 -346.9767)
		(end 5.364988 -346.499942)
		(width 0.508)
		(layer "F.Cu")
		(net "GND")
	)
	(segment
		(start 17.500092 -253.211838)
		(end 17.500092 -254.329946)
		(width 0.635)
		(layer "F.Cu")
		(net "GND")
	)
	(segment
		(start 194.839082 -287.388808)
		(end 194.839082 -288.1757)
		(width 0.4064)
		(layer "F.Cu")
		(net "GND")
	)
	(segment
		(start 44.651422 -123.391422)
		(end 44.957746 -123.391422)
		(width 0.4064)
		(layer "F.Cu")
		(net "GND")
	)
	(segment
		(start 3.19024 -56.704738)
		(end 6.666738 -56.704738)
		(width 0.7112)
		(layer "F.Cu")
		(net "GND")
	)
	(segment
		(start 21.5138 -278.7777)
		(end 21.5265 -278.765)
		(width 0.508)
		(layer "F.Cu")
		(net "GND")
	)
	(segment
		(start 3.19405 -129.500376)
		(end 3.192526 -129.498852)
		(width 0.508)
		(layer "F.Cu")
		(net "GND")
	)
	(segment
		(start 24.430736 -38.37051)
		(end 24.406352 -38.394894)
		(width 0.508)
		(layer "F.Cu")
		(net "GND")
	)
	(segment
		(start 227.054918 -62.589918)
		(end 225.399854 -62.589918)
		(width 0.381)
		(layer "F.Cu")
		(net "GND")
	)
	(segment
		(start 191.516 -393.954)
		(end 191.933576 -393.536424)
		(width 0.4064)
		(layer "F.Cu")
		(net "GND")
	)
	(segment
		(start 195.117212 -84.826856)
		(end 195.001388 -84.826856)
		(width 0.508)
		(layer "F.Cu")
		(net "GND")
	)
	(segment
		(start 8.127746 -487.3752)
		(end 7.380986 -487.3752)
		(width 0.3048)
		(layer "F.Cu")
		(net "GND")
	)
	(segment
		(start 38.255194 -182.734966)
		(end 38.250114 -182.740046)
		(width 0.508)
		(layer "F.Cu")
		(net "GND")
	)
	(segment
		(start 69.000878 -479.998532)
		(end 69.000878 -484.35514)
		(width 0.635)
		(layer "F.Cu")
		(net "GND")
	)
	(segment
		(start 3.19405 -363.500416)
		(end 3.192526 -363.498892)
		(width 0.508)
		(layer "F.Cu")
		(net "GND")
	)
	(segment
		(start 5.841746 -369.0747)
		(end 5.841746 -369.010946)
		(width 0.508)
		(layer "F.Cu")
		(net "GND")
	)
	(segment
		(start 61.975746 -25.9207)
		(end 62.356746 -25.5397)
		(width 0.3556)
		(layer "F.Cu")
		(net "GND")
	)
	(segment
		(start 252.501146 -271.498568)
		(end 252.501146 -275.855176)
		(width 0.635)
		(layer "F.Cu")
		(net "GND")
	)
	(segment
		(start 221.176342 -158.67507)
		(end 221.246446 -158.604966)
		(width 0.508)
		(layer "F.Cu")
		(net "GND")
	)
	(segment
		(start 3.19405 -143.500348)
		(end 3.192526 -143.498824)
		(width 0.508)
		(layer "F.Cu")
		(net "GND")
	)
	(segment
		(start 225.835718 -89.669874)
		(end 227.499926 -89.669874)
		(width 0.635)
		(layer "F.Cu")
		(net "GND")
	)
	(segment
		(start 29.194506 -333.1972)
		(end 28.320746 -333.1972)
		(width 0.508)
		(layer "F.Cu")
		(net "GND")
	)
	(segment
		(start 81.548986 -400.6215)
		(end 82.295746 -400.6215)
		(width 0.508)
		(layer "F.Cu")
		(net "GND")
	)
	(segment
		(start 7.746746 -405.0665)
		(end 7.899146 -405.2189)
		(width 0.508)
		(layer "F.Cu")
		(net "GND")
	)
	(segment
		(start 40.835834 -89.669874)
		(end 42.500042 -89.669874)
		(width 0.635)
		(layer "F.Cu")
		(net "GND")
	)
	(segment
		(start 3.19405 -393.500356)
		(end 3.192526 -393.498832)
		(width 0.508)
		(layer "F.Cu")
		(net "GND")
	)
	(segment
		(start 75.057 -84.5185)
		(end 75.1205 -84.582)
		(width 0.508)
		(layer "F.Cu")
		(net "GND")
	)
	(segment
		(start 42.500042 -501.670066)
		(end 44.16425 -501.670066)
		(width 0.635)
		(layer "F.Cu")
		(net "GND")
	)
	(segment
		(start 82.3468 -499.483888)
		(end 83.0834 -499.483888)
		(width 0.4064)
		(layer "F.Cu")
		(net "GND")
	)
	(segment
		(start 6.222746 -352.974402)
		(end 5.69722 -353.499928)
		(width 0.508)
		(layer "F.Cu")
		(net "GND")
	)
	(segment
		(start 252.501146 -271.498568)
		(end 256.857754 -271.498568)
		(width 0.635)
		(layer "F.Cu")
		(net "GND")
	)
	(segment
		(start 19.976084 -325.805038)
		(end 21.74494 -325.805038)
		(width 0.508)
		(layer "F.Cu")
		(net "GND")
	)
	(segment
		(start 5.548376 -406.50033)
		(end 3.19405 -406.50033)
		(width 0.508)
		(layer "F.Cu")
		(net "GND")
	)
	(segment
		(start 24.047958 -347.389958)
		(end 24.384 -347.726)
		(width 0.508)
		(layer "F.Cu")
		(net "GND")
	)
	(segment
		(start 17.500092 -4.329938)
		(end 17.500092 -5.448046)
		(width 0.635)
		(layer "F.Cu")
		(net "GND")
	)
	(segment
		(start 5.421884 -163.500308)
		(end 3.19405 -163.500308)
		(width 0.508)
		(layer "F.Cu")
		(net "GND")
	)
	(segment
		(start 35.941 -435.737)
		(end 35.7632 -435.5592)
		(width 0.4064)
		(layer "F.Cu")
		(net "GND")
	)
	(segment
		(start 97.027746 -12.7381)
		(end 97.241106 -12.95146)
		(width 0.4064)
		(layer "F.Cu")
		(net "GND")
	)
	(segment
		(start 21.74494 -428.805086)
		(end 21.75002 -428.800006)
		(width 0.508)
		(layer "F.Cu")
		(net "GND")
	)
	(segment
		(start 194.156584 -186.917584)
		(end 193.675 -186.436)
		(width 0.4064)
		(layer "F.Cu")
		(net "GND")
	)
	(segment
		(start 24.4094 -351.7011)
		(end 23.904956 -351.196656)
		(width 0.635)
		(layer "F.Cu")
		(net "GND")
	)
	(segment
		(start 40.39997 -64.989964)
		(end 40.385746 -65.004188)
		(width 0.508)
		(layer "F.Cu")
		(net "GND")
	)
	(segment
		(start 32.99968 -4.499864)
		(end 37.356288 -4.499864)
		(width 0.635)
		(layer "F.Cu")
		(net "GND")
	)
	(segment
		(start 3.19405 -177.50028)
		(end 5.600446 -177.50028)
		(width 0.508)
		(layer "F.Cu")
		(net "GND")
	)
	(segment
		(start 21.74494 -323.265038)
		(end 21.75002 -323.259958)
		(width 0.508)
		(layer "F.Cu")
		(net "GND")
	)
	(segment
		(start 194.804284 -186.02833)
		(end 194.690746 -186.141868)
		(width 0.4064)
		(layer "F.Cu")
		(net "GND")
	)
	(segment
		(start 5.968746 -100.985066)
		(end 5.483606 -100.499926)
		(width 0.508)
		(layer "F.Cu")
		(net "GND")
	)
	(segment
		(start 3.19405 -359.500424)
		(end 3.192526 -359.4989)
		(width 0.508)
		(layer "F.Cu")
		(net "GND")
	)
	(segment
		(start 50.936906 -226.1362)
		(end 51.317906 -226.5172)
		(width 0.4064)
		(layer "F.Cu")
		(net "GND")
	)
	(segment
		(start 3.19405 -137.50036)
		(end 3.192526 -137.498836)
		(width 0.508)
		(layer "F.Cu")
		(net "GND")
	)
	(segment
		(start 15.354046 -467.03615)
		(end 15.354046 -468.0077)
		(width 0.508)
		(layer "F.Cu")
		(net "GND")
	)
	(segment
		(start 75.1205 -84.582)
		(end 75.8952 -84.582)
		(width 0.508)
		(layer "F.Cu")
		(net "GND")
	)
	(segment
		(start 3.19405 -406.50033)
		(end 3.192526 -406.498806)
		(width 0.508)
		(layer "F.Cu")
		(net "GND")
	)
	(segment
		(start 3.19405 -160.500314)
		(end 3.192526 -160.49879)
		(width 0.508)
		(layer "F.Cu")
		(net "GND")
	)
	(segment
		(start 5.872734 -387.6802)
		(end 5.692902 -387.500368)
		(width 0.508)
		(layer "F.Cu")
		(net "GND")
	)
	(segment
		(start 3.19405 -425.500292)
		(end 3.192526 -425.498768)
		(width 0.508)
		(layer "F.Cu")
		(net "GND")
	)
	(segment
		(start 227.499926 -295.66997)
		(end 229.164134 -295.66997)
		(width 0.635)
		(layer "F.Cu")
		(net "GND")
	)
	(segment
		(start 57.3786 -80.8736)
		(end 57.382156 -80.877156)
		(width 0.508)
		(layer "F.Cu")
		(net "GND")
	)
	(segment
		(start 5.7912 -137.0584)
		(end 5.34924 -137.50036)
		(width 0.508)
		(layer "F.Cu")
		(net "GND")
	)
	(segment
		(start 23.904956 -351.196656)
		(end 21.753322 -351.196656)
		(width 0.635)
		(layer "F.Cu")
		(net "GND")
	)
	(segment
		(start 3.19405 -110.500414)
		(end 3.192526 -110.49889)
		(width 0.508)
		(layer "F.Cu")
		(net "GND")
	)
	(segment
		(start 3.19405 -117.5004)
		(end 3.192526 -117.498876)
		(width 0.508)
		(layer "F.Cu")
		(net "GND")
	)
	(segment
		(start 5.968746 -408.9527)
		(end 5.395976 -409.52547)
		(width 0.508)
		(layer "F.Cu")
		(net "GND")
	)
	(segment
		(start 3.14452 -78.628494)
		(end 7.501128 -78.628494)
		(width 0.635)
		(layer "F.Cu")
		(net "GND")
	)
	(segment
		(start 3.19405 -379.500384)
		(end 3.192526 -379.49886)
		(width 0.508)
		(layer "F.Cu")
		(net "GND")
	)
	(segment
		(start 40.42664 -491.74019)
		(end 40.429942 -491.736888)
		(width 0.508)
		(layer "F.Cu")
		(net "GND")
	)
	(segment
		(start 33.90265 -336.9945)
		(end 33.90265 -338.1248)
		(width 0.508)
		(layer "F.Cu")
		(net "GND")
	)
	(segment
		(start 19.603466 -340.406736)
		(end 21.04771 -340.406736)
		(width 0.508)
		(layer "F.Cu")
		(net "GND")
	)
	(segment
		(start 42.500042 -45.669962)
		(end 44.16425 -45.669962)
		(width 0.635)
		(layer "F.Cu")
		(net "GND")
	)
	(segment
		(start 51.317906 -226.5172)
		(end 51.673506 -226.5172)
		(width 0.4064)
		(layer "F.Cu")
		(net "GND")
	)
	(segment
		(start 15.835884 -48.32985)
		(end 17.500092 -48.32985)
		(width 0.635)
		(layer "F.Cu")
		(net "GND")
	)
	(segment
		(start 69.000878 -479.998532)
		(end 73.357486 -479.998532)
		(width 0.635)
		(layer "F.Cu")
		(net "GND")
	)
	(segment
		(start 251.56795 -415.010092)
		(end 251.56795 -414.92805)
		(width 0.508)
		(layer "F.Cu")
		(net "GND")
	)
	(segment
		(start 211.53755 -69.8373)
		(end 212.471 -69.8373)
		(width 0.762)
		(layer "F.Cu")
		(net "GND")
	)
	(segment
		(start 4.50088 -479.041968)
		(end 4.50088 -483.398576)
		(width 0.635)
		(layer "F.Cu")
		(net "GND")
	)
	(segment
		(start 3.19405 -380.500382)
		(end 3.192526 -380.498858)
		(width 0.508)
		(layer "F.Cu")
		(net "GND")
	)
	(segment
		(start 19.600164 -445.810132)
		(end 19.600164 -446.925446)
		(width 0.508)
		(layer "F.Cu")
		(net "GND")
	)
	(segment
		(start 192.276984 -188.580268)
		(end 192.276984 -189.189106)
		(width 0.4064)
		(layer "F.Cu")
		(net "GND")
	)
	(segment
		(start 40.835834 -354.670106)
		(end 42.500042 -354.670106)
		(width 0.635)
		(layer "F.Cu")
		(net "GND")
	)
	(segment
		(start 221.246446 -158.604966)
		(end 223.244918 -158.604966)
		(width 0.508)
		(layer "F.Cu")
		(net "GND")
	)
	(segment
		(start 38.255194 -72.114918)
		(end 38.250114 -72.119998)
		(width 0.508)
		(layer "F.Cu")
		(net "GND")
	)
	(segment
		(start 252.500892 -170.998642)
		(end 252.500892 -175.35525)
		(width 0.635)
		(layer "F.Cu")
		(net "GND")
	)
	(segment
		(start 3.19405 -422.500298)
		(end 3.192526 -422.498774)
		(width 0.508)
		(layer "F.Cu")
		(net "GND")
	)
	(segment
		(start 5.968746 -160.985454)
		(end 5.483606 -160.500314)
		(width 0.508)
		(layer "F.Cu")
		(net "GND")
	)
	(segment
		(start 5.614162 -175.500284)
		(end 3.19405 -175.500284)
		(width 0.508)
		(layer "F.Cu")
		(net "GND")
	)
	(segment
		(start 4.50088 -483.398576)
		(end 8.857488 -483.398576)
		(width 0.635)
		(layer "F.Cu")
		(net "GND")
	)
	(segment
		(start 5.421884 -99.499928)
		(end 3.19405 -99.499928)
		(width 0.508)
		(layer "F.Cu")
		(net "GND")
	)
	(segment
		(start 23.702264 -343.154)
		(end 23.279608 -343.576656)
		(width 0.508)
		(layer "F.Cu")
		(net "GND")
	)
	(segment
		(start 3.19405 -383.500376)
		(end 3.192526 -383.498852)
		(width 0.508)
		(layer "F.Cu")
		(net "GND")
	)
	(segment
		(start 3.19405 -396.50035)
		(end 3.192526 -396.498826)
		(width 0.508)
		(layer "F.Cu")
		(net "GND")
	)
	(segment
		(start 57.382156 -80.877156)
		(end 58.8772 -80.877156)
		(width 0.508)
		(layer "F.Cu")
		(net "GND")
	)
	(segment
		(start 227.499926 -397.55191)
		(end 227.499926 -398.670018)
		(width 0.635)
		(layer "F.Cu")
		(net "GND")
	)
	(segment
		(start 227.499926 -148.67001)
		(end 227.499926 -149.788118)
		(width 0.635)
		(layer "F.Cu")
		(net "GND")
	)
	(segment
		(start 207.137 -482.7905)
		(end 206.9465 -482.7905)
		(width 0.508)
		(layer "F.Cu")
		(net "GND")
	)
	(segment
		(start 3.19405 -414.500314)
		(end 3.192526 -414.49879)
		(width 0.508)
		(layer "F.Cu")
		(net "GND")
	)
	(segment
		(start 5.692394 -143.500348)
		(end 3.19405 -143.500348)
		(width 0.508)
		(layer "F.Cu")
		(net "GND")
	)
	(segment
		(start 80.502506 -192.27546)
		(end 80.502506 -192.8749)
		(width 0.4064)
		(layer "F.Cu")
		(net "GND")
	)
	(segment
		(start 3.19405 -121.500392)
		(end 3.192526 -121.498868)
		(width 0.508)
		(layer "F.Cu")
		(net "GND")
	)
	(segment
		(start 3.19405 -114.500406)
		(end 3.192526 -114.498882)
		(width 0.508)
		(layer "F.Cu")
		(net "GND")
	)
	(segment
		(start 69.000878 -273.998436)
		(end 69.000878 -278.355044)
		(width 0.635)
		(layer "F.Cu")
		(net "GND")
	)
	(segment
		(start 5.9944 -103.094282)
		(end 5.9944 -103.0478)
		(width 0.508)
		(layer "F.Cu")
		(net "GND")
	)
	(segment
		(start 227.499926 -89.669874)
		(end 227.499926 -90.787982)
		(width 0.635)
		(layer "F.Cu")
		(net "GND")
	)
	(segment
		(start 35.942524 -481.57511)
		(end 35.940746 -481.576888)
		(width 0.508)
		(layer "F.Cu")
		(net "GND")
	)
	(segment
		(start 3.19405 -175.500284)
		(end 3.192526 -175.49876)
		(width 0.508)
		(layer "F.Cu")
		(net "GND")
	)
	(segment
		(start 21.7551 -38.394894)
		(end 21.75002 -38.389814)
		(width 0.508)
		(layer "F.Cu")
		(net "GND")
	)
	(segment
		(start 45.719746 -419.858698)
		(end 45.719746 -420.595298)
		(width 0.4064)
		(layer "F.Cu")
		(net "GND")
	)
	(segment
		(start 192.306956 -496.512342)
		(end 191.204342 -496.512342)
		(width 0.4064)
		(layer "F.Cu")
		(net "GND")
	)
	(segment
		(start 5.765546 -146.7993)
		(end 5.466588 -146.500342)
		(width 0.508)
		(layer "F.Cu")
		(net "GND")
	)
	(segment
		(start 24.312372 -34.584894)
		(end 21.7551 -34.584894)
		(width 0.508)
		(layer "F.Cu")
		(net "GND")
	)
	(segment
		(start 55.428896 -194.39255)
		(end 56.209946 -193.6115)
		(width 0.508)
		(layer "F.Cu")
		(net "GND")
	)
	(segment
		(start 19.600164 -337.143344)
		(end 19.59991 -337.14309)
		(width 0.508)
		(layer "F.Cu")
		(net "GND")
	)
	(segment
		(start 5.463794 -426.50029)
		(end 6.157976 -427.194472)
		(width 0.508)
		(layer "F.Cu")
		(net "GND")
	)
	(segment
		(start 40.355012 -175.114966)
		(end 38.255194 -175.114966)
		(width 0.508)
		(layer "F.Cu")
		(net "GND")
	)
	(segment
		(start 227.499926 -398.670018)
		(end 229.164134 -398.670018)
		(width 0.635)
		(layer "F.Cu")
		(net "GND")
	)
	(segment
		(start 3.19405 -96.499934)
		(end 3.192526 -96.49841)
		(width 0.508)
		(layer "F.Cu")
		(net "GND")
	)
	(segment
		(start 42.500042 -192.669922)
		(end 44.16425 -192.669922)
		(width 0.635)
		(layer "F.Cu")
		(net "GND")
	)
	(segment
		(start 232.790746 -28.3972)
		(end 232.790746 -29.2227)
		(width 0.508)
		(layer "F.Cu")
		(net "GND")
	)
	(segment
		(start 5.968746 -406.9207)
		(end 5.548376 -406.50033)
		(width 0.508)
		(layer "F.Cu")
		(net "GND")
	)
	(segment
		(start 70.850506 -84.7852)
		(end 70.850506 -85.714586)
		(width 0.4064)
		(layer "F.Cu")
		(net "GND")
	)
	(segment
		(start 6.222746 -378.9807)
		(end 5.703062 -379.500384)
		(width 0.508)
		(layer "F.Cu")
		(net "GND")
	)
	(segment
		(start 42.500042 -147.551902)
		(end 42.500042 -148.67001)
		(width 0.635)
		(layer "F.Cu")
		(net "GND")
	)
	(segment
		(start 3.19405 -125.500384)
		(end 3.192526 -125.49886)
		(width 0.508)
		(layer "F.Cu")
		(net "GND")
	)
	(segment
		(start 5.39242 -384.500374)
		(end 3.19405 -384.500374)
		(width 0.508)
		(layer "F.Cu")
		(net "GND")
	)
	(segment
		(start 24.406352 -38.394894)
		(end 21.7551 -38.394894)
		(width 0.508)
		(layer "F.Cu")
		(net "GND")
	)
	(segment
		(start 3.19405 -384.500374)
		(end 3.192526 -384.49885)
		(width 0.508)
		(layer "F.Cu")
		(net "GND")
	)
	(segment
		(start 38.250114 -257.800094)
		(end 40.198294 -257.800094)
		(width 0.508)
		(layer "F.Cu")
		(net "GND")
	)
	(segment
		(start 75.401932 -496.881912)
		(end 75.401932 -494.684812)
		(width 0.508)
		(layer "F.Cu")
		(net "GND")
	)
	(segment
		(start 5.421884 -117.5004)
		(end 3.19405 -117.5004)
		(width 0.508)
		(layer "F.Cu")
		(net "GND")
	)
	(segment
		(start 227.499926 -501.670066)
		(end 229.164134 -501.670066)
		(width 0.635)
		(layer "F.Cu")
		(net "GND")
	)
	(segment
		(start 81.802986 -194.7545)
		(end 82.539586 -194.7545)
		(width 0.508)
		(layer "F.Cu")
		(net "GND")
	)
	(segment
		(start 5.968746 -172.98543)
		(end 5.483606 -172.50029)
		(width 0.508)
		(layer "F.Cu")
		(net "GND")
	)
	(segment
		(start 42.500042 -354.670106)
		(end 42.500042 -355.788214)
		(width 0.635)
		(layer "F.Cu")
		(net "GND")
	)
	(segment
		(start 5.968746 -414.883346)
		(end 5.585714 -414.500314)
		(width 0.508)
		(layer "F.Cu")
		(net "GND")
	)
	(segment
		(start 23.279608 -343.576656)
		(end 21.753322 -343.576656)
		(width 0.508)
		(layer "F.Cu")
		(net "GND")
	)
	(segment
		(start 11.683746 -500.5197)
		(end 11.683746 -500.7483)
		(width 0.508)
		(layer "F.Cu")
		(net "GND")
	)
	(segment
		(start 21.753322 -351.196656)
		(end 21.75002 -351.199958)
		(width 0.635)
		(layer "F.Cu")
		(net "GND")
	)
	(segment
		(start 3.19405 -353.499928)
		(end 3.192526 -353.498404)
		(width 0.508)
		(layer "F.Cu")
		(net "GND")
	)
	(segment
		(start 227.499926 -88.551766)
		(end 227.499926 -89.669874)
		(width 0.635)
		(layer "F.Cu")
		(net "GND")
	)
	(segment
		(start 80.263746 -497.4717)
		(end 80.396334 -497.604288)
		(width 0.4064)
		(layer "F.Cu")
		(net "GND")
	)
	(segment
		(start 40.39997 -169.011346)
		(end 40.399716 -169.0116)
		(width 0.508)
		(layer "F.Cu")
		(net "GND")
	)
	(segment
		(start 40.39997 -268.590014)
		(end 40.403272 -268.586712)
		(width 0.508)
		(layer "F.Cu")
		(net "GND")
	)
	(segment
		(start 5.421884 -113.500408)
		(end 3.19405 -113.500408)
		(width 0.508)
		(layer "F.Cu")
		(net "GND")
	)
	(segment
		(start 38.245034 -55.604918)
		(end 38.250114 -55.609998)
		(width 0.508)
		(layer "F.Cu")
		(net "GND")
	)
	(segment
		(start 5.422138 -417.500308)
		(end 3.19405 -417.500308)
		(width 0.508)
		(layer "F.Cu")
		(net "GND")
	)
	(segment
		(start 42.500042 -148.67001)
		(end 42.500042 -149.788118)
		(width 0.635)
		(layer "F.Cu")
		(net "GND")
	)
	(segment
		(start 3.19405 -100.499926)
		(end 3.192526 -100.498402)
		(width 0.508)
		(layer "F.Cu")
		(net "GND")
	)
	(segment
		(start 38.254178 -79.735934)
		(end 39.5224 -79.735934)
		(width 0.508)
		(layer "F.Cu")
		(net "GND")
	)
	(segment
		(start 42.500042 -45.669962)
		(end 42.500042 -46.78807)
		(width 0.635)
		(layer "F.Cu")
		(net "GND")
	)
	(segment
		(start 5.841746 -413.0167)
		(end 5.35813 -413.500316)
		(width 0.508)
		(layer "F.Cu")
		(net "GND")
	)
	(segment
		(start 40.39997 -371.590062)
		(end 38.738048 -371.590062)
		(width 0.381)
		(layer "F.Cu")
		(net "GND")
	)
	(segment
		(start 62.610746 -20.4597)
		(end 61.645546 -20.4597)
		(width 0.508)
		(layer "F.Cu")
		(net "GND")
	)
	(segment
		(start 17.500092 -416.33013)
		(end 17.500092 -417.448238)
		(width 0.635)
		(layer "F.Cu")
		(net "GND")
	)
	(segment
		(start 5.968746 -350.824546)
		(end 5.644134 -350.499934)
		(width 0.508)
		(layer "F.Cu")
		(net "GND")
	)
	(segment
		(start 21.753322 -343.576656)
		(end 21.75002 -343.579958)
		(width 0.508)
		(layer "F.Cu")
		(net "GND")
	)
	(segment
		(start 21.7551 -426.265086)
		(end 21.75002 -426.260006)
		(width 0.508)
		(layer "F.Cu")
		(net "GND")
	)
	(segment
		(start 7.501128 -78.628494)
		(end 11.857736 -78.628494)
		(width 0.635)
		(layer "F.Cu")
		(net "GND")
	)
	(segment
		(start 19.938746 -166.1287)
		(end 19.500596 -166.56685)
		(width 0.508)
		(layer "F.Cu")
		(net "GND")
	)
	(segment
		(start 42.500042 -397.55191)
		(end 42.500042 -398.670018)
		(width 0.635)
		(layer "F.Cu")
		(net "GND")
	)
	(segment
		(start 71.104506 -188.0362)
		(end 70.367906 -188.0362)
		(width 0.508)
		(layer "F.Cu")
		(net "GND")
	)
	(segment
		(start 225.835718 -398.670018)
		(end 227.499926 -398.670018)
		(width 0.635)
		(layer "F.Cu")
		(net "GND")
	)
	(segment
		(start 48.640746 -224.564702)
		(end 50.418746 -224.564702)
		(width 0.508)
		(layer "F.Cu")
		(net "GND")
	)
	(segment
		(start 15.835884 -254.329946)
		(end 17.500092 -254.329946)
		(width 0.635)
		(layer "F.Cu")
		(net "GND")
	)
	(segment
		(start 42.500042 -148.67001)
		(end 44.16425 -148.67001)
		(width 0.635)
		(layer "F.Cu")
		(net "GND")
	)
	(segment
		(start 26.949146 -282.8671)
		(end 26.949146 -282.38704)
		(width 0.4064)
		(layer "F.Cu")
		(net "GND")
	)
	(segment
		(start 41.624758 -139.564872)
		(end 40.876728 -139.564872)
		(width 0.3556)
		(layer "F.Cu")
		(net "GND")
	)
	(segment
		(start 5.968746 -361.0737)
		(end 5.968746 -360.933746)
		(width 0.508)
		(layer "F.Cu")
		(net "GND")
	)
	(segment
		(start 223.244918 -158.604966)
		(end 223.249998 -158.610046)
		(width 0.508)
		(layer "F.Cu")
		(net "GND")
	)
	(segment
		(start 227.499926 -147.551902)
		(end 227.499926 -148.67001)
		(width 0.635)
		(layer "F.Cu")
		(net "GND")
	)
	(segment
		(start 35.873436 -261.59079)
		(end 35.88766 -261.605014)
		(width 0.508)
		(layer "F.Cu")
		(net "GND")
	)
	(segment
		(start 5.85216 -427.500288)
		(end 3.19405 -427.500288)
		(width 0.508)
		(layer "F.Cu")
		(net "GND")
	)
	(segment
		(start 3.19405 -171.500292)
		(end 3.192526 -171.498768)
		(width 0.508)
		(layer "F.Cu")
		(net "GND")
	)
	(segment
		(start 221.446344 -467.606888)
		(end 221.448122 -467.60511)
		(width 0.508)
		(layer "F.Cu")
		(net "GND")
	)
	(segment
		(start 97.241106 -12.95146)
		(end 98.488246 -12.95146)
		(width 0.4064)
		(layer "F.Cu")
		(net "GND")
	)
	(segment
		(start 80.248506 -89.4969)
		(end 79.511906 -89.4969)
		(width 0.4064)
		(layer "F.Cu")
		(net "GND")
	)
	(segment
		(start 98.246946 -10.56894)
		(end 98.246946 -11.43)
		(width 0.4064)
		(layer "F.Cu")
		(net "GND")
	)
	(segment
		(start 40.39997 -270.99006)
		(end 40.39997 -271.8816)
		(width 0.508)
		(layer "F.Cu")
		(net "GND")
	)
	(segment
		(start 3.14452 -261.498588)
		(end 7.501128 -261.498588)
		(width 0.635)
		(layer "F.Cu")
		(net "GND")
	)
	(segment
		(start 21.335746 -340.1187)
		(end 21.88591 -340.1187)
		(width 0.508)
		(layer "F.Cu")
		(net "GND")
	)
	(segment
		(start 5.58927 -383.500376)
		(end 3.19405 -383.500376)
		(width 0.508)
		(layer "F.Cu")
		(net "GND")
	)
	(segment
		(start 58.12155 -379.3363)
		(end 59.0931 -379.3363)
		(width 0.508)
		(layer "F.Cu")
		(net "GND")
	)
	(segment
		(start 5.968746 -126.985522)
		(end 5.483606 -126.500382)
		(width 0.508)
		(layer "F.Cu")
		(net "GND")
	)
	(segment
		(start 36.340034 -180.194966)
		(end 38.245034 -180.194966)
		(width 0.508)
		(layer "F.Cu")
		(net "GND")
	)
	(segment
		(start 61.645546 -20.8915)
		(end 61.213746 -20.8915)
		(width 0.508)
		(layer "F.Cu")
		(net "GND")
	)
	(segment
		(start 23.875746 -14.8717)
		(end 23.26894 -14.264894)
		(width 0.508)
		(layer "F.Cu")
		(net "GND")
	)
	(segment
		(start 252.500892 -37.998654)
		(end 252.500892 -42.355262)
		(width 0.635)
		(layer "F.Cu")
		(net "GND")
	)
	(segment
		(start 42.500042 -192.669922)
		(end 42.500042 -193.78803)
		(width 0.635)
		(layer "F.Cu")
		(net "GND")
	)
	(segment
		(start 42.500042 -457.670154)
		(end 44.16425 -457.670154)
		(width 0.635)
		(layer "F.Cu")
		(net "GND")
	)
	(segment
		(start 3.19405 -113.500408)
		(end 3.192526 -113.498884)
		(width 0.508)
		(layer "F.Cu")
		(net "GND")
	)
	(segment
		(start 64.64427 -376.998484)
		(end 69.000878 -376.998484)
		(width 0.635)
		(layer "F.Cu")
		(net "GND")
	)
	(segment
		(start 251.968 -418.084)
		(end 251.993908 -418.109908)
		(width 0.508)
		(layer "F.Cu")
		(net "GND")
	)
	(segment
		(start 195.002912 -84.712556)
		(end 195.117212 -84.826856)
		(width 0.508)
		(layer "F.Cu")
		(net "GND")
	)
	(segment
		(start 5.703062 -379.500384)
		(end 3.19405 -379.500384)
		(width 0.508)
		(layer "F.Cu")
		(net "GND")
	)
	(segment
		(start 252.0442 -425.6024)
		(end 252.171708 -425.729908)
		(width 0.508)
		(layer "F.Cu")
		(net "GND")
	)
	(segment
		(start 56.209946 -193.6115)
		(end 56.209946 -193.1797)
		(width 0.508)
		(layer "F.Cu")
		(net "GND")
	)
	(segment
		(start 5.483606 -164.500306)
		(end 3.19405 -164.500306)
		(width 0.508)
		(layer "F.Cu")
		(net "GND")
	)
	(segment
		(start 30.733746 -300.3677)
		(end 30.733746 -301.7647)
		(width 0.508)
		(layer "F.Cu")
		(net "GND")
	)
	(segment
		(start 21.04771 -340.406736)
		(end 21.335746 -340.1187)
		(width 0.508)
		(layer "F.Cu")
		(net "GND")
	)
	(segment
		(start 3.19405 -421.5003)
		(end 3.192526 -421.498776)
		(width 0.508)
		(layer "F.Cu")
		(net "GND")
	)
	(segment
		(start 227.499926 -353.551998)
		(end 227.499926 -354.670106)
		(width 0.635)
		(layer "F.Cu")
		(net "GND")
	)
	(segment
		(start 227.499926 -457.670154)
		(end 229.164134 -457.670154)
		(width 0.635)
		(layer "F.Cu")
		(net "GND")
	)
	(segment
		(start 5.841746 -423.0497)
		(end 5.292344 -422.500298)
		(width 0.508)
		(layer "F.Cu")
		(net "GND")
	)
	(segment
		(start 17.500092 -254.329946)
		(end 17.500092 -255.448054)
		(width 0.635)
		(layer "F.Cu")
		(net "GND")
	)
	(segment
		(start 43.421046 -133.465062)
		(end 42.787062 -134.099046)
		(width 0.508)
		(layer "F.Cu")
		(net "GND")
	)
	(segment
		(start 49.288446 -453.73925)
		(end 49.288446 -455.3204)
		(width 0.508)
		(layer "F.Cu")
		(net "GND")
	)
	(segment
		(start 40.492934 -489.196888)
		(end 40.491156 -489.19511)
		(width 0.508)
		(layer "F.Cu")
		(net "GND")
	)
	(segment
		(start 227.499926 -294.551862)
		(end 227.499926 -295.66997)
		(width 0.635)
		(layer "F.Cu")
		(net "GND")
	)
	(segment
		(start 23.621746 -24.416512)
		(end 23.613364 -24.424894)
		(width 0.508)
		(layer "F.Cu")
		(net "GND")
	)
	(segment
		(start 40.35679 -175.116744)
		(end 40.355012 -175.114966)
		(width 0.508)
		(layer "F.Cu")
		(net "GND")
	)
	(segment
		(start 33.197546 -308.242462)
		(end 33.197546 -307.505862)
		(width 0.508)
		(layer "F.Cu")
		(net "GND")
	)
	(segment
		(start 199.501506 -84.60994)
		(end 199.501506 -83.2612)
		(width 0.4064)
		(layer "F.Cu")
		(net "GND")
	)
	(segment
		(start 194.609212 -85.219032)
		(end 194.609212 -85.563456)
		(width 0.508)
		(layer "F.Cu")
		(net "GND")
	)
	(segment
		(start 251.333508 -418.084)
		(end 251.968 -418.084)
		(width 0.508)
		(layer "F.Cu")
		(net "GND")
	)
	(segment
		(start 207.264 -276.606)
		(end 206.756 -276.098)
		(width 0.508)
		(layer "F.Cu")
		(net "GND")
	)
	(segment
		(start 17.500092 -415.212022)
		(end 17.500092 -416.33013)
		(width 0.635)
		(layer "F.Cu")
		(net "GND")
	)
	(segment
		(start 59.007756 -481.041202)
		(end 59.007756 -480.190302)
		(width 0.508)
		(layer "F.Cu")
		(net "GND")
	)
	(segment
		(start 248.143014 -479.996754)
		(end 252.499622 -479.996754)
		(width 0.635)
		(layer "F.Cu")
		(net "GND")
	)
	(segment
		(start 42.500042 -44.551854)
		(end 42.500042 -45.669962)
		(width 0.635)
		(layer "F.Cu")
		(net "GND")
	)
	(segment
		(start 6.095746 -359.0417)
		(end 5.637022 -359.500424)
		(width 0.508)
		(layer "F.Cu")
		(net "GND")
	)
	(segment
		(start 3.19405 -159.500316)
		(end 3.192526 -159.498792)
		(width 0.508)
		(layer "F.Cu")
		(net "GND")
	)
	(segment
		(start 5.968746 -164.985446)
		(end 5.483606 -164.500306)
		(width 0.508)
		(layer "F.Cu")
		(net "GND")
	)
	(segment
		(start 42.500042 -89.669874)
		(end 42.500042 -90.787982)
		(width 0.635)
		(layer "F.Cu")
		(net "GND")
	)
	(segment
		(start 3.19405 -364.500414)
		(end 3.192526 -364.49889)
		(width 0.508)
		(layer "F.Cu")
		(net "GND")
	)
	(segment
		(start 221.436946 -55.609998)
		(end 221.433644 -55.606696)
		(width 0.508)
		(layer "F.Cu")
		(net "GND")
	)
	(segment
		(start 221.171516 -261.605014)
		(end 223.244918 -261.605014)
		(width 0.508)
		(layer "F.Cu")
		(net "GND")
	)
	(segment
		(start 52.844446 -350.69145)
		(end 52.844446 -351.9297)
		(width 0.508)
		(layer "F.Cu")
		(net "GND")
	)
	(segment
		(start 248.144284 -37.998654)
		(end 252.500892 -37.998654)
		(width 0.635)
		(layer "F.Cu")
		(net "GND")
	)
	(segment
		(start 5.807456 -425.0817)
		(end 5.388864 -425.500292)
		(width 0.508)
		(layer "F.Cu")
		(net "GND")
	)
	(segment
		(start 223.244918 -364.605062)
		(end 223.249998 -364.610142)
		(width 0.508)
		(layer "F.Cu")
		(net "GND")
	)
	(segment
		(start 5.849112 -373.019066)
		(end 5.330444 -372.500398)
		(width 0.508)
		(layer "F.Cu")
		(net "GND")
	)
	(segment
		(start 5.421884 -133.500368)
		(end 3.19405 -133.500368)
		(width 0.508)
		(layer "F.Cu")
		(net "GND")
	)
	(segment
		(start 227.499926 -45.669962)
		(end 229.164134 -45.669962)
		(width 0.635)
		(layer "F.Cu")
		(net "GND")
	)
	(segment
		(start 17.500092 -3.21183)
		(end 17.500092 -4.329938)
		(width 0.635)
		(layer "F.Cu")
		(net "GND")
	)
	(segment
		(start 5.477002 -306.704746)
		(end 5.8928 -307.120544)
		(width 0.7112)
		(layer "F.Cu")
		(net "GND")
	)
	(segment
		(start 225.835718 -192.669922)
		(end 227.499926 -192.669922)
		(width 0.635)
		(layer "F.Cu")
		(net "GND")
	)
	(segment
		(start 5.57403 -363.500416)
		(end 3.19405 -363.500416)
		(width 0.508)
		(layer "F.Cu")
		(net "GND")
	)
	(segment
		(start 79.9465 -191.7065)
		(end 80.01 -191.643)
		(width 0.508)
		(layer "F.Cu")
		(net "GND")
	)
	(segment
		(start 62.610492 -81.054956)
		(end 64.24549 -81.054956)
		(width 0.508)
		(layer "F.Cu")
		(net "GND")
	)
	(segment
		(start 23.5966 -426.256704)
		(end 23.588218 -426.265086)
		(width 0.508)
		(layer "F.Cu")
		(net "GND")
	)
	(segment
		(start 19.600164 -237.40999)
		(end 21.166074 -237.40999)
		(width 0.381)
		(layer "F.Cu")
		(net "GND")
	)
	(segment
		(start 40.39997 -265.435842)
		(end 40.512746 -265.323066)
		(width 0.508)
		(layer "F.Cu")
		(net "GND")
	)
	(segment
		(start 6.600444 -176.500282)
		(end 6.603746 -176.49698)
		(width 0.508)
		(layer "F.Cu")
		(net "GND")
	)
	(segment
		(start 250.7488 -425.6024)
		(end 252.0442 -425.6024)
		(width 0.508)
		(layer "F.Cu")
		(net "GND")
	)
	(segment
		(start 6.095746 -175.0187)
		(end 5.614162 -175.500284)
		(width 0.508)
		(layer "F.Cu")
		(net "GND")
	)
	(segment
		(start 223.244918 -261.605014)
		(end 223.249998 -261.610094)
		(width 0.508)
		(layer "F.Cu")
		(net "GND")
	)
	(segment
		(start 48.056546 -208.737454)
		(end 48.056546 -211.214462)
		(width 0.4064)
		(layer "F.Cu")
		(net "GND")
	)
	(segment
		(start 19.500596 -166.56685)
		(end 18.808446 -166.56685)
		(width 0.508)
		(layer "F.Cu")
		(net "GND")
	)
	(segment
		(start 35.79368 -265.415014)
		(end 38.245034 -265.415014)
		(width 0.508)
		(layer "F.Cu")
		(net "GND")
	)
	(segment
		(start 252.500892 -166.642034)
		(end 252.500892 -170.998642)
		(width 0.635)
		(layer "F.Cu")
		(net "GND")
	)
	(segment
		(start 64.64427 -479.998532)
		(end 69.000878 -479.998532)
		(width 0.635)
		(layer "F.Cu")
		(net "GND")
	)
	(segment
		(start 23.489666 -436.416704)
		(end 23.481284 -436.425086)
		(width 0.508)
		(layer "F.Cu")
		(net "GND")
	)
	(segment
		(start 3.19405 -109.500416)
		(end 3.192526 -109.498892)
		(width 0.508)
		(layer "F.Cu")
		(net "GND")
	)
	(segment
		(start 252.499622 -479.996754)
		(end 256.85623 -479.996754)
		(width 0.635)
		(layer "F.Cu")
		(net "GND")
	)
	(segment
		(start 40.228012 -182.734966)
		(end 38.255194 -182.734966)
		(width 0.508)
		(layer "F.Cu")
		(net "GND")
	)
	(segment
		(start 5.330444 -372.500398)
		(end 3.19405 -372.500398)
		(width 0.508)
		(layer "F.Cu")
		(net "GND")
	)
	(segment
		(start 225.835718 -295.66997)
		(end 227.499926 -295.66997)
		(width 0.635)
		(layer "F.Cu")
		(net "GND")
	)
	(segment
		(start 71.295006 -493.44834)
		(end 71.297546 -493.4458)
		(width 0.4064)
		(layer "F.Cu")
		(net "GND")
	)
	(segment
		(start 227.499926 -354.670106)
		(end 229.164134 -354.670106)
		(width 0.635)
		(layer "F.Cu")
		(net "GND")
	)
	(segment
		(start 35.940746 -481.576888)
		(end 35.944048 -481.58019)
		(width 0.508)
		(layer "F.Cu")
		(net "GND")
	)
	(segment
		(start 23.621746 -21.876512)
		(end 23.613364 -21.884894)
		(width 0.508)
		(layer "F.Cu")
		(net "GND")
	)
	(segment
		(start 23.589742 -433.876704)
		(end 23.58136 -433.885086)
		(width 0.508)
		(layer "F.Cu")
		(net "GND")
	)
	(segment
		(start 17.500092 -151.329898)
		(end 19.1643 -151.329898)
		(width 0.635)
		(layer "F.Cu")
		(net "GND")
	)
	(segment
		(start 225.835718 -457.670154)
		(end 227.499926 -457.670154)
		(width 0.635)
		(layer "F.Cu")
		(net "GND")
	)
	(segment
		(start 50.546 -207.01)
		(end 49.784 -207.01)
		(width 0.4064)
		(layer "F.Cu")
		(net "GND")
	)
	(segment
		(start 5.94741 -416.975036)
		(end 5.422138 -417.500308)
		(width 0.508)
		(layer "F.Cu")
		(net "GND")
	)
	(segment
		(start 5.943346 -108.978954)
		(end 5.421884 -109.500416)
		(width 0.508)
		(layer "F.Cu")
		(net "GND")
	)
	(segment
		(start 227.499926 -398.670018)
		(end 227.499926 -399.788126)
		(width 0.635)
		(layer "F.Cu")
		(net "GND")
	)
	(segment
		(start 42.500042 -89.669874)
		(end 44.16425 -89.669874)
		(width 0.635)
		(layer "F.Cu")
		(net "GND")
	)
	(segment
		(start 69.000878 -269.641828)
		(end 69.000878 -273.998436)
		(width 0.635)
		(layer "F.Cu")
		(net "GND")
	)
	(segment
		(start 40.835834 -295.66997)
		(end 42.500042 -295.66997)
		(width 0.635)
		(layer "F.Cu")
		(net "GND")
	)
	(segment
		(start 21.75002 -244.38991)
		(end 21.748242 -244.391688)
		(width 0.508)
		(layer "F.Cu")
		(net "GND")
	)
	(segment
		(start 17.500092 -150.21179)
		(end 17.500092 -151.329898)
		(width 0.635)
		(layer "F.Cu")
		(net "GND")
	)
	(segment
		(start 17.500092 -47.211742)
		(end 17.500092 -48.32985)
		(width 0.635)
		(layer "F.Cu")
		(net "GND")
	)
	(segment
		(start 40.385746 -65.004188)
		(end 40.385746 -65.9892)
		(width 0.508)
		(layer "F.Cu")
		(net "GND")
	)
	(segment
		(start 83.819746 -495.6937)
		(end 83.291172 -495.165126)
		(width 0.4064)
		(layer "F.Cu")
		(net "GND")
	)
	(segment
		(start 45.561504 -20.936712)
		(end 44.703746 -20.936712)
		(width 0.508)
		(layer "F.Cu")
		(net "GND")
	)
	(segment
		(start 3.19405 -168.500298)
		(end 3.192526 -168.498774)
		(width 0.508)
		(layer "F.Cu")
		(net "GND")
	)
	(segment
		(start 36.364164 -51.794918)
		(end 38.245034 -51.794918)
		(width 0.508)
		(layer "F.Cu")
		(net "GND")
	)
	(segment
		(start 75.692 -187.7695)
		(end 75.692 -188.849)
		(width 0.508)
		(layer "F.Cu")
		(net "GND")
	)
	(segment
		(start 71.297546 -493.4458)
		(end 72.031606 -493.4458)
		(width 0.4064)
		(layer "F.Cu")
		(net "GND")
	)
	(segment
		(start 36.34994 -51.780694)
		(end 36.364164 -51.794918)
		(width 0.508)
		(layer "F.Cu")
		(net "GND")
	)
	(segment
		(start 6.044946 -158.9913)
		(end 5.53593 -159.500316)
		(width 0.508)
		(layer "F.Cu")
		(net "GND")
	)
	(segment
		(start 28.701746 -280.4287)
		(end 28.828746 -280.5557)
		(width 0.508)
		(layer "F.Cu")
		(net "GND")
	)
	(segment
		(start 5.483606 -114.500406)
		(end 3.19405 -114.500406)
		(width 0.508)
		(layer "F.Cu")
		(net "GND")
	)
	(segment
		(start 42.500042 -353.551998)
		(end 42.500042 -354.670106)
		(width 0.635)
		(layer "F.Cu")
		(net "GND")
	)
	(segment
		(start 5.968746 -130.985514)
		(end 5.483606 -130.500374)
		(width 0.508)
		(layer "F.Cu")
		(net "GND")
	)
	(segment
		(start 40.39997 -167.990012)
		(end 40.39997 -169.011346)
		(width 0.508)
		(layer "F.Cu")
		(net "GND")
	)
	(segment
		(start 21.135086 -441.01004)
		(end 21.361146 -441.2361)
		(width 0.381)
		(layer "F.Cu")
		(net "GND")
	)
	(segment
		(start 191.503046 -457.528676)
		(end 191.503046 -456.741276)
		(width 0.508)
		(layer "F.Cu")
		(net "GND")
	)
	(segment
		(start 5.943346 -124.978922)
		(end 5.421884 -125.500384)
		(width 0.508)
		(layer "F.Cu")
		(net "GND")
	)
	(segment
		(start 3.19405 -372.500398)
		(end 3.192526 -372.498874)
		(width 0.508)
		(layer "F.Cu")
		(net "GND")
	)
	(segment
		(start 212.28685 -377.5837)
		(end 212.50275 -377.7996)
		(width 0.508)
		(layer "F.Cu")
		(net "GND")
	)
	(segment
		(start 49.161446 -41.92905)
		(end 50.266346 -41.92905)
		(width 0.508)
		(layer "F.Cu")
		(net "GND")
	)
	(segment
		(start 6.019546 -170.9801)
		(end 5.499354 -171.500292)
		(width 0.508)
		(layer "F.Cu")
		(net "GND")
	)
	(segment
		(start 69.000878 -67.998594)
		(end 73.357486 -67.998594)
		(width 0.635)
		(layer "F.Cu")
		(net "GND")
	)
	(segment
		(start 169.265346 -459.901036)
		(end 167.525446 -459.901036)
		(width 0.3048)
		(layer "F.Cu")
		(net "GND")
	)
	(segment
		(start 3.19405 -418.500306)
		(end 3.192526 -418.498782)
		(width 0.508)
		(layer "F.Cu")
		(net "GND")
	)
	(segment
		(start 199.374506 -185.1152)
		(end 199.374506 -186.3217)
		(width 0.4064)
		(layer "F.Cu")
		(net "GND")
	)
	(segment
		(start 5.943346 -132.978906)
		(end 5.421884 -133.500368)
		(width 0.508)
		(layer "F.Cu")
		(net "GND")
	)
	(segment
		(start 24.336756 -34.56051)
		(end 24.312372 -34.584894)
		(width 0.508)
		(layer "F.Cu")
		(net "GND")
	)
	(segment
		(start 36.242752 -55.590694)
		(end 36.256976 -55.604918)
		(width 0.508)
		(layer "F.Cu")
		(net "GND")
	)
	(segment
		(start 3.19405 -126.500382)
		(end 3.192526 -126.498858)
		(width 0.508)
		(layer "F.Cu")
		(net "GND")
	)
	(segment
		(start 252.196092 -414.299908)
		(end 255.474978 -414.299908)
		(width 0.508)
		(layer "F.Cu")
		(net "GND")
	)
	(segment
		(start 5.943346 -98.978466)
		(end 5.421884 -99.499928)
		(width 0.508)
		(layer "F.Cu")
		(net "GND")
	)
	(segment
		(start 5.523484 -167.5003)
		(end 3.19405 -167.5003)
		(width 0.508)
		(layer "F.Cu")
		(net "GND")
	)
	(segment
		(start 221.448122 -364.605062)
		(end 223.244918 -364.605062)
		(width 0.508)
		(layer "F.Cu")
		(net "GND")
	)
	(segment
		(start 5.34924 -137.50036)
		(end 3.19405 -137.50036)
		(width 0.508)
		(layer "F.Cu")
		(net "GND")
	)
	(segment
		(start 3.19405 -163.500308)
		(end 3.192526 -163.498784)
		(width 0.508)
		(layer "F.Cu")
		(net "GND")
	)
	(segment
		(start 39.987982 -72.114918)
		(end 38.255194 -72.114918)
		(width 0.508)
		(layer "F.Cu")
		(net "GND")
	)
	(segment
		(start 55.117492 -72.101456)
		(end 54.228746 -72.101456)
		(width 0.508)
		(layer "F.Cu")
		(net "GND")
	)
	(segment
		(start 5.968746 -134.985506)
		(end 5.483606 -134.500366)
		(width 0.508)
		(layer "F.Cu")
		(net "GND")
	)
	(segment
		(start 23.588218 -16.804894)
		(end 21.7551 -16.804894)
		(width 0.508)
		(layer "F.Cu")
		(net "GND")
	)
	(segment
		(start 234.073446 -453.35825)
		(end 234.073446 -454.27265)
		(width 0.508)
		(layer "F.Cu")
		(net "GND")
	)
	(segment
		(start 42.4688 -474.472)
		(end 42.35069 -474.59011)
		(width 0.381)
		(layer "F.Cu")
		(net "GND")
	)
	(segment
		(start 69.000878 -63.641986)
		(end 69.000878 -67.998594)
		(width 0.635)
		(layer "F.Cu")
		(net "GND")
	)
	(segment
		(start 62.610746 -21.8567)
		(end 61.645546 -20.8915)
		(width 0.508)
		(layer "F.Cu")
		(net "GND")
	)
	(segment
		(start 252.171708 -425.729908)
		(end 255.474978 -425.729908)
		(width 0.508)
		(layer "F.Cu")
		(net "GND")
	)
	(segment
		(start 5.968746 -415.0487)
		(end 5.968746 -414.883346)
		(width 0.508)
		(layer "F.Cu")
		(net "GND")
	)
	(segment
		(start 3.19405 -146.500342)
		(end 3.192526 -146.498818)
		(width 0.508)
		(layer "F.Cu")
		(net "GND")
	)
	(segment
		(start 28.462986 -307.432202)
		(end 29.209746 -307.432202)
		(width 0.508)
		(layer "F.Cu")
		(net "GND")
	)
	(segment
		(start 5.904992 -396.50035)
		(end 3.19405 -396.50035)
		(width 0.508)
		(layer "F.Cu")
		(net "GND")
	)
	(segment
		(start 6.157976 -427.194472)
		(end 5.85216 -427.500288)
		(width 0.508)
		(layer "F.Cu")
		(net "GND")
	)
	(segment
		(start 3.19405 -376.50039)
		(end 3.192526 -376.498866)
		(width 0.508)
		(layer "F.Cu")
		(net "GND")
	)
	(segment
		(start 6.095746 -418.9857)
		(end 5.610352 -418.500306)
		(width 0.508)
		(layer "F.Cu")
		(net "GND")
	)
	(segment
		(start 21.74494 -333.425038)
		(end 21.75002 -333.419958)
		(width 0.508)
		(layer "F.Cu")
		(net "GND")
	)
	(segment
		(start 31.222188 -309.6387)
		(end 31.317946 -309.542942)
		(width 0.508)
		(layer "F.Cu")
		(net "GND")
	)
	(segment
		(start 62.610746 -184.4167)
		(end 64.134746 -184.4167)
		(width 0.508)
		(layer "F.Cu")
		(net "GND")
	)
	(segment
		(start 3.19405 -367.500408)
		(end 3.192526 -367.498884)
		(width 0.508)
		(layer "F.Cu")
		(net "GND")
	)
	(segment
		(start 225.835718 -45.669962)
		(end 227.499926 -45.669962)
		(width 0.635)
		(layer "F.Cu")
		(net "GND")
	)
	(segment
		(start 5.466588 -146.500342)
		(end 3.19405 -146.500342)
		(width 0.508)
		(layer "F.Cu")
		(net "GND")
	)
	(segment
		(start 5.968746 -96.985074)
		(end 5.483606 -96.499934)
		(width 0.508)
		(layer "F.Cu")
		(net "GND")
	)
	(segment
		(start 47.244 -417.576)
		(end 47.244 -418.202872)
		(width 0.4064)
		(layer "F.Cu")
		(net "GND")
	)
	(segment
		(start 15.835884 -4.329938)
		(end 17.500092 -4.329938)
		(width 0.635)
		(layer "F.Cu")
		(net "GND")
	)
	(segment
		(start 51.180746 -25.7302)
		(end 51.180746 -26.5557)
		(width 0.508)
		(layer "F.Cu")
		(net "GND")
	)
	(segment
		(start 19.600164 -340.410038)
		(end 19.603466 -340.406736)
		(width 0.508)
		(layer "F.Cu")
		(net "GND")
	)
	(segment
		(start 5.841746 -365.0107)
		(end 5.33146 -364.500414)
		(width 0.508)
		(layer "F.Cu")
		(net "GND")
	)
	(segment
		(start 83.291172 -495.165126)
		(end 83.050634 -495.165126)
		(width 0.4064)
		(layer "F.Cu")
		(net "GND")
	)
	(segment
		(start 5.968746 -168.985438)
		(end 5.483606 -168.500298)
		(width 0.508)
		(layer "F.Cu")
		(net "GND")
	)
	(segment
		(start 225.835718 -501.670066)
		(end 227.499926 -501.670066)
		(width 0.635)
		(layer "F.Cu")
		(net "GND")
	)
	(segment
		(start 26.288746 -330.546202)
		(end 26.288746 -331.4827)
		(width 0.508)
		(layer "F.Cu")
		(net "GND")
	)
	(segment
		(start 17.500092 -254.329946)
		(end 19.1643 -254.329946)
		(width 0.635)
		(layer "F.Cu")
		(net "GND")
	)
	(segment
		(start 227.457 -437.261)
		(end 228.727 -437.261)
		(width 0.508)
		(layer "F.Cu")
		(net "GND")
	)
	(segment
		(start 240.512346 -30.4165)
		(end 240.537746 -30.3911)
		(width 0.508)
		(layer "F.Cu")
		(net "GND")
	)
	(segment
		(start 23.26894 -14.264894)
		(end 21.7551 -14.264894)
		(width 0.508)
		(layer "F.Cu")
		(net "GND")
	)
	(segment
		(start 42.35069 -474.59011)
		(end 40.39997 -474.59011)
		(width 0.381)
		(layer "F.Cu")
		(net "GND")
	)
	(segment
		(start 42.087546 -109.042454)
		(end 42.087546 -109.995462)
		(width 0.508)
		(layer "F.Cu")
		(net "GND")
	)
	(segment
		(start 5.4229 -371.525546)
		(end 5.397754 -371.5004)
		(width 0.508)
		(layer "F.Cu")
		(net "GND")
	)
	(segment
		(start 5.585714 -414.500314)
		(end 3.19405 -414.500314)
		(width 0.508)
		(layer "F.Cu")
		(net "GND")
	)
	(segment
		(start 20.447 -278.7777)
		(end 21.5138 -278.7777)
		(width 0.508)
		(layer "F.Cu")
		(net "GND")
	)
	(segment
		(start 80.396334 -497.604288)
		(end 81.04632 -497.604288)
		(width 0.4064)
		(layer "F.Cu")
		(net "GND")
	)
	(segment
		(start 5.535422 -360.500422)
		(end 3.19405 -360.500422)
		(width 0.508)
		(layer "F.Cu")
		(net "GND")
	)
	(segment
		(start 21.74494 -330.885038)
		(end 21.75002 -330.879958)
		(width 0.508)
		(layer "F.Cu")
		(net "GND")
	)
	(segment
		(start 19.600164 -235.009944)
		(end 19.600164 -234.158282)
		(width 0.508)
		(layer "F.Cu")
		(net "GND")
	)
	(segment
		(start 40.403272 -268.586712)
		(end 42.0624 -268.586712)
		(width 0.508)
		(layer "F.Cu")
		(net "GND")
	)
	(segment
		(start 42.291 -108.839)
		(end 42.087546 -109.042454)
		(width 0.508)
		(layer "F.Cu")
		(net "GND")
	)
	(segment
		(start 4.635246 -492.7727)
		(end 3.809746 -492.7727)
		(width 0.508)
		(layer "F.Cu")
		(net "GND")
	)
	(segment
		(start 227.499926 -192.669922)
		(end 229.164134 -192.669922)
		(width 0.635)
		(layer "F.Cu")
		(net "GND")
	)
	(segment
		(start 5.331206 -368.500406)
		(end 3.19405 -368.500406)
		(width 0.508)
		(layer "F.Cu")
		(net "GND")
	)
	(segment
		(start 7.501128 -74.271886)
		(end 7.501128 -78.628494)
		(width 0.635)
		(layer "F.Cu")
		(net "GND")
	)
	(segment
		(start 227.499926 -45.669962)
		(end 227.499926 -46.78807)
		(width 0.635)
		(layer "F.Cu")
		(net "GND")
	)
	(segment
		(start 19.938746 -323.4817)
		(end 20.155408 -323.265038)
		(width 0.508)
		(layer "F.Cu")
		(net "GND")
	)
	(segment
		(start 80.01 -191.643)
		(end 80.01 -191.782954)
		(width 0.4064)
		(layer "F.Cu")
		(net "GND")
	)
	(segment
		(start 251.916692 -413.029908)
		(end 255.474978 -413.029908)
		(width 0.508)
		(layer "F.Cu")
		(net "GND")
	)
	(segment
		(start 40.491156 -489.19511)
		(end 38.255194 -489.19511)
		(width 0.508)
		(layer "F.Cu")
		(net "GND")
	)
	(segment
		(start 49.161446 -247.89765)
		(end 50.526696 -247.89765)
		(width 0.508)
		(layer "F.Cu")
		(net "GND")
	)
	(segment
		(start 20.018248 -330.885038)
		(end 21.74494 -330.885038)
		(width 0.508)
		(layer "F.Cu")
		(net "GND")
	)
	(segment
		(start 42.500042 -398.670018)
		(end 42.500042 -399.788126)
		(width 0.635)
		(layer "F.Cu")
		(net "GND")
	)
	(segment
		(start 38.250114 -79.739998)
		(end 38.254178 -79.735934)
		(width 0.508)
		(layer "F.Cu")
		(net "GND")
	)
	(segment
		(start 227.499926 -295.66997)
		(end 227.499926 -296.788078)
		(width 0.635)
		(layer "F.Cu")
		(net "GND")
	)
	(segment
		(start 38.245034 -180.194966)
		(end 38.250114 -180.200046)
		(width 0.508)
		(layer "F.Cu")
		(net "GND")
	)
	(segment
		(start 5.600446 -177.50028)
		(end 6.600444 -176.500282)
		(width 0.508)
		(layer "F.Cu")
		(net "GND")
	)
	(segment
		(start 8.826246 -156.4767)
		(end 8.826246 -157.231842)
		(width 0.508)
		(layer "F.Cu")
		(net "GND")
	)
	(segment
		(start 55.625492 -80.800956)
		(end 54.372002 -80.800956)
		(width 0.508)
		(layer "F.Cu")
		(net "GND")
	)
	(segment
		(start 40.198294 -257.800094)
		(end 40.2082 -257.81)
		(width 0.508)
		(layer "F.Cu")
		(net "GND")
	)
	(segment
		(start 42.500042 -354.670106)
		(end 44.16425 -354.670106)
		(width 0.635)
		(layer "F.Cu")
		(net "GND")
	)
	(segment
		(start 6.02615 -166.997634)
		(end 5.523484 -167.5003)
		(width 0.508)
		(layer "F.Cu")
		(net "GND")
	)
	(segment
		(start 252.501146 -267.14196)
		(end 252.501146 -271.498568)
		(width 0.635)
		(layer "F.Cu")
		(net "GND")
	)
	(segment
		(start 5.483606 -168.500298)
		(end 3.19405 -168.500298)
		(width 0.508)
		(layer "F.Cu")
		(net "GND")
	)
	(segment
		(start 5.968746 -410.9847)
		(end 5.484368 -410.500322)
		(width 0.508)
		(layer "F.Cu")
		(net "GND")
	)
	(segment
		(start 17.500092 -106.211878)
		(end 17.500092 -107.329986)
		(width 0.635)
		(layer "F.Cu")
		(net "GND")
	)
	(segment
		(start 191.933576 -393.536424)
		(end 192.818258 -393.536424)
		(width 0.4064)
		(layer "F.Cu")
		(net "GND")
	)
	(segment
		(start 21.75002 -347.389958)
		(end 24.047958 -347.389958)
		(width 0.508)
		(layer "F.Cu")
		(net "GND")
	)
	(segment
		(start 3.19405 -134.500366)
		(end 3.192526 -134.498842)
		(width 0.508)
		(layer "F.Cu")
		(net "GND")
	)
	(segment
		(start 82.105246 -189.51194)
		(end 82.105246 -190.24854)
		(width 0.508)
		(layer "F.Cu")
		(net "GND")
	)
	(segment
		(start 208.918048 -461.054958)
		(end 208.914746 -461.051656)
		(width 0.3556)
		(layer "F.Cu")
		(net "GND")
	)
	(segment
		(start 5.33146 -364.500414)
		(end 3.19405 -364.500414)
		(width 0.508)
		(layer "F.Cu")
		(net "GND")
	)
	(segment
		(start 194.195446 -289.179)
		(end 194.183 -289.191446)
		(width 0.4064)
		(layer "F.Cu")
		(net "GND")
	)
	(segment
		(start 28.828746 -280.5557)
		(end 28.828746 -281.08656)
		(width 0.508)
		(layer "F.Cu")
		(net "GND")
	)
	(segment
		(start 29.527246 -279.17394)
		(end 29.527246 -280.0477)
		(width 0.508)
		(layer "F.Cu")
		(net "GND")
	)
	(segment
		(start 42.500042 -501.670066)
		(end 42.500042 -502.788174)
		(width 0.635)
		(layer "F.Cu")
		(net "GND")
	)
	(segment
		(start 6.178042 -396.2273)
		(end 5.904992 -396.50035)
		(width 0.508)
		(layer "F.Cu")
		(net "GND")
	)
	(segment
		(start 19.600164 -441.01004)
		(end 21.135086 -441.01004)
		(width 0.381)
		(layer "F.Cu")
		(net "GND")
	)
	(segment
		(start 28.701746 -280.34996)
		(end 28.701746 -280.4287)
		(width 0.508)
		(layer "F.Cu")
		(net "GND")
	)
	(segment
		(start 38.245034 -265.415014)
		(end 38.250114 -265.420094)
		(width 0.508)
		(layer "F.Cu")
		(net "GND")
	)
	(segment
		(start 5.483606 -96.499934)
		(end 3.19405 -96.499934)
		(width 0.508)
		(layer "F.Cu")
		(net "GND")
	)
	(segment
		(start 57.66435 -172.256704)
		(end 57.505346 -172.0977)
		(width 0.508)
		(layer "F.Cu")
		(net "GND")
	)
	(segment
		(start 5.397754 -371.5004)
		(end 3.19405 -371.5004)
		(width 0.508)
		(layer "F.Cu")
		(net "GND")
	)
	(segment
		(start 3.19405 -156.500322)
		(end 3.192526 -156.498798)
		(width 0.508)
		(layer "F.Cu")
		(net "GND")
	)
	(segment
		(start 5.421884 -121.500392)
		(end 3.19405 -121.500392)
		(width 0.508)
		(layer "F.Cu")
		(net "GND")
	)
	(segment
		(start 199.262746 -84.8487)
		(end 199.501506 -84.60994)
		(width 0.4064)
		(layer "F.Cu")
		(net "GND")
	)
	(segment
		(start 5.343144 -349.499936)
		(end 3.19405 -349.499936)
		(width 0.508)
		(layer "F.Cu")
		(net "GND")
	)
	(segment
		(start 248.144284 -170.998642)
		(end 252.500892 -170.998642)
		(width 0.635)
		(layer "F.Cu")
		(net "GND")
	)
	(segment
		(start 5.483606 -134.500366)
		(end 3.19405 -134.500366)
		(width 0.508)
		(layer "F.Cu")
		(net "GND")
	)
	(segment
		(start 19.8374 -428.800006)
		(end 19.84248 -428.805086)
		(width 0.508)
		(layer "F.Cu")
		(net "GND")
	)
	(segment
		(start 36.194746 -484.116888)
		(end 36.196524 -484.11511)
		(width 0.508)
		(layer "F.Cu")
		(net "GND")
	)
	(segment
		(start 227.499926 -250.55195)
		(end 227.499926 -251.670058)
		(width 0.635)
		(layer "F.Cu")
		(net "GND")
	)
	(segment
		(start 5.968746 -367.0427)
		(end 5.511038 -367.500408)
		(width 0.508)
		(layer "F.Cu")
		(net "GND")
	)
	(segment
		(start 38.255194 -489.19511)
		(end 38.250114 -489.20019)
		(width 0.508)
		(layer "F.Cu")
		(net "GND")
	)
	(segment
		(start 17.500092 -107.329986)
		(end 19.1643 -107.329986)
		(width 0.635)
		(layer "F.Cu")
		(net "GND")
	)
	(via
		(at 6.044946 -158.9913)
		(size 0.5588)
		(drill 0.3048)
		(layers "F.Cu" "B.Cu")
		(net "GND")
	)
	(via
		(at 156.895546 -251.0155)
		(size 0.7112)
		(drill 0.4064)
		(layers "F.Cu" "B.Cu")
		(net "GND")
	)
	(via
		(at 118.109746 -471.2843)
		(size 0.7112)
		(drill 0.4064)
		(layers "F.Cu" "B.Cu")
		(net "GND")
	)
	(via
		(at 245.566946 -148.6789)
		(size 0.7112)
		(drill 0.4064)
		(layers "F.Cu" "B.Cu")
		(net "GND")
	)
	(via
		(at 243.534946 -42.5069)
		(size 0.7112)
		(drill 0.4064)
		(layers "F.Cu" "B.Cu")
		(net "GND")
	)
	(via
		(at 65.150746 -150.2537)
		(size 0.7112)
		(drill 0.4064)
		(layers "F.Cu" "B.Cu")
		(net "GND")
	)
	(via
		(at 237.235746 -128.6637)
		(size 0.7112)
		(drill 0.4064)
		(layers "F.Cu" "B.Cu")
		(net "GND")
	)
	(via
		(at 203.834746 -206.8957)
		(size 0.7112)
		(drill 0.4064)
		(layers "F.Cu" "B.Cu")
		(net "GND")
	)
	(via
		(at 129.082546 -409.0543)
		(size 0.7112)
		(drill 0.4064)
		(layers "F.Cu" "B.Cu")
		(net "GND")
	)
	(via
		(at 171.373546 -274.4343)
		(size 0.7112)
		(drill 0.4064)
		(layers "F.Cu" "B.Cu")
		(net "GND")
	)
	(via
		(at 72.770746 -341.6427)
		(size 0.7112)
		(drill 0.4064)
		(layers "F.Cu" "B.Cu")
		(net "GND")
	)
	(via
		(at 158.800546 -378.2441)
		(size 0.7112)
		(drill 0.4064)
		(layers "F.Cu" "B.Cu")
		(net "GND")
	)
	(via
		(at 43.586146 -289.5473)
		(size 0.7112)
		(drill 0.4064)
		(layers "F.Cu" "B.Cu")
		(net "GND")
	)
	(via
		(at 118.312946 -11.1125)
		(size 0.7112)
		(drill 0.4064)
		(layers "F.Cu" "B.Cu")
		(net "GND")
	)
	(via
		(at 31.368746 -35.5727)
		(size 0.7112)
		(drill 0.4064)
		(layers "F.Cu" "B.Cu")
		(net "GND")
	)
	(via
		(at 245.3894 -397.764)
		(size 0.7112)
		(drill 0.4064)
		(layers "F.Cu" "B.Cu")
		(net "GND")
	)
	(via
		(at 122.173746 -446.0367)
		(size 0.7112)
		(drill 0.4064)
		(layers "F.Cu" "B.Cu")
		(net "GND")
	)
	(via
		(at 159.5628 -81.28)
		(size 0.7112)
		(drill 0.4064)
		(layers "F.Cu" "B.Cu")
		(net "GND")
	)
	(via
		(at 133.095746 -353.3267)
		(size 0.7112)
		(drill 0.4064)
		(layers "F.Cu" "B.Cu")
		(net "GND")
	)
	(via
		(at 107.441746 -199.4027)
		(size 0.7112)
		(drill 0.4064)
		(layers "F.Cu" "B.Cu")
		(net "GND")
	)
	(via
		(at 7.619746 -176.4157)
		(size 0.5588)
		(drill 0.3048)
		(layers "F.Cu" "B.Cu")
		(net "GND")
	)
	(via
		(at 147.294346 -95.4405)
		(size 0.7112)
		(drill 0.4064)
		(layers "F.Cu" "B.Cu")
		(net "GND")
	)
	(via
		(at 187.756546 -342.6333)
		(size 0.7112)
		(drill 0.4064)
		(layers "F.Cu" "B.Cu")
		(net "GND")
	)
	(via
		(at 192.074546 -129.3241)
		(size 0.7112)
		(drill 0.4064)
		(layers "F.Cu" "B.Cu")
		(net "GND")
	)
	(via
		(at 105.689146 -300.6217)
		(size 0.7112)
		(drill 0.4064)
		(layers "F.Cu" "B.Cu")
		(net "GND")
	)
	(via
		(at 137.642346 -259.4483)
		(size 0.7112)
		(drill 0.4064)
		(layers "F.Cu" "B.Cu")
		(net "GND")
	)
	(via
		(at 139.064746 -202.9587)
		(size 0.7112)
		(drill 0.4064)
		(layers "F.Cu" "B.Cu")
		(net "GND")
	)
	(via
		(at 210.184746 -79.609696)
		(size 0.5588)
		(drill 0.3048)
		(layers "F.Cu" "B.Cu")
		(net "GND")
	)
	(via
		(at 78.104746 -137.4267)
		(size 0.7112)
		(drill 0.4064)
		(layers "F.Cu" "B.Cu")
		(net "GND")
	)
	(via
		(at 76.631546 -354.5205)
		(size 0.7112)
		(drill 0.4064)
		(layers "F.Cu" "B.Cu")
		(net "GND")
	)
	(via
		(at 53.720746 -314.7187)
		(size 0.7112)
		(drill 0.4064)
		(layers "F.Cu" "B.Cu")
		(net "GND")
	)
	(via
		(at 218.465146 -329.0443)
		(size 0.7112)
		(drill 0.4064)
		(layers "F.Cu" "B.Cu")
		(net "GND")
	)
	(via
		(at 5.968746 -110.985554)
		(size 0.5588)
		(drill 0.3048)
		(layers "F.Cu" "B.Cu")
		(net "GND")
	)
	(via
		(at 255.345946 -53.8353)
		(size 0.7112)
		(drill 0.4064)
		(layers "F.Cu" "B.Cu")
		(net "GND")
	)
	(via
		(at 78.231746 -204.0001)
		(size 0.7112)
		(drill 0.4064)
		(layers "F.Cu" "B.Cu")
		(net "GND")
	)
	(via
		(at 9.8044 -477.5708)
		(size 0.7112)
		(drill 0.4064)
		(layers "F.Cu" "B.Cu")
		(net "GND")
	)
	(via
		(at 186.384946 -193.4083)
		(size 0.7112)
		(drill 0.4064)
		(layers "F.Cu" "B.Cu")
		(net "GND")
	)
	(via
		(at 107.949746 -319.9257)
		(size 0.7112)
		(drill 0.4064)
		(layers "F.Cu" "B.Cu")
		(net "GND")
	)
	(via
		(at 260.1722 -346.7608)
		(size 0.7112)
		(drill 0.4064)
		(layers "F.Cu" "B.Cu")
		(net "GND")
	)
	(via
		(at 42.3672 -61.1632)
		(size 0.7112)
		(drill 0.4064)
		(layers "F.Cu" "B.Cu")
		(net "GND")
	)
	(via
		(at 116.839746 -472.9607)
		(size 0.7112)
		(drill 0.3556)
		(layers "F.Cu" "B.Cu")
		(net "GND")
	)
	(via
		(at 202.437746 -37.3507)
		(size 0.7112)
		(drill 0.4064)
		(layers "F.Cu" "B.Cu")
		(net "GND")
	)
	(via
		(at 242.010946 -86.9061)
		(size 0.7112)
		(drill 0.4064)
		(layers "F.Cu" "B.Cu")
		(net "GND")
	)
	(via
		(at 253.644146 -282.1813)
		(size 0.7112)
		(drill 0.4064)
		(layers "F.Cu" "B.Cu")
		(net "GND")
	)
	(via
		(at 174.497746 -373.0879)
		(size 0.7112)
		(drill 0.4064)
		(layers "F.Cu" "B.Cu")
		(net "GND")
	)
	(via
		(at 214.884 -460.0956)
		(size 0.7112)
		(drill 0.3556)
		(layers "F.Cu" "B.Cu")
		(net "GND")
	)
	(via
		(at 153.415746 -8.9789)
		(size 0.7112)
		(drill 0.4064)
		(layers "F.Cu" "B.Cu")
		(net "GND")
	)
	(via
		(at 190.499746 -177.8127)
		(size 0.7112)
		(drill 0.4064)
		(layers "F.Cu" "B.Cu")
		(net "GND")
	)
	(via
		(at 207.670146 -11.1125)
		(size 0.7112)
		(drill 0.4064)
		(layers "F.Cu" "B.Cu")
		(net "GND")
	)
	(via
		(at 106.374946 -227.5967)
		(size 0.7112)
		(drill 0.4064)
		(layers "F.Cu" "B.Cu")
		(net "GND")
	)
	(via
		(at 213.435946 -109.4613)
		(size 0.7112)
		(drill 0.4064)
		(layers "F.Cu" "B.Cu")
		(net "GND")
	)
	(via
		(at 122.9868 -401.2946)
		(size 0.7112)
		(drill 0.4064)
		(layers "F.Cu" "B.Cu")
		(net "GND")
	)
	(via
		(at 21.332952 -237.243112)
		(size 0.7112)
		(drill 0.4064)
		(layers "F.Cu" "B.Cu")
		(net "GND")
	)
	(via
		(at 189.940946 -448.7545)
		(size 0.7112)
		(drill 0.4064)
		(layers "F.Cu" "B.Cu")
		(net "GND")
	)
	(via
		(at 218.642184 -172.372528)
		(size 0.7112)
		(drill 0.4064)
		(layers "F.Cu" "B.Cu")
		(net "GND")
	)
	(via
		(at 202.005946 -336.9691)
		(size 0.7112)
		(drill 0.4064)
		(layers "F.Cu" "B.Cu")
		(net "GND")
	)
	(via
		(at 154.660346 -331.4827)
		(size 0.7112)
		(drill 0.4064)
		(layers "F.Cu" "B.Cu")
		(net "GND")
	)
	(via
		(at 227.583746 -182.8927)
		(size 0.7112)
		(drill 0.4064)
		(layers "F.Cu" "B.Cu")
		(net "GND")
	)
	(via
		(at 48.361346 -175.0187)
		(size 0.7112)
		(drill 0.4064)
		(layers "F.Cu" "B.Cu")
		(net "GND")
	)
	(via
		(at 5.968746 -6.8707)
		(size 0.7112)
		(drill 0.4064)
		(layers "F.Cu" "B.Cu")
		(net "GND")
	)
	(via
		(at 248.030746 -305.9557)
		(size 0.7112)
		(drill 0.4064)
		(layers "F.Cu" "B.Cu")
		(net "GND")
	)
	(via
		(at 79.654146 -475.0435)
		(size 0.7112)
		(drill 0.4064)
		(layers "F.Cu" "B.Cu")
		(net "GND")
	)
	(via
		(at 181.000146 -132.3467)
		(size 0.7112)
		(drill 0.4064)
		(layers "F.Cu" "B.Cu")
		(net "GND")
	)
	(via
		(at 44.703746 -20.936712)
		(size 0.5588)
		(drill 0.3048)
		(layers "F.Cu" "B.Cu")
		(net "GND")
	)
	(via
		(at 3.047746 -17.5387)
		(size 0.7112)
		(drill 0.4064)
		(layers "F.Cu" "B.Cu")
		(net "GND")
	)
	(via
		(at 23.6728 -129.667)
		(size 0.5588)
		(drill 0.3048)
		(layers "F.Cu" "B.Cu")
		(net "GND")
	)
	(via
		(at 246.760746 -496.8367)
		(size 0.7112)
		(drill 0.4064)
		(layers "F.Cu" "B.Cu")
		(net "GND")
	)
	(via
		(at 36.677346 -297.4721)
		(size 0.7112)
		(drill 0.4064)
		(layers "F.Cu" "B.Cu")
		(net "GND")
	)
	(via
		(at 204.698346 -371.9195)
		(size 0.7112)
		(drill 0.4064)
		(layers "F.Cu" "B.Cu")
		(net "GND")
	)
	(via
		(at 252.221746 -227.2157)
		(size 0.7112)
		(drill 0.4064)
		(layers "F.Cu" "B.Cu")
		(net "GND")
	)
	(via
		(at 10.921746 -70.0151)
		(size 0.7112)
		(drill 0.4064)
		(layers "F.Cu" "B.Cu")
		(net "GND")
	)
	(via
		(at 75.183746 -240.9317)
		(size 0.7112)
		(drill 0.3556)
		(layers "F.Cu" "B.Cu")
		(net "GND")
	)
	(via
		(at 159.384746 -76.0857)
		(size 0.7112)
		(drill 0.4064)
		(layers "F.Cu" "B.Cu")
		(net "GND")
	)
	(via
		(at 38.937946 -239.7125)
		(size 0.7112)
		(drill 0.4064)
		(layers "F.Cu" "B.Cu")
		(net "GND")
	)
	(via
		(at 12.075922 -146.89836)
		(size 0.5588)
		(drill 0.3048)
		(layers "F.Cu" "B.Cu")
		(net "GND")
	)
	(via
		(at 100.583746 -1.4097)
		(size 0.7112)
		(drill 0.4064)
		(layers "F.Cu" "B.Cu")
		(net "GND")
	)
	(via
		(at 245.3894 -393.065)
		(size 0.7112)
		(drill 0.4064)
		(layers "F.Cu" "B.Cu")
		(net "GND")
	)
	(via
		(at 242.696746 -480.8347)
		(size 0.7112)
		(drill 0.4064)
		(layers "F.Cu" "B.Cu")
		(net "GND")
	)
	(via
		(at 19.946366 -454.180702)
		(size 0.7112)
		(drill 0.4064)
		(layers "F.Cu" "B.Cu")
		(net "GND")
	)
	(via
		(at 115.442746 -116.3447)
		(size 0.7112)
		(drill 0.4064)
		(layers "F.Cu" "B.Cu")
		(net "GND")
	)
	(via
		(at 255.218946 -91.8083)
		(size 0.7112)
		(drill 0.4064)
		(layers "F.Cu" "B.Cu")
		(net "GND")
	)
	(via
		(at 187.451746 -301.6377)
		(size 0.7112)
		(drill 0.4064)
		(layers "F.Cu" "B.Cu")
		(net "GND")
	)
	(via
		(at 202.336146 -31.3563)
		(size 0.7112)
		(drill 0.4064)
		(layers "F.Cu" "B.Cu")
		(net "GND")
	)
	(via
		(at 124.586746 -117.8687)
		(size 0.7112)
		(drill 0.4064)
		(layers "F.Cu" "B.Cu")
		(net "GND")
	)
	(via
		(at 118.871746 -1.4097)
		(size 0.7112)
		(drill 0.4064)
		(layers "F.Cu" "B.Cu")
		(net "GND")
	)
	(via
		(at 107.771946 -391.5029)
		(size 0.7112)
		(drill 0.4064)
		(layers "F.Cu" "B.Cu")
		(net "GND")
	)
	(via
		(at 95.706946 -440.4487)
		(size 0.7112)
		(drill 0.4064)
		(layers "F.Cu" "B.Cu")
		(net "GND")
	)
	(via
		(at 249.935746 -108.4707)
		(size 0.7112)
		(drill 0.4064)
		(layers "F.Cu" "B.Cu")
		(net "GND")
	)
	(via
		(at 202.564746 -27.9527)
		(size 0.7112)
		(drill 0.4064)
		(layers "F.Cu" "B.Cu")
		(net "GND")
	)
	(via
		(at 222.452946 -98.1075)
		(size 0.7112)
		(drill 0.4064)
		(layers "F.Cu" "B.Cu")
		(net "GND")
	)
	(via
		(at 241.248946 -446.0875)
		(size 0.7112)
		(drill 0.4064)
		(layers "F.Cu" "B.Cu")
		(net "GND")
	)
	(via
		(at 6.705346 -190.7159)
		(size 0.7112)
		(drill 0.4064)
		(layers "F.Cu" "B.Cu")
		(net "GND")
	)
	(via
		(at 136.042146 -271.6657)
		(size 0.7112)
		(drill 0.4064)
		(layers "F.Cu" "B.Cu")
		(net "GND")
	)
	(via
		(at 244.2464 -394.4366)
		(size 0.7112)
		(drill 0.4064)
		(layers "F.Cu" "B.Cu")
		(net "GND")
	)
	(via
		(at 188.099446 -457.869036)
		(size 0.7112)
		(drill 0.4064)
		(layers "F.Cu" "B.Cu")
		(net "GND")
	)
	(via
		(at 107.441746 -207.5307)
		(size 0.7112)
		(drill 0.4064)
		(layers "F.Cu" "B.Cu")
		(net "GND")
	)
	(via
		(at 109.981746 -1.5367)
		(size 0.7112)
		(drill 0.4064)
		(layers "F.Cu" "B.Cu")
		(net "GND")
	)
	(via
		(at 218.439746 -198.6407)
		(size 0.7112)
		(drill 0.4064)
		(layers "F.Cu" "B.Cu")
		(net "GND")
	)
	(via
		(at 245.871746 -18.5547)
		(size 0.7112)
		(drill 0.4064)
		(layers "F.Cu" "B.Cu")
		(net "GND")
	)
	(via
		(at 130.606546 -461.2005)
		(size 0.7112)
		(drill 0.4064)
		(layers "F.Cu" "B.Cu")
		(net "GND")
	)
	(via
		(at 210.489546 -232.0163)
		(size 0.7112)
		(drill 0.4064)
		(layers "F.Cu" "B.Cu")
		(net "GND")
	)
	(via
		(at 245.566946 -143.8529)
		(size 0.7112)
		(drill 0.4064)
		(layers "F.Cu" "B.Cu")
		(net "GND")
	)
	(via
		(at 57.784746 -500.6467)
		(size 0.7112)
		(drill 0.4064)
		(layers "F.Cu" "B.Cu")
		(net "GND")
	)
	(via
		(at 154.177746 -197.6247)
		(size 0.7112)
		(drill 0.4064)
		(layers "F.Cu" "B.Cu")
		(net "GND")
	)
	(via
		(at 196.723 -454.152)
		(size 0.5588)
		(drill 0.3048)
		(layers "F.Cu" "B.Cu")
		(net "GND")
	)
	(via
		(at 184.276746 -36.4617)
		(size 0.7112)
		(drill 0.4064)
		(layers "F.Cu" "B.Cu")
		(net "GND")
	)
	(via
		(at 242.849146 -46.0629)
		(size 0.7112)
		(drill 0.4064)
		(layers "F.Cu" "B.Cu")
		(net "GND")
	)
	(via
		(at 137.388346 -254.1143)
		(size 0.7112)
		(drill 0.4064)
		(layers "F.Cu" "B.Cu")
		(net "GND")
	)
	(via
		(at 79.0956 -4.3434)
		(size 0.5588)
		(drill 0.3048)
		(layers "F.Cu" "B.Cu")
		(net "GND")
	)
	(via
		(at 26.543508 -134.760208)
		(size 0.5588)
		(drill 0.3048)
		(layers "F.Cu" "B.Cu")
		(net "GND")
	)
	(via
		(at 212.1281 -172.1231)
		(size 0.5588)
		(drill 0.3048)
		(layers "F.Cu" "B.Cu")
		(net "GND")
	)
	(via
		(at 184.276746 -319.9511)
		(size 0.7112)
		(drill 0.4064)
		(layers "F.Cu" "B.Cu")
		(net "GND")
	)
	(via
		(at 191.896746 -148.7551)
		(size 0.7112)
		(drill 0.4064)
		(layers "F.Cu" "B.Cu")
		(net "GND")
	)
	(via
		(at 60.8076 -412.5722)
		(size 0.7112)
		(drill 0.4064)
		(layers "F.Cu" "B.Cu")
		(net "GND")
	)
	(via
		(at 74.853546 -251.3457)
		(size 0.7112)
		(drill 0.4064)
		(layers "F.Cu" "B.Cu")
		(net "GND")
	)
	(via
		(at 189.153546 -474.5863)
		(size 0.7112)
		(drill 0.4064)
		(layers "F.Cu" "B.Cu")
		(net "GND")
	)
	(via
		(at 23.6474 -145.19656)
		(size 0.7112)
		(drill 0.4064)
		(layers "F.Cu" "B.Cu")
		(net "GND")
	)
	(via
		(at 244.1448 -402.6154)
		(size 0.7112)
		(drill 0.4064)
		(layers "F.Cu" "B.Cu")
		(net "GND")
	)
	(via
		(at 242.137946 -73.8251)
		(size 0.7112)
		(drill 0.4064)
		(layers "F.Cu" "B.Cu")
		(net "GND")
	)
	(via
		(at 47.243746 -63.6397)
		(size 0.7112)
		(drill 0.4064)
		(layers "F.Cu" "B.Cu")
		(net "GND")
	)
	(via
		(at 42.05605 -425.95165)
		(size 0.5588)
		(drill 0.3048)
		(layers "F.Cu" "B.Cu")
		(net "GND")
	)
	(via
		(at 161.035746 -280.1747)
		(size 0.7112)
		(drill 0.4064)
		(layers "F.Cu" "B.Cu")
		(net "GND")
	)
	(via
		(at 232.079546 -123.1011)
		(size 0.7112)
		(drill 0.4064)
		(layers "F.Cu" "B.Cu")
		(net "GND")
	)
	(via
		(at 7.060946 -9.7663)
		(size 0.7112)
		(drill 0.4064)
		(layers "F.Cu" "B.Cu")
		(net "GND")
	)
	(via
		(at 106.120946 -454.8759)
		(size 0.7112)
		(drill 0.4064)
		(layers "F.Cu" "B.Cu")
		(net "GND")
	)
	(via
		(at 130.682746 -251.4727)
		(size 0.7112)
		(drill 0.4064)
		(layers "F.Cu" "B.Cu")
		(net "GND")
	)
	(via
		(at 221.509844 -388.73684)
		(size 0.5588)
		(drill 0.3048)
		(layers "F.Cu" "B.Cu")
		(net "GND")
	)
	(via
		(at 242.518946 -4.5339)
		(size 0.7112)
		(drill 0.4064)
		(layers "F.Cu" "B.Cu")
		(net "GND")
	)
	(via
		(at 39.98976 -77.196696)
		(size 0.5588)
		(drill 0.3048)
		(layers "F.Cu" "B.Cu")
		(net "GND")
	)
	(via
		(at 65.150746 -154.6987)
		(size 0.7112)
		(drill 0.4064)
		(layers "F.Cu" "B.Cu")
		(net "GND")
	)
	(via
		(at 248.030746 -314.0837)
		(size 0.7112)
		(drill 0.4064)
		(layers "F.Cu" "B.Cu")
		(net "GND")
	)
	(via
		(at 247.142 -386.7912)
		(size 0.7112)
		(drill 0.4064)
		(layers "F.Cu" "B.Cu")
		(net "GND")
	)
	(via
		(at 5.968746 -164.985446)
		(size 0.5588)
		(drill 0.3048)
		(layers "F.Cu" "B.Cu")
		(net "GND")
	)
	(via
		(at 122.834146 -45.5549)
		(size 0.7112)
		(drill 0.4064)
		(layers "F.Cu" "B.Cu")
		(net "GND")
	)
	(via
		(at 58.5724 -424.307)
		(size 0.7112)
		(drill 0.4064)
		(layers "F.Cu" "B.Cu")
		(net "GND")
	)
	(via
		(at 254.685546 -10.1727)
		(size 0.7112)
		(drill 0.4064)
		(layers "F.Cu" "B.Cu")
		(net "GND")
	)
	(via
		(at 106.781346 -491.3757)
		(size 0.7112)
		(drill 0.4064)
		(layers "F.Cu" "B.Cu")
		(net "GND")
	)
	(via
		(at 123.189746 -415.6837)
		(size 0.7112)
		(drill 0.4064)
		(layers "F.Cu" "B.Cu")
		(net "GND")
	)
	(via
		(at 141.274546 -438.6707)
		(size 0.7112)
		(drill 0.4064)
		(layers "F.Cu" "B.Cu")
		(net "GND")
	)
	(via
		(at 170.052746 -283.6037)
		(size 0.7112)
		(drill 0.4064)
		(layers "F.Cu" "B.Cu")
		(net "GND")
	)
	(via
		(at 253.898146 -328.0283)
		(size 0.7112)
		(drill 0.4064)
		(layers "F.Cu" "B.Cu")
		(net "GND")
	)
	(via
		(at 6.203442 -387.889242)
		(size 0.5588)
		(drill 0.3048)
		(layers "F.Cu" "B.Cu")
		(net "GND")
	)
	(via
		(at 159.943546 -492.3155)
		(size 0.7112)
		(drill 0.4064)
		(layers "F.Cu" "B.Cu")
		(net "GND")
	)
	(via
		(at 92.074746 -64.4017)
		(size 0.7112)
		(drill 0.4064)
		(layers "F.Cu" "B.Cu")
		(net "GND")
	)
	(via
		(at 208.787746 -49.051464)
		(size 0.5588)
		(drill 0.3048)
		(layers "F.Cu" "B.Cu")
		(net "GND")
	)
	(via
		(at 140.588746 -504.7107)
		(size 0.7112)
		(drill 0.4064)
		(layers "F.Cu" "B.Cu")
		(net "GND")
	)
	(via
		(at 242.010946 -54.2671)
		(size 0.7112)
		(drill 0.4064)
		(layers "F.Cu" "B.Cu")
		(net "GND")
	)
	(via
		(at 242.518946 -106.5911)
		(size 0.7112)
		(drill 0.4064)
		(layers "F.Cu" "B.Cu")
		(net "GND")
	)
	(via
		(at 72.973946 -228.8667)
		(size 0.7112)
		(drill 0.4064)
		(layers "F.Cu" "B.Cu")
		(net "GND")
	)
	(via
		(at 40.385746 -65.9892)
		(size 0.7112)
		(drill 0.4064)
		(layers "F.Cu" "B.Cu")
		(net "GND")
	)
	(via
		(at 95.122746 -342.2777)
		(size 0.7112)
		(drill 0.4064)
		(layers "F.Cu" "B.Cu")
		(net "GND")
	)
	(via
		(at 98.932746 -478.8027)
		(size 0.7112)
		(drill 0.4064)
		(layers "F.Cu" "B.Cu")
		(net "GND")
	)
	(via
		(at 176.529746 -350.2787)
		(size 0.7112)
		(drill 0.4064)
		(layers "F.Cu" "B.Cu")
		(net "GND")
	)
	(via
		(at 175.259746 -280.8097)
		(size 0.7112)
		(drill 0.4064)
		(layers "F.Cu" "B.Cu")
		(net "GND")
	)
	(via
		(at 159.943546 -494.6015)
		(size 0.7112)
		(drill 0.4064)
		(layers "F.Cu" "B.Cu")
		(net "GND")
	)
	(via
		(at 155.168346 -380.1745)
		(size 0.7112)
		(drill 0.4064)
		(layers "F.Cu" "B.Cu")
		(net "GND")
	)
	(via
		(at 237.108746 -113.5507)
		(size 0.7112)
		(drill 0.4064)
		(layers "F.Cu" "B.Cu")
		(net "GND")
	)
	(via
		(at 50.936906 -226.1362)
		(size 0.5588)
		(drill 0.3048)
		(layers "F.Cu" "B.Cu")
		(net "GND")
	)
	(via
		(at 258.571746 -504.7107)
		(size 0.7112)
		(drill 0.4064)
		(layers "F.Cu" "B.Cu")
		(net "GND")
	)
	(via
		(at 158.368746 -397.2687)
		(size 0.7112)
		(drill 0.4064)
		(layers "F.Cu" "B.Cu")
		(net "GND")
	)
	(via
		(at 4.4704 -1.423416)
		(size 0.7112)
		(drill 0.4064)
		(layers "F.Cu" "B.Cu")
		(net "GND")
	)
	(via
		(at 216.9922 -33.6804)
		(size 0.7112)
		(drill 0.4064)
		(layers "F.Cu" "B.Cu")
		(net "GND")
	)
	(via
		(at 173.811946 -317.3857)
		(size 0.7112)
		(drill 0.4064)
		(layers "F.Cu" "B.Cu")
		(net "GND")
	)
	(via
		(at 27.177746 -283.19984)
		(size 0.7112)
		(drill 0.4064)
		(layers "F.Cu" "B.Cu")
		(net "GND")
	)
	(via
		(at 259.333746 -95.0087)
		(size 0.7112)
		(drill 0.4064)
		(layers "F.Cu" "B.Cu")
		(net "GND")
	)
	(via
		(at 221.360746 -1.6637)
		(size 0.7112)
		(drill 0.4064)
		(layers "F.Cu" "B.Cu")
		(net "GND")
	)
	(via
		(at 232.816146 -493.4331)
		(size 0.7112)
		(drill 0.4064)
		(layers "F.Cu" "B.Cu")
		(net "GND")
	)
	(via
		(at 103.377746 -483.8827)
		(size 0.7112)
		(drill 0.4064)
		(layers "F.Cu" "B.Cu")
		(net "GND")
	)
	(via
		(at 115.188746 -289.6997)
		(size 0.7112)
		(drill 0.4064)
		(layers "F.Cu" "B.Cu")
		(net "GND")
	)
	(via
		(at 135.254746 -424.0657)
		(size 0.7112)
		(drill 0.4064)
		(layers "F.Cu" "B.Cu")
		(net "GND")
	)
	(via
		(at 247.573546 -16.4211)
		(size 0.7112)
		(drill 0.4064)
		(layers "F.Cu" "B.Cu")
		(net "GND")
	)
	(via
		(at 169.417746 -129.1717)
		(size 0.7112)
		(drill 0.4064)
		(layers "F.Cu" "B.Cu")
		(net "GND")
	)
	(via
		(at 46.101 -375.666)
		(size 0.7112)
		(drill 0.4064)
		(layers "F.Cu" "B.Cu")
		(net "GND")
	)
	(via
		(at 204.114146 -411.0609)
		(size 0.7112)
		(drill 0.4064)
		(layers "F.Cu" "B.Cu")
		(net "GND")
	)
	(via
		(at 132.968746 -345.4527)
		(size 0.7112)
		(drill 0.4064)
		(layers "F.Cu" "B.Cu")
		(net "GND")
	)
	(via
		(at 110.946946 -450.2277)
		(size 0.7112)
		(drill 0.4064)
		(layers "F.Cu" "B.Cu")
		(net "GND")
	)
	(via
		(at 115.163346 -210.0453)
		(size 0.7112)
		(drill 0.4064)
		(layers "F.Cu" "B.Cu")
		(net "GND")
	)
	(via
		(at 19.430746 -380.5047)
		(size 0.7112)
		(drill 0.4064)
		(layers "F.Cu" "B.Cu")
		(net "GND")
	)
	(via
		(at 139.394946 -318.2239)
		(size 0.7112)
		(drill 0.4064)
		(layers "F.Cu" "B.Cu")
		(net "GND")
	)
	(via
		(at 242.010946 -58.7121)
		(size 0.7112)
		(drill 0.4064)
		(layers "F.Cu" "B.Cu")
		(net "GND")
	)
	(via
		(at 252.348746 -463.4357)
		(size 0.7112)
		(drill 0.4064)
		(layers "F.Cu" "B.Cu")
		(net "GND")
	)
	(via
		(at 84.022946 -180.9623)
		(size 0.7112)
		(drill 0.4064)
		(layers "F.Cu" "B.Cu")
		(net "GND")
	)
	(via
		(at 135.788146 -266.3317)
		(size 0.7112)
		(drill 0.4064)
		(layers "F.Cu" "B.Cu")
		(net "GND")
	)
	(via
		(at 246.379746 -197.1675)
		(size 0.7112)
		(drill 0.4064)
		(layers "F.Cu" "B.Cu")
		(net "GND")
	)
	(via
		(at 54.228746 -72.101456)
		(size 0.5588)
		(drill 0.3048)
		(layers "F.Cu" "B.Cu")
		(net "GND")
	)
	(via
		(at 193.674746 -343.6747)
		(size 0.7112)
		(drill 0.4064)
		(layers "F.Cu" "B.Cu")
		(net "GND")
	)
	(via
		(at 216.154 -268.732)
		(size 0.5588)
		(drill 0.3048)
		(layers "F.Cu" "B.Cu")
		(net "GND")
	)
	(via
		(at 76.834746 -488.2007)
		(size 0.7112)
		(drill 0.4064)
		(layers "F.Cu" "B.Cu")
		(net "GND")
	)
	(via
		(at 185.038746 -213.8299)
		(size 0.7112)
		(drill 0.4064)
		(layers "F.Cu" "B.Cu")
		(net "GND")
	)
	(via
		(at 183.895746 -203.7969)
		(size 0.7112)
		(drill 0.4064)
		(layers "F.Cu" "B.Cu")
		(net "GND")
	)
	(via
		(at 203.453746 -263.5377)
		(size 0.7112)
		(drill 0.4064)
		(layers "F.Cu" "B.Cu")
		(net "GND")
	)
	(via
		(at 146.887946 -227.4951)
		(size 0.7112)
		(drill 0.4064)
		(layers "F.Cu" "B.Cu")
		(net "GND")
	)
	(via
		(at 39.98976 -378.57684)
		(size 0.5588)
		(drill 0.3048)
		(layers "F.Cu" "B.Cu")
		(net "GND")
	)
	(via
		(at 146.049746 -491.3757)
		(size 0.7112)
		(drill 0.4064)
		(layers "F.Cu" "B.Cu")
		(net "GND")
	)
	(via
		(at 59.007756 -480.190302)
		(size 0.5588)
		(drill 0.3048)
		(layers "F.Cu" "B.Cu")
		(net "GND")
	)
	(via
		(at 199.897746 -382.6637)
		(size 0.7112)
		(drill 0.4064)
		(layers "F.Cu" "B.Cu")
		(net "GND")
	)
	(via
		(at 169.036746 -194.7037)
		(size 0.7112)
		(drill 0.4064)
		(layers "F.Cu" "B.Cu")
		(net "GND")
	)
	(via
		(at 183.260746 -501.5357)
		(size 0.7112)
		(drill 0.4064)
		(layers "F.Cu" "B.Cu")
		(net "GND")
	)
	(via
		(at 192.379346 -319.6971)
		(size 0.7112)
		(drill 0.4064)
		(layers "F.Cu" "B.Cu")
		(net "GND")
	)
	(via
		(at 23.088346 -3.7719)
		(size 0.7112)
		(drill 0.4064)
		(layers "F.Cu" "B.Cu")
		(net "GND")
	)
	(via
		(at 51.257454 -432.1683)
		(size 0.7112)
		(drill 0.4064)
		(layers "F.Cu" "B.Cu")
		(net "GND")
	)
	(via
		(at 71.295006 -493.44834)
		(size 0.5588)
		(drill 0.3048)
		(layers "F.Cu" "B.Cu")
		(net "GND")
	)
	(via
		(at 6.095746 -58.1787)
		(size 0.7112)
		(drill 0.4064)
		(layers "F.Cu" "B.Cu")
		(net "GND")
	)
	(via
		(at 175.742346 -149.5679)
		(size 0.7112)
		(drill 0.4064)
		(layers "F.Cu" "B.Cu")
		(net "GND")
	)
	(via
		(at 237.743746 -156.4767)
		(size 0.7112)
		(drill 0.4064)
		(layers "F.Cu" "B.Cu")
		(net "GND")
	)
	(via
		(at 3.302 -292.354)
		(size 0.7112)
		(drill 0.4064)
		(layers "F.Cu" "B.Cu")
		(net "GND")
	)
	(via
		(at 53.974746 -300.8757)
		(size 0.7112)
		(drill 0.4064)
		(layers "F.Cu" "B.Cu")
		(net "GND")
	)
	(via
		(at 141.858746 -276.3647)
		(size 0.7112)
		(drill 0.4064)
		(layers "F.Cu" "B.Cu")
		(net "GND")
	)
	(via
		(at 188.086746 -322.5927)
		(size 0.7112)
		(drill 0.4064)
		(layers "F.Cu" "B.Cu")
		(net "GND")
	)
	(via
		(at 93.218 -459.74)
		(size 0.5588)
		(drill 0.3048)
		(layers "F.Cu" "B.Cu")
		(net "GND")
	)
	(via
		(at 157.022546 -329.2475)
		(size 0.7112)
		(drill 0.4064)
		(layers "F.Cu" "B.Cu")
		(net "GND")
	)
	(via
		(at 42.747946 -477.4819)
		(size 0.7112)
		(drill 0.4064)
		(layers "F.Cu" "B.Cu")
		(net "GND")
	)
	(via
		(at 122.300746 -72.0217)
		(size 0.7112)
		(drill 0.4064)
		(layers "F.Cu" "B.Cu")
		(net "GND")
	)
	(via
		(at 114.858546 -393.8651)
		(size 0.7112)
		(drill 0.4064)
		(layers "F.Cu" "B.Cu")
		(net "GND")
	)
	(via
		(at 151.383746 -154.8257)
		(size 0.7112)
		(drill 0.4064)
		(layers "F.Cu" "B.Cu")
		(net "GND")
	)
	(via
		(at 77.495146 -4.318)
		(size 0.5588)
		(drill 0.3048)
		(layers "F.Cu" "B.Cu")
		(net "GND")
	)
	(via
		(at 77.7494 -117.348)
		(size 0.7112)
		(drill 0.4064)
		(layers "F.Cu" "B.Cu")
		(net "GND")
	)
	(via
		(at 183.692546 -474.4593)
		(size 0.7112)
		(drill 0.4064)
		(layers "F.Cu" "B.Cu")
		(net "GND")
	)
	(via
		(at 192.379346 -314.8711)
		(size 0.7112)
		(drill 0.4064)
		(layers "F.Cu" "B.Cu")
		(net "GND")
	)
	(via
		(at 5.841746 -346.9767)
		(size 0.5588)
		(drill 0.3048)
		(layers "F.Cu" "B.Cu")
		(net "GND")
	)
	(via
		(at 245.363746 -242.4557)
		(size 0.5588)
		(drill 0.3048)
		(layers "F.Cu" "B.Cu")
		(net "GND")
	)
	(via
		(at 217.14587 -463.698082)
		(size 0.5588)
		(drill 0.3048)
		(layers "F.Cu" "B.Cu")
		(net "GND")
	)
	(via
		(at 27.2542 -443.5602)
		(size 0.5588)
		(drill 0.3048)
		(layers "F.Cu" "B.Cu")
		(net "GND")
	)
	(via
		(at 216.153746 -244.4877)
		(size 0.7112)
		(drill 0.4064)
		(layers "F.Cu" "B.Cu")
		(net "GND")
	)
	(via
		(at 77.317346 -253.3777)
		(size 0.7112)
		(drill 0.4064)
		(layers "F.Cu" "B.Cu")
		(net "GND")
	)
	(via
		(at 198.881746 -428.5107)
		(size 0.7112)
		(drill 0.4064)
		(layers "F.Cu" "B.Cu")
		(net "GND")
	)
	(via
		(at 229.742746 -112.0267)
		(size 0.7112)
		(drill 0.4064)
		(layers "F.Cu" "B.Cu")
		(net "GND")
	)
	(via
		(at 168.655746 -218.1987)
		(size 0.7112)
		(drill 0.4064)
		(layers "F.Cu" "B.Cu")
		(net "GND")
	)
	(via
		(at 137.540746 -6.3627)
		(size 0.7112)
		(drill 0.4064)
		(layers "F.Cu" "B.Cu")
		(net "GND")
	)
	(via
		(at 144.652746 -411.3657)
		(size 0.7112)
		(drill 0.4064)
		(layers "F.Cu" "B.Cu")
		(net "GND")
	)
	(via
		(at 5.968746 -134.985506)
		(size 0.5588)
		(drill 0.3048)
		(layers "F.Cu" "B.Cu")
		(net "GND")
	)
	(via
		(at 7.7216 -469.8111)
		(size 0.7112)
		(drill 0.4064)
		(layers "F.Cu" "B.Cu")
		(net "GND")
	)
	(via
		(at 250.316746 -145.6817)
		(size 0.7112)
		(drill 0.4064)
		(layers "F.Cu" "B.Cu")
		(net "GND")
	)
	(via
		(at 84.099146 -234.6071)
		(size 0.7112)
		(drill 0.4064)
		(layers "F.Cu" "B.Cu")
		(net "GND")
	)
	(via
		(at 239.724946 -350.7359)
		(size 0.7112)
		(drill 0.4064)
		(layers "F.Cu" "B.Cu")
		(net "GND")
	)
	(via
		(at 252.729746 -444.2333)
		(size 0.7112)
		(drill 0.4064)
		(layers "F.Cu" "B.Cu")
		(net "GND")
	)
	(via
		(at 203.961746 -222.0087)
		(size 0.7112)
		(drill 0.4064)
		(layers "F.Cu" "B.Cu")
		(net "GND")
	)
	(via
		(at 138.455146 -344.2335)
		(size 0.7112)
		(drill 0.4064)
		(layers "F.Cu" "B.Cu")
		(net "GND")
	)
	(via
		(at 113.232946 -46.9011)
		(size 0.7112)
		(drill 0.4064)
		(layers "F.Cu" "B.Cu")
		(net "GND")
	)
	(via
		(at 66.420746 -463.5627)
		(size 0.7112)
		(drill 0.4064)
		(layers "F.Cu" "B.Cu")
		(net "GND")
	)
	(via
		(at 231.0638 -400.4056)
		(size 0.7112)
		(drill 0.4064)
		(layers "F.Cu" "B.Cu")
		(net "GND")
	)
	(via
		(at 219.709746 -504.7107)
		(size 0.7112)
		(drill 0.4064)
		(layers "F.Cu" "B.Cu")
		(net "GND")
	)
	(via
		(at 239.902746 -414.6931)
		(size 0.7112)
		(drill 0.4064)
		(layers "F.Cu" "B.Cu")
		(net "GND")
	)
	(via
		(at 206.882746 -148.3487)
		(size 0.7112)
		(drill 0.4064)
		(layers "F.Cu" "B.Cu")
		(net "GND")
	)
	(via
		(at 22.732746 -445.40805)
		(size 0.5588)
		(drill 0.3048)
		(layers "F.Cu" "B.Cu")
		(net "GND")
	)
	(via
		(at 7.3914 -370.6368)
		(size 0.5588)
		(drill 0.3048)
		(layers "F.Cu" "B.Cu")
		(net "GND")
	)
	(via
		(at 220.979746 -471.416888)
		(size 0.7112)
		(drill 0.4064)
		(layers "F.Cu" "B.Cu")
		(net "GND")
	)
	(via
		(at 221.360746 -175.116744)
		(size 0.7112)
		(drill 0.4064)
		(layers "F.Cu" "B.Cu")
		(net "GND")
	)
	(via
		(at 255.27 -503.047)
		(size 0.7112)
		(drill 0.4064)
		(layers "F.Cu" "B.Cu")
		(net "GND")
	)
	(via
		(at 72.897746 -117.3607)
		(size 0.7112)
		(drill 0.4064)
		(layers "F.Cu" "B.Cu")
		(net "GND")
	)
	(via
		(at 72.211946 -460.0321)
		(size 0.7112)
		(drill 0.4064)
		(layers "F.Cu" "B.Cu")
		(net "GND")
	)
	(via
		(at 46.303946 -457.5429)
		(size 0.7112)
		(drill 0.4064)
		(layers "F.Cu" "B.Cu")
		(net "GND")
	)
	(via
		(at 147.903946 -389.6741)
		(size 0.7112)
		(drill 0.4064)
		(layers "F.Cu" "B.Cu")
		(net "GND")
	)
	(via
		(at 77.393546 -321.5259)
		(size 0.7112)
		(drill 0.4064)
		(layers "F.Cu" "B.Cu")
		(net "GND")
	)
	(via
		(at 89.0524 -409.1686)
		(size 0.7112)
		(drill 0.4064)
		(layers "F.Cu" "B.Cu")
		(net "GND")
	)
	(via
		(at 244.0686 -392.9634)
		(size 0.7112)
		(drill 0.4064)
		(layers "F.Cu" "B.Cu")
		(net "GND")
	)
	(via
		(at 245.4656 -402.717)
		(size 0.7112)
		(drill 0.4064)
		(layers "F.Cu" "B.Cu")
		(net "GND")
	)
	(via
		(at 155.447746 -471.4113)
		(size 0.7112)
		(drill 0.4064)
		(layers "F.Cu" "B.Cu")
		(net "GND")
	)
	(via
		(at 253.771146 -301.7393)
		(size 0.7112)
		(drill 0.4064)
		(layers "F.Cu" "B.Cu")
		(net "GND")
	)
	(via
		(at 62.102746 -31.0007)
		(size 0.7112)
		(drill 0.4064)
		(layers "F.Cu" "B.Cu")
		(net "GND")
	)
	(via
		(at 179.5018 -401.2946)
		(size 0.7112)
		(drill 0.4064)
		(layers "F.Cu" "B.Cu")
		(net "GND")
	)
	(via
		(at 45.593 -320.548)
		(size 0.7112)
		(drill 0.4064)
		(layers "F.Cu" "B.Cu")
		(net "GND")
	)
	(via
		(at 137.032746 -454.1901)
		(size 0.7112)
		(drill 0.4064)
		(layers "F.Cu" "B.Cu")
		(net "GND")
	)
	(via
		(at 202.564746 -32.3977)
		(size 0.7112)
		(drill 0.4064)
		(layers "F.Cu" "B.Cu")
		(net "GND")
	)
	(via
		(at 176.021746 -260.6167)
		(size 0.7112)
		(drill 0.4064)
		(layers "F.Cu" "B.Cu")
		(net "GND")
	)
	(via
		(at 106.552746 -309.7657)
		(size 0.7112)
		(drill 0.4064)
		(layers "F.Cu" "B.Cu")
		(net "GND")
	)
	(via
		(at 107.035346 -479.5647)
		(size 0.7112)
		(drill 0.4064)
		(layers "F.Cu" "B.Cu")
		(net "GND")
	)
	(via
		(at 86.461346 -236.5375)
		(size 0.7112)
		(drill 0.4064)
		(layers "F.Cu" "B.Cu")
		(net "GND")
	)
	(via
		(at 242.518946 -114.7191)
		(size 0.7112)
		(drill 0.4064)
		(layers "F.Cu" "B.Cu")
		(net "GND")
	)
	(via
		(at 225.551746 -307.1749)
		(size 0.7112)
		(drill 0.4064)
		(layers "F.Cu" "B.Cu")
		(net "GND")
	)
	(via
		(at 12.1666 -439.7502)
		(size 0.5588)
		(drill 0.3048)
		(layers "F.Cu" "B.Cu")
		(net "GND")
	)
	(via
		(at 259.079746 -214.7697)
		(size 0.7112)
		(drill 0.4064)
		(layers "F.Cu" "B.Cu")
		(net "GND")
	)
	(via
		(at 164.1094 -27.1526)
		(size 0.7112)
		(drill 0.3556)
		(layers "F.Cu" "B.Cu")
		(net "GND")
	)
	(via
		(at 131.317746 -365.0107)
		(size 0.7112)
		(drill 0.4064)
		(layers "F.Cu" "B.Cu")
		(net "GND")
	)
	(via
		(at 200.405746 -324.6501)
		(size 0.7112)
		(drill 0.4064)
		(layers "F.Cu" "B.Cu")
		(net "GND")
	)
	(via
		(at 114.934746 -147.2057)
		(size 0.7112)
		(drill 0.4064)
		(layers "F.Cu" "B.Cu")
		(net "GND")
	)
	(via
		(at 120.700546 -495.7953)
		(size 0.7112)
		(drill 0.4064)
		(layers "F.Cu" "B.Cu")
		(net "GND")
	)
	(via
		(at 258.190746 -314.0837)
		(size 0.7112)
		(drill 0.4064)
		(layers "F.Cu" "B.Cu")
		(net "GND")
	)
	(via
		(at 196.849746 -117.3607)
		(size 0.7112)
		(drill 0.4064)
		(layers "F.Cu" "B.Cu")
		(net "GND")
	)
	(via
		(at 201.040746 -306.4637)
		(size 0.7112)
		(drill 0.4064)
		(layers "F.Cu" "B.Cu")
		(net "GND")
	)
	(via
		(at 5.968746 -350.901)
		(size 0.5588)
		(drill 0.3048)
		(layers "F.Cu" "B.Cu")
		(net "GND")
	)
	(via
		(at 162.6362 -231.521)
		(size 0.7112)
		(drill 0.3556)
		(layers "F.Cu" "B.Cu")
		(net "GND")
	)
	(via
		(at 110.565946 -201.9681)
		(size 0.7112)
		(drill 0.4064)
		(layers "F.Cu" "B.Cu")
		(net "GND")
	)
	(via
		(at 259.333746 -17.7927)
		(size 0.7112)
		(drill 0.4064)
		(layers "F.Cu" "B.Cu")
		(net "GND")
	)
	(via
		(at 129.539746 -166.3827)
		(size 0.7112)
		(drill 0.4064)
		(layers "F.Cu" "B.Cu")
		(net "GND")
	)
	(via
		(at 82.448146 -176.8221)
		(size 0.7112)
		(drill 0.4064)
		(layers "F.Cu" "B.Cu")
		(net "GND")
	)
	(via
		(at 184.759346 -430.3649)
		(size 0.7112)
		(drill 0.4064)
		(layers "F.Cu" "B.Cu")
		(net "GND")
	)
	(via
		(at 137.794746 -47.0027)
		(size 0.7112)
		(drill 0.4064)
		(layers "F.Cu" "B.Cu")
		(net "GND")
	)
	(via
		(at 50.6984 -501.6246)
		(size 0.7112)
		(drill 0.4064)
		(layers "F.Cu" "B.Cu")
		(net "GND")
	)
	(via
		(at 106.781346 -498.4877)
		(size 0.7112)
		(drill 0.4064)
		(layers "F.Cu" "B.Cu")
		(net "GND")
	)
	(via
		(at 259.587746 -123.5837)
		(size 0.7112)
		(drill 0.4064)
		(layers "F.Cu" "B.Cu")
		(net "GND")
	)
	(via
		(at 190.525146 -430.5173)
		(size 0.7112)
		(drill 0.4064)
		(layers "F.Cu" "B.Cu")
		(net "GND")
	)
	(via
		(at 241.375946 -160.4391)
		(size 0.7112)
		(drill 0.4064)
		(layers "F.Cu" "B.Cu")
		(net "GND")
	)
	(via
		(at 181.914546 -381.7747)
		(size 0.7112)
		(drill 0.4064)
		(layers "F.Cu" "B.Cu")
		(net "GND")
	)
	(via
		(at 157.860746 -122.9487)
		(size 0.7112)
		(drill 0.4064)
		(layers "F.Cu" "B.Cu")
		(net "GND")
	)
	(via
		(at 95.25 -262.636)
		(size 0.7112)
		(drill 0.4064)
		(layers "F.Cu" "B.Cu")
		(net "GND")
	)
	(via
		(at 49.530254 -433.8701)
		(size 0.7112)
		(drill 0.4064)
		(layers "F.Cu" "B.Cu")
		(net "GND")
	)
	(via
		(at 159.511746 -66.6877)
		(size 0.7112)
		(drill 0.4064)
		(layers "F.Cu" "B.Cu")
		(net "GND")
	)
	(via
		(at 241.604546 -311.3405)
		(size 0.7112)
		(drill 0.4064)
		(layers "F.Cu" "B.Cu")
		(net "GND")
	)
	(via
		(at 245.973346 -34.8361)
		(size 0.7112)
		(drill 0.4064)
		(layers "F.Cu" "B.Cu")
		(net "GND")
	)
	(via
		(at 131.444746 -368.0587)
		(size 0.7112)
		(drill 0.4064)
		(layers "F.Cu" "B.Cu")
		(net "GND")
	)
	(via
		(at 216.407746 -309.5117)
		(size 0.7112)
		(drill 0.4064)
		(layers "F.Cu" "B.Cu")
		(net "GND")
	)
	(via
		(at 132.6642 -441.7568)
		(size 0.7112)
		(drill 0.4064)
		(layers "F.Cu" "B.Cu")
		(net "GND")
	)
	(via
		(at 29.844746 -274.1422)
		(size 0.5588)
		(drill 0.3048)
		(layers "F.Cu" "B.Cu")
		(net "GND")
	)
	(via
		(at 117.855746 -171.2087)
		(size 0.7112)
		(drill 0.4064)
		(layers "F.Cu" "B.Cu")
		(net "GND")
	)
	(via
		(at 49.656746 -322.5927)
		(size 0.7112)
		(drill 0.4064)
		(layers "F.Cu" "B.Cu")
		(net "GND")
	)
	(via
		(at 124.967746 -493.6617)
		(size 0.7112)
		(drill 0.4064)
		(layers "F.Cu" "B.Cu")
		(net "GND")
	)
	(via
		(at 19.811746 -125.2347)
		(size 0.5588)
		(drill 0.3048)
		(layers "F.Cu" "B.Cu")
		(net "GND")
	)
	(via
		(at 164.464746 -175.0187)
		(size 0.7112)
		(drill 0.4064)
		(layers "F.Cu" "B.Cu")
		(net "GND")
	)
	(via
		(at 259.333746 -8.3947)
		(size 0.7112)
		(drill 0.4064)
		(layers "F.Cu" "B.Cu")
		(net "GND")
	)
	(via
		(at 146.659346 -106.6927)
		(size 0.7112)
		(drill 0.4064)
		(layers "F.Cu" "B.Cu")
		(net "GND")
	)
	(via
		(at 184.403746 -27.0637)
		(size 0.7112)
		(drill 0.4064)
		(layers "F.Cu" "B.Cu")
		(net "GND")
	)
	(via
		(at 202.437746 -42.1767)
		(size 0.7112)
		(drill 0.4064)
		(layers "F.Cu" "B.Cu")
		(net "GND")
	)
	(via
		(at 193.903346 -6.1341)
		(size 0.7112)
		(drill 0.4064)
		(layers "F.Cu" "B.Cu")
		(net "GND")
	)
	(via
		(at 65.861946 -365.4425)
		(size 0.7112)
		(drill 0.4064)
		(layers "F.Cu" "B.Cu")
		(net "GND")
	)
	(via
		(at 218.142058 -377.366784)
		(size 0.5588)
		(drill 0.3048)
		(layers "F.Cu" "B.Cu")
		(net "GND")
	)
	(via
		(at 252.5268 -361.061)
		(size 0.7112)
		(drill 0.4064)
		(layers "F.Cu" "B.Cu")
		(net "GND")
	)
	(via
		(at 123.570746 -303.7967)
		(size 0.7112)
		(drill 0.4064)
		(layers "F.Cu" "B.Cu")
		(net "GND")
	)
	(via
		(at 158.241746 -175.1457)
		(size 0.7112)
		(drill 0.4064)
		(layers "F.Cu" "B.Cu")
		(net "GND")
	)
	(via
		(at 120.141746 -187.0837)
		(size 0.7112)
		(drill 0.4064)
		(layers "F.Cu" "B.Cu")
		(net "GND")
	)
	(via
		(at 259.079746 -237.2487)
		(size 0.7112)
		(drill 0.4064)
		(layers "F.Cu" "B.Cu")
		(net "GND")
	)
	(via
		(at 180.847746 -74.4347)
		(size 0.7112)
		(drill 0.4064)
		(layers "F.Cu" "B.Cu")
		(net "GND")
	)
	(via
		(at 53.51399 -18.98015)
		(size 0.5588)
		(drill 0.3048)
		(layers "F.Cu" "B.Cu")
		(net "GND")
	)
	(via
		(at 187.578746 -132.6007)
		(size 0.7112)
		(drill 0.4064)
		(layers "F.Cu" "B.Cu")
		(net "GND")
	)
	(via
		(at 1.803146 -436.3085)
		(size 0.7112)
		(drill 0.4064)
		(layers "F.Cu" "B.Cu")
		(net "GND")
	)
	(via
		(at 2.793746 -196.6087)
		(size 0.7112)
		(drill 0.4064)
		(layers "F.Cu" "B.Cu")
		(net "GND")
	)
	(via
		(at 254.177546 -117.6909)
		(size 0.7112)
		(drill 0.4064)
		(layers "F.Cu" "B.Cu")
		(net "GND")
	)
	(via
		(at 38.353746 -300.0121)
		(size 0.7112)
		(drill 0.4064)
		(layers "F.Cu" "B.Cu")
		(net "GND")
	)
	(via
		(at 83.464146 -112.3315)
		(size 0.7112)
		(drill 0.4064)
		(layers "F.Cu" "B.Cu")
		(net "GND")
	)
	(via
		(at 39.877746 -215.9127)
		(size 0.7112)
		(drill 0.4064)
		(layers "F.Cu" "B.Cu")
		(net "GND")
	)
	(via
		(at 70.814946 -352.1075)
		(size 0.7112)
		(drill 0.4064)
		(layers "F.Cu" "B.Cu")
		(net "GND")
	)
	(via
		(at 246.888 -393.065)
		(size 0.7112)
		(drill 0.4064)
		(layers "F.Cu" "B.Cu")
		(net "GND")
	)
	(via
		(at 79.323946 -277.7617)
		(size 0.7112)
		(drill 0.4064)
		(layers "F.Cu" "B.Cu")
		(net "GND")
	)
	(via
		(at 245.135146 -336.3849)
		(size 0.7112)
		(drill 0.4064)
		(layers "F.Cu" "B.Cu")
		(net "GND")
	)
	(via
		(at 120.700546 -493.5093)
		(size 0.7112)
		(drill 0.4064)
		(layers "F.Cu" "B.Cu")
		(net "GND")
	)
	(via
		(at 217.703146 -221.8563)
		(size 0.7112)
		(drill 0.4064)
		(layers "F.Cu" "B.Cu")
		(net "GND")
	)
	(via
		(at 116.458746 -442.4807)
		(size 0.7112)
		(drill 0.4064)
		(layers "F.Cu" "B.Cu")
		(net "GND")
	)
	(via
		(at 51.3334 -261.1374)
		(size 0.7112)
		(drill 0.4064)
		(layers "F.Cu" "B.Cu")
		(net "GND")
	)
	(via
		(at 120.421146 -296.0497)
		(size 0.7112)
		(drill 0.4064)
		(layers "F.Cu" "B.Cu")
		(net "GND")
	)
	(via
		(at 206.248 -457.073)
		(size 0.5588)
		(drill 0.3048)
		(layers "F.Cu" "B.Cu")
		(net "GND")
	)
	(via
		(at 221.742 -37.719)
		(size 0.5588)
		(drill 0.3048)
		(layers "F.Cu" "B.Cu")
		(net "GND")
	)
	(via
		(at 5.94741 -416.975036)
		(size 0.5588)
		(drill 0.3048)
		(layers "F.Cu" "B.Cu")
		(net "GND")
	)
	(via
		(at 119.481346 -21.4757)
		(size 0.7112)
		(drill 0.4064)
		(layers "F.Cu" "B.Cu")
		(net "GND")
	)
	(via
		(at 230.631746 -67.0941)
		(size 0.7112)
		(drill 0.4064)
		(layers "F.Cu" "B.Cu")
		(net "GND")
	)
	(via
		(at 156.209746 -94.3737)
		(size 0.7112)
		(drill 0.3556)
		(layers "F.Cu" "B.Cu")
		(net "GND")
	)
	(via
		(at 57.556146 -340.4235)
		(size 0.7112)
		(drill 0.4064)
		(layers "F.Cu" "B.Cu")
		(net "GND")
	)
	(via
		(at 122.300746 -356.2477)
		(size 0.7112)
		(drill 0.4064)
		(layers "F.Cu" "B.Cu")
		(net "GND")
	)
	(via
		(at 135.254746 -447.8147)
		(size 0.7112)
		(drill 0.4064)
		(layers "F.Cu" "B.Cu")
		(net "GND")
	)
	(via
		(at 52.501546 -242.0747)
		(size 0.7112)
		(drill 0.4064)
		(layers "F.Cu" "B.Cu")
		(net "GND")
	)
	(via
		(at 201.929746 -168.7957)
		(size 0.7112)
		(drill 0.4064)
		(layers "F.Cu" "B.Cu")
		(net "GND")
	)
	(via
		(at 241.121946 -256.4003)
		(size 0.7112)
		(drill 0.4064)
		(layers "F.Cu" "B.Cu")
		(net "GND")
	)
	(via
		(at 85.648546 -415.6329)
		(size 0.7112)
		(drill 0.4064)
		(layers "F.Cu" "B.Cu")
		(net "GND")
	)
	(via
		(at 222.2246 -60.6044)
		(size 0.5588)
		(drill 0.3048)
		(layers "F.Cu" "B.Cu")
		(net "GND")
	)
	(via
		(at 45.72 -365.633)
		(size 0.7112)
		(drill 0.4064)
		(layers "F.Cu" "B.Cu")
		(net "GND")
	)
	(via
		(at 211.200746 -307.2257)
		(size 0.7112)
		(drill 0.4064)
		(layers "F.Cu" "B.Cu")
		(net "GND")
	)
	(via
		(at 252.729746 -262.3947)
		(size 0.7112)
		(drill 0.4064)
		(layers "F.Cu" "B.Cu")
		(net "GND")
	)
	(via
		(at 241.731546 -330.8985)
		(size 0.7112)
		(drill 0.4064)
		(layers "F.Cu" "B.Cu")
		(net "GND")
	)
	(via
		(at 206.120746 -194.9577)
		(size 0.7112)
		(drill 0.4064)
		(layers "F.Cu" "B.Cu")
		(net "GND")
	)
	(via
		(at 241.477546 -285.0515)
		(size 0.7112)
		(drill 0.4064)
		(layers "F.Cu" "B.Cu")
		(net "GND")
	)
	(via
		(at 5.968746 -168.985438)
		(size 0.5588)
		(drill 0.3048)
		(layers "F.Cu" "B.Cu")
		(net "GND")
	)
	(via
		(at 47.244 -417.576)
		(size 0.5588)
		(drill 0.3048)
		(layers "F.Cu" "B.Cu")
		(net "GND")
	)
	(via
		(at 60.071 -504.825)
		(size 0.7112)
		(drill 0.4064)
		(layers "F.Cu" "B.Cu")
		(net "GND")
	)
	(via
		(at 213.181946 -99.3013)
		(size 0.7112)
		(drill 0.4064)
		(layers "F.Cu" "B.Cu")
		(net "GND")
	)
	(via
		(at 126.999746 -16.2687)
		(size 0.7112)
		(drill 0.4064)
		(layers "F.Cu" "B.Cu")
		(net "GND")
	)
	(via
		(at 139.191746 -185.0517)
		(size 0.7112)
		(drill 0.4064)
		(layers "F.Cu" "B.Cu")
		(net "GND")
	)
	(via
		(at 193.039746 -10.0457)
		(size 0.7112)
		(drill 0.3556)
		(layers "F.Cu" "B.Cu")
		(net "GND")
	)
	(via
		(at 115.569746 -283.3497)
		(size 0.7112)
		(drill 0.4064)
		(layers "F.Cu" "B.Cu")
		(net "GND")
	)
	(via
		(at 79.501746 -397.7767)
		(size 0.5588)
		(drill 0.3048)
		(layers "F.Cu" "B.Cu")
		(net "GND")
	)
	(via
		(at 53.847746 -399.9357)
		(size 0.7112)
		(drill 0.4064)
		(layers "F.Cu" "B.Cu")
		(net "GND")
	)
	(via
		(at 73.913746 -54.8767)
		(size 0.7112)
		(drill 0.4064)
		(layers "F.Cu" "B.Cu")
		(net "GND")
	)
	(via
		(at 241.477546 -320.7385)
		(size 0.7112)
		(drill 0.4064)
		(layers "F.Cu" "B.Cu")
		(net "GND")
	)
	(via
		(at 241.375946 -152.3111)
		(size 0.7112)
		(drill 0.4064)
		(layers "F.Cu" "B.Cu")
		(net "GND")
	)
	(via
		(at 31.114746 -424.8277)
		(size 0.7112)
		(drill 0.4064)
		(layers "F.Cu" "B.Cu")
		(net "GND")
	)
	(via
		(at 141.985746 -266.5857)
		(size 0.7112)
		(drill 0.4064)
		(layers "F.Cu" "B.Cu")
		(net "GND")
	)
	(via
		(at 187.654946 -426.0215)
		(size 0.7112)
		(drill 0.4064)
		(layers "F.Cu" "B.Cu")
		(net "GND")
	)
	(via
		(at 245.6434 -399.4912)
		(size 0.7112)
		(drill 0.4064)
		(layers "F.Cu" "B.Cu")
		(net "GND")
	)
	(via
		(at 56.082946 -455.0537)
		(size 0.7112)
		(drill 0.4064)
		(layers "F.Cu" "B.Cu")
		(net "GND")
	)
	(via
		(at 174.243746 -198.1327)
		(size 0.7112)
		(drill 0.4064)
		(layers "F.Cu" "B.Cu")
		(net "GND")
	)
	(via
		(at 227.076 -474.586808)
		(size 0.7112)
		(drill 0.4064)
		(layers "F.Cu" "B.Cu")
		(net "GND")
	)
	(via
		(at 197.154546 -223.3295)
		(size 0.7112)
		(drill 0.4064)
		(layers "F.Cu" "B.Cu")
		(net "GND")
	)
	(via
		(at 168.274746 -55.3847)
		(size 0.7112)
		(drill 0.4064)
		(layers "F.Cu" "B.Cu")
		(net "GND")
	)
	(via
		(at 200.913746 -298.5897)
		(size 0.7112)
		(drill 0.4064)
		(layers "F.Cu" "B.Cu")
		(net "GND")
	)
	(via
		(at 2.285746 -260.4897)
		(size 0.7112)
		(drill 0.4064)
		(layers "F.Cu" "B.Cu")
		(net "GND")
	)
	(via
		(at 157.987746 -212.1027)
		(size 0.7112)
		(drill 0.4064)
		(layers "F.Cu" "B.Cu")
		(net "GND")
	)
	(via
		(at 22.8092 -33.6296)
		(size 0.5588)
		(drill 0.3048)
		(layers "F.Cu" "B.Cu")
		(net "GND")
	)
	(via
		(at 212.4964 -359.791)
		(size 0.7112)
		(drill 0.4064)
		(layers "F.Cu" "B.Cu")
		(net "GND")
	)
	(via
		(at 203.580746 -249.9487)
		(size 0.7112)
		(drill 0.4064)
		(layers "F.Cu" "B.Cu")
		(net "GND")
	)
	(via
		(at 209.803746 -400.8247)
		(size 0.7112)
		(drill 0.4064)
		(layers "F.Cu" "B.Cu")
		(net "GND")
	)
	(via
		(at 74.5998 -394.551154)
		(size 0.5588)
		(drill 0.3048)
		(layers "F.Cu" "B.Cu")
		(net "GND")
	)
	(via
		(at 6.552946 -16.2687)
		(size 0.7112)
		(drill 0.4064)
		(layers "F.Cu" "B.Cu")
		(net "GND")
	)
	(via
		(at 259.333746 -182.8927)
		(size 0.7112)
		(drill 0.4064)
		(layers "F.Cu" "B.Cu")
		(net "GND")
	)
	(via
		(at 90.423746 -61.6585)
		(size 0.7112)
		(drill 0.4064)
		(layers "F.Cu" "B.Cu")
		(net "GND")
	)
	(via
		(at 106.044746 -31.8897)
		(size 0.7112)
		(drill 0.4064)
		(layers "F.Cu" "B.Cu")
		(net "GND")
	)
	(via
		(at 81.609946 -143.5735)
		(size 0.7112)
		(drill 0.4064)
		(layers "F.Cu" "B.Cu")
		(net "GND")
	)
	(via
		(at 242.442746 -453.0217)
		(size 0.7112)
		(drill 0.4064)
		(layers "F.Cu" "B.Cu")
		(net "GND")
	)
	(via
		(at 87.503 -402.2344)
		(size 0.7112)
		(drill 0.4064)
		(layers "F.Cu" "B.Cu")
		(net "GND")
	)
	(via
		(at 2.285746 -251.0917)
		(size 0.7112)
		(drill 0.4064)
		(layers "F.Cu" "B.Cu")
		(net "GND")
	)
	(via
		(at 85.546946 -474.9673)
		(size 0.7112)
		(drill 0.4064)
		(layers "F.Cu" "B.Cu")
		(net "GND")
	)
	(via
		(at 28.701746 -31.5087)
		(size 0.5588)
		(drill 0.3048)
		(layers "F.Cu" "B.Cu")
		(net "GND")
	)
	(via
		(at 153.644346 -357.5685)
		(size 0.7112)
		(drill 0.4064)
		(layers "F.Cu" "B.Cu")
		(net "GND")
	)
	(via
		(at 252.577346 -25.7175)
		(size 0.7112)
		(drill 0.4064)
		(layers "F.Cu" "B.Cu")
		(net "GND")
	)
	(via
		(at 259.333746 -73.4187)
		(size 0.7112)
		(drill 0.4064)
		(layers "F.Cu" "B.Cu")
		(net "GND")
	)
	(via
		(at 233.933746 -266.8397)
		(size 0.7112)
		(drill 0.4064)
		(layers "F.Cu" "B.Cu")
		(net "GND")
	)
	(via
		(at 144.398746 -55.2577)
		(size 0.7112)
		(drill 0.4064)
		(layers "F.Cu" "B.Cu")
		(net "GND")
	)
	(via
		(at 29.781246 -434.87086)
		(size 0.5588)
		(drill 0.3048)
		(layers "F.Cu" "B.Cu")
		(net "GND")
	)
	(via
		(at 75.8952 -84.582)
		(size 0.5588)
		(drill 0.3048)
		(layers "F.Cu" "B.Cu")
		(net "GND")
	)
	(via
		(at 76.428346 -364.0709)
		(size 0.7112)
		(drill 0.4064)
		(layers "F.Cu" "B.Cu")
		(net "GND")
	)
	(via
		(at 38.861746 -35.8267)
		(size 0.7112)
		(drill 0.4064)
		(layers "F.Cu" "B.Cu")
		(net "GND")
	)
	(via
		(at 32.6136 -301.9044)
		(size 0.7112)
		(drill 0.4064)
		(layers "F.Cu" "B.Cu")
		(net "GND")
	)
	(via
		(at 245.5164 -388.3914)
		(size 0.7112)
		(drill 0.4064)
		(layers "F.Cu" "B.Cu")
		(net "GND")
	)
	(via
		(at 220.090746 -407.1747)
		(size 0.7112)
		(drill 0.4064)
		(layers "F.Cu" "B.Cu")
		(net "GND")
	)
	(via
		(at 210.768946 -471.5129)
		(size 0.7112)
		(drill 0.4064)
		(layers "F.Cu" "B.Cu")
		(net "GND")
	)
	(via
		(at 119.049546 -200.2409)
		(size 0.7112)
		(drill 0.4064)
		(layers "F.Cu" "B.Cu")
		(net "GND")
	)
	(via
		(at 195.198746 -487.0577)
		(size 0.7112)
		(drill 0.4064)
		(layers "F.Cu" "B.Cu")
		(net "GND")
	)
	(via
		(at 81.609946 -260.2865)
		(size 0.7112)
		(drill 0.4064)
		(layers "F.Cu" "B.Cu")
		(net "GND")
	)
	(via
		(at 56.133746 -310.9849)
		(size 0.7112)
		(drill 0.4064)
		(layers "F.Cu" "B.Cu")
		(net "GND")
	)
	(via
		(at 91.439746 -477.1517)
		(size 0.7112)
		(drill 0.4064)
		(layers "F.Cu" "B.Cu")
		(net "GND")
	)
	(via
		(at 13.715746 -200.914)
		(size 0.7112)
		(drill 0.4064)
		(layers "F.Cu" "B.Cu")
		(net "GND")
	)
	(via
		(at 171.703746 -449.3387)
		(size 0.7112)
		(drill 0.4064)
		(layers "F.Cu" "B.Cu")
		(net "GND")
	)
	(via
		(at 82.956146 -282.5369)
		(size 0.7112)
		(drill 0.4064)
		(layers "F.Cu" "B.Cu")
		(net "GND")
	)
	(via
		(at 87.756746 -1.2827)
		(size 0.7112)
		(drill 0.4064)
		(layers "F.Cu" "B.Cu")
		(net "GND")
	)
	(via
		(at 20.447 -278.7777)
		(size 0.5588)
		(drill 0.3048)
		(layers "F.Cu" "B.Cu")
		(net "GND")
	)
	(via
		(at 248.030746 -1.6637)
		(size 0.7112)
		(drill 0.4064)
		(layers "F.Cu" "B.Cu")
		(net "GND")
	)
	(via
		(at 241.477546 -281.3685)
		(size 0.7112)
		(drill 0.4064)
		(layers "F.Cu" "B.Cu")
		(net "GND")
	)
	(via
		(at 142.493746 -253.7587)
		(size 0.7112)
		(drill 0.4064)
		(layers "F.Cu" "B.Cu")
		(net "GND")
	)
	(via
		(at 167.385746 -243.5987)
		(size 0.7112)
		(drill 0.4064)
		(layers "F.Cu" "B.Cu")
		(net "GND")
	)
	(via
		(at 56.006746 -146.6977)
		(size 0.7112)
		(drill 0.4064)
		(layers "F.Cu" "B.Cu")
		(net "GND")
	)
	(via
		(at 209.168746 -425.2087)
		(size 0.7112)
		(drill 0.4064)
		(layers "F.Cu" "B.Cu")
		(net "GND")
	)
	(via
		(at 88.645746 -482.1047)
		(size 0.7112)
		(drill 0.4064)
		(layers "F.Cu" "B.Cu")
		(net "GND")
	)
	(via
		(at 90.296746 -55.6387)
		(size 0.7112)
		(drill 0.4064)
		(layers "F.Cu" "B.Cu")
		(net "GND")
	)
	(via
		(at 259.333746 -40.2717)
		(size 0.7112)
		(drill 0.4064)
		(layers "F.Cu" "B.Cu")
		(net "GND")
	)
	(via
		(at 180.111146 -444.9699)
		(size 0.7112)
		(drill 0.4064)
		(layers "F.Cu" "B.Cu")
		(net "GND")
	)
	(via
		(at 208.584546 -34.9123)
		(size 0.7112)
		(drill 0.4064)
		(layers "F.Cu" "B.Cu")
		(net "GND")
	)
	(via
		(at 54.203346 -381.0762)
		(size 0.7112)
		(drill 0.4064)
		(layers "F.Cu" "B.Cu")
		(net "GND")
	)
	(via
		(at 101.980746 -20.4597)
		(size 0.5588)
		(drill 0.3048)
		(layers "F.Cu" "B.Cu")
		(net "GND")
	)
	(via
		(at 203.961746 -118.3767)
		(size 0.7112)
		(drill 0.4064)
		(layers "F.Cu" "B.Cu")
		(net "GND")
	)
	(via
		(at 58.165746 -471.4367)
		(size 0.7112)
		(drill 0.4064)
		(layers "F.Cu" "B.Cu")
		(net "GND")
	)
	(via
		(at 113.283746 -496.4557)
		(size 0.7112)
		(drill 0.4064)
		(layers "F.Cu" "B.Cu")
		(net "GND")
	)
	(via
		(at 212.648546 -421.7797)
		(size 0.7112)
		(drill 0.4064)
		(layers "F.Cu" "B.Cu")
		(net "GND")
	)
	(via
		(at 145.668746 -88.0237)
		(size 0.7112)
		(drill 0.4064)
		(layers "F.Cu" "B.Cu")
		(net "GND")
	)
	(via
		(at 245.871746 -20.8407)
		(size 0.7112)
		(drill 0.4064)
		(layers "F.Cu" "B.Cu")
		(net "GND")
	)
	(via
		(at 2.870708 -41.021)
		(size 0.7112)
		(drill 0.4064)
		(layers "F.Cu" "B.Cu")
		(net "GND")
	)
	(via
		(at 69.925946 -204.8129)
		(size 0.7112)
		(drill 0.4064)
		(layers "F.Cu" "B.Cu")
		(net "GND")
	)
	(via
		(at 80.847946 -263.8425)
		(size 0.7112)
		(drill 0.4064)
		(layers "F.Cu" "B.Cu")
		(net "GND")
	)
	(via
		(at 61.27877 -481.59797)
		(size 0.7112)
		(drill 0.4064)
		(layers "F.Cu" "B.Cu")
		(net "GND")
	)
	(via
		(at 176.783746 -305.5747)
		(size 0.7112)
		(drill 0.4064)
		(layers "F.Cu" "B.Cu")
		(net "GND")
	)
	(via
		(at 234.695746 -1.5367)
		(size 0.7112)
		(drill 0.4064)
		(layers "F.Cu" "B.Cu")
		(net "GND")
	)
	(via
		(at 2.387346 -342.2269)
		(size 0.7112)
		(drill 0.4064)
		(layers "F.Cu" "B.Cu")
		(net "GND")
	)
	(via
		(at 140.461746 -55.2577)
		(size 0.7112)
		(drill 0.4064)
		(layers "F.Cu" "B.Cu")
		(net "GND")
	)
	(via
		(at 32.146748 -424.335702)
		(size 0.7112)
		(drill 0.4064)
		(layers "F.Cu" "B.Cu")
		(net "GND")
	)
	(via
		(at 90.347546 -459.9305)
		(size 0.7112)
		(drill 0.4064)
		(layers "F.Cu" "B.Cu")
		(net "GND")
	)
	(via
		(at 5.968746 -118.985538)
		(size 0.5588)
		(drill 0.3048)
		(layers "F.Cu" "B.Cu")
		(net "GND")
	)
	(via
		(at 184.378346 -471.2589)
		(size 0.7112)
		(drill 0.4064)
		(layers "F.Cu" "B.Cu")
		(net "GND")
	)
	(via
		(at 12.953746 -12.1285)
		(size 0.7112)
		(drill 0.4064)
		(layers "F.Cu" "B.Cu")
		(net "GND")
	)
	(via
		(at 147.827746 -348.0181)
		(size 0.7112)
		(drill 0.4064)
		(layers "F.Cu" "B.Cu")
		(net "GND")
	)
	(via
		(at 98.932746 -485.9147)
		(size 0.7112)
		(drill 0.4064)
		(layers "F.Cu" "B.Cu")
		(net "GND")
	)
	(via
		(at 1.800606 -42.192194)
		(size 0.7112)
		(drill 0.4064)
		(layers "F.Cu" "B.Cu")
		(net "GND")
	)
	(via
		(at 83.438746 -161.4551)
		(size 0.7112)
		(drill 0.4064)
		(layers "F.Cu" "B.Cu")
		(net "GND")
	)
	(via
		(at 85.724746 -71.7677)
		(size 0.7112)
		(drill 0.4064)
		(layers "F.Cu" "B.Cu")
		(net "GND")
	)
	(via
		(at 76.631546 -349.9993)
		(size 0.7112)
		(drill 0.4064)
		(layers "F.Cu" "B.Cu")
		(net "GND")
	)
	(via
		(at 163.321746 -143.8275)
		(size 0.7112)
		(drill 0.4064)
		(layers "F.Cu" "B.Cu")
		(net "GND")
	)
	(via
		(at 61.518546 -238.4425)
		(size 0.7112)
		(drill 0.4064)
		(layers "F.Cu" "B.Cu")
		(net "GND")
	)
	(via
		(at 29.590746 -476.8977)
		(size 0.7112)
		(drill 0.4064)
		(layers "F.Cu" "B.Cu")
		(net "GND")
	)
	(via
		(at 177.164746 -293.0017)
		(size 0.7112)
		(drill 0.4064)
		(layers "F.Cu" "B.Cu")
		(net "GND")
	)
	(via
		(at 31.368746 -37.8587)
		(size 0.7112)
		(drill 0.4064)
		(layers "F.Cu" "B.Cu")
		(net "GND")
	)
	(via
		(at 75.031346 -328.4093)
		(size 0.7112)
		(drill 0.4064)
		(layers "F.Cu" "B.Cu")
		(net "GND")
	)
	(via
		(at 181.355746 -266.4587)
		(size 0.7112)
		(drill 0.4064)
		(layers "F.Cu" "B.Cu")
		(net "GND")
	)
	(via
		(at 191.820546 -123.9901)
		(size 0.7112)
		(drill 0.4064)
		(layers "F.Cu" "B.Cu")
		(net "GND")
	)
	(via
		(at 28.320746 -333.1972)
		(size 0.5588)
		(drill 0.3048)
		(layers "F.Cu" "B.Cu")
		(net "GND")
	)
	(via
		(at 160.197546 -480.5045)
		(size 0.7112)
		(drill 0.4064)
		(layers "F.Cu" "B.Cu")
		(net "GND")
	)
	(via
		(at 176.605946 -489.3183)
		(size 0.7112)
		(drill 0.4064)
		(layers "F.Cu" "B.Cu")
		(net "GND")
	)
	(via
		(at 186.994546 -355.3587)
		(size 0.7112)
		(drill 0.4064)
		(layers "F.Cu" "B.Cu")
		(net "GND")
	)
	(via
		(at 169.087546 -371.4115)
		(size 0.7112)
		(drill 0.4064)
		(layers "F.Cu" "B.Cu")
		(net "GND")
	)
	(via
		(at 199.262746 -1.5367)
		(size 0.7112)
		(drill 0.4064)
		(layers "F.Cu" "B.Cu")
		(net "GND")
	)
	(via
		(at 95.579946 -365.1631)
		(size 0.7112)
		(drill 0.4064)
		(layers "F.Cu" "B.Cu")
		(net "GND")
	)
	(via
		(at 139.064746 -198.1327)
		(size 0.7112)
		(drill 0.4064)
		(layers "F.Cu" "B.Cu")
		(net "GND")
	)
	(via
		(at 3.911346 -433.9209)
		(size 0.7112)
		(drill 0.4064)
		(layers "F.Cu" "B.Cu")
		(net "GND")
	)
	(via
		(at 12.953746 -5.3721)
		(size 0.7112)
		(drill 0.4064)
		(layers "F.Cu" "B.Cu")
		(net "GND")
	)
	(via
		(at 180.847746 -55.3847)
		(size 0.7112)
		(drill 0.4064)
		(layers "F.Cu" "B.Cu")
		(net "GND")
	)
	(via
		(at 68.579746 -267.3477)
		(size 0.7112)
		(drill 0.4064)
		(layers "F.Cu" "B.Cu")
		(net "GND")
	)
	(via
		(at 45.440346 -194.3735)
		(size 0.7112)
		(drill 0.4064)
		(layers "F.Cu" "B.Cu")
		(net "GND")
	)
	(via
		(at 112.902746 -280.0477)
		(size 0.7112)
		(drill 0.4064)
		(layers "F.Cu" "B.Cu")
		(net "GND")
	)
	(via
		(at 5.996432 -399.453862)
		(size 0.5588)
		(drill 0.3048)
		(layers "F.Cu" "B.Cu")
		(net "GND")
	)
	(via
		(at 181.863746 -450.1007)
		(size 0.7112)
		(drill 0.4064)
		(layers "F.Cu" "B.Cu")
		(net "GND")
	)
	(via
		(at 197.865746 -204.9653)
		(size 0.7112)
		(drill 0.4064)
		(layers "F.Cu" "B.Cu")
		(net "GND")
	)
	(via
		(at 221.33179 -182.736744)
		(size 0.7112)
		(drill 0.4064)
		(layers "F.Cu" "B.Cu")
		(net "GND")
	)
	(via
		(at 193.877946 -479.6409)
		(size 0.7112)
		(drill 0.4064)
		(layers "F.Cu" "B.Cu")
		(net "GND")
	)
	(via
		(at 23.5966 -426.256704)
		(size 0.5588)
		(drill 0.3048)
		(layers "F.Cu" "B.Cu")
		(net "GND")
	)
	(via
		(at 114.833146 -193.6623)
		(size 0.7112)
		(drill 0.4064)
		(layers "F.Cu" "B.Cu")
		(net "GND")
	)
	(via
		(at 152.399746 -351.1677)
		(size 0.7112)
		(drill 0.4064)
		(layers "F.Cu" "B.Cu")
		(net "GND")
	)
	(via
		(at 96.773746 -410.9847)
		(size 0.7112)
		(drill 0.3556)
		(layers "F.Cu" "B.Cu")
		(net "GND")
	)
	(via
		(at 28.39466 -33.593786)
		(size 0.5588)
		(drill 0.3048)
		(layers "F.Cu" "B.Cu")
		(net "GND")
	)
	(via
		(at 116.458746 -97.0407)
		(size 0.7112)
		(drill 0.4064)
		(layers "F.Cu" "B.Cu")
		(net "GND")
	)
	(via
		(at 223.528382 -268.882368)
		(size 0.7112)
		(drill 0.4064)
		(layers "F.Cu" "B.Cu")
		(net "GND")
	)
	(via
		(at 23.622 -230.41991)
		(size 0.7112)
		(drill 0.4064)
		(layers "F.Cu" "B.Cu")
		(net "GND")
	)
	(via
		(at 163.347146 -391.5029)
		(size 0.7112)
		(drill 0.4064)
		(layers "F.Cu" "B.Cu")
		(net "GND")
	)
	(via
		(at 40.741346 -234.4039)
		(size 0.5588)
		(drill 0.3048)
		(layers "F.Cu" "B.Cu")
		(net "GND")
	)
	(via
		(at 54.558946 -196.7865)
		(size 0.7112)
		(drill 0.4064)
		(layers "F.Cu" "B.Cu")
		(net "GND")
	)
	(via
		(at 45.644054 -438.0357)
		(size 0.7112)
		(drill 0.4064)
		(layers "F.Cu" "B.Cu")
		(net "GND")
	)
	(via
		(at 221.055692 -265.487658)
		(size 0.7112)
		(drill 0.4064)
		(layers "F.Cu" "B.Cu")
		(net "GND")
	)
	(via
		(at 253.517146 -296.4053)
		(size 0.7112)
		(drill 0.4064)
		(layers "F.Cu" "B.Cu")
		(net "GND")
	)
	(via
		(at 6.8326 -135.3312)
		(size 0.5588)
		(drill 0.3048)
		(layers "F.Cu" "B.Cu")
		(net "GND")
	)
	(via
		(at 125.475746 -210.3247)
		(size 0.7112)
		(drill 0.4064)
		(layers "F.Cu" "B.Cu")
		(net "GND")
	)
	(via
		(at 144.855946 -501.9675)
		(size 0.7112)
		(drill 0.4064)
		(layers "F.Cu" "B.Cu")
		(net "GND")
	)
	(via
		(at 91.439746 -484.2637)
		(size 0.7112)
		(drill 0.4064)
		(layers "F.Cu" "B.Cu")
		(net "GND")
	)
	(via
		(at 65.150746 -245.6307)
		(size 0.7112)
		(drill 0.4064)
		(layers "F.Cu" "B.Cu")
		(net "GND")
	)
	(via
		(at 19.684746 -244.386608)
		(size 0.7112)
		(drill 0.4064)
		(layers "F.Cu" "B.Cu")
		(net "GND")
	)
	(via
		(at 19.59991 -130.7211)
		(size 0.7112)
		(drill 0.4064)
		(layers "F.Cu" "B.Cu")
		(net "GND")
	)
	(via
		(at 190.880746 -12.2809)
		(size 0.7112)
		(drill 0.4064)
		(layers "F.Cu" "B.Cu")
		(net "GND")
	)
	(via
		(at 232.333546 -133.2611)
		(size 0.7112)
		(drill 0.4064)
		(layers "F.Cu" "B.Cu")
		(net "GND")
	)
	(via
		(at 229.514146 -428.4599)
		(size 0.7112)
		(drill 0.4064)
		(layers "F.Cu" "B.Cu")
		(net "GND")
	)
	(via
		(at 251.815346 -5.7023)
		(size 0.7112)
		(drill 0.4064)
		(layers "F.Cu" "B.Cu")
		(net "GND")
	)
	(via
		(at 199.262746 -84.8487)
		(size 0.5588)
		(drill 0.3048)
		(layers "F.Cu" "B.Cu")
		(net "GND")
	)
	(via
		(at 234.187746 -276.9997)
		(size 0.7112)
		(drill 0.4064)
		(layers "F.Cu" "B.Cu")
		(net "GND")
	)
	(via
		(at 52.6542 -162.4076)
		(size 0.7112)
		(drill 0.4064)
		(layers "F.Cu" "B.Cu")
		(net "GND")
	)
	(via
		(at 131.673346 -488.5055)
		(size 0.7112)
		(drill 0.4064)
		(layers "F.Cu" "B.Cu")
		(net "GND")
	)
	(via
		(at 78.206346 -201.8157)
		(size 0.7112)
		(drill 0.4064)
		(layers "F.Cu" "B.Cu")
		(net "GND")
	)
	(via
		(at 80.212946 -14.0589)
		(size 0.7112)
		(drill 0.4064)
		(layers "F.Cu" "B.Cu")
		(net "GND")
	)
	(via
		(at 40.35679 -172.576744)
		(size 0.5588)
		(drill 0.3048)
		(layers "F.Cu" "B.Cu")
		(net "GND")
	)
	(via
		(at 157.860746 -114.8207)
		(size 0.7112)
		(drill 0.4064)
		(layers "F.Cu" "B.Cu")
		(net "GND")
	)
	(via
		(at 179.323746 -219.8497)
		(size 0.7112)
		(drill 0.4064)
		(layers "F.Cu" "B.Cu")
		(net "GND")
	)
	(via
		(at 111.124746 -69.8627)
		(size 0.7112)
		(drill 0.4064)
		(layers "F.Cu" "B.Cu")
		(net "GND")
	)
	(via
		(at 203.453746 -259.0927)
		(size 0.7112)
		(drill 0.4064)
		(layers "F.Cu" "B.Cu")
		(net "GND")
	)
	(via
		(at 71.373746 -220.9927)
		(size 0.7112)
		(drill 0.4064)
		(layers "F.Cu" "B.Cu")
		(net "GND")
	)
	(via
		(at 142.950946 -32.4485)
		(size 0.7112)
		(drill 0.4064)
		(layers "F.Cu" "B.Cu")
		(net "GND")
	)
	(via
		(at 181.863746 -447.8147)
		(size 0.7112)
		(drill 0.4064)
		(layers "F.Cu" "B.Cu")
		(net "GND")
	)
	(via
		(at 169.671746 -475.2213)
		(size 0.7112)
		(drill 0.4064)
		(layers "F.Cu" "B.Cu")
		(net "GND")
	)
	(via
		(at 178.434746 -504.8377)
		(size 0.7112)
		(drill 0.4064)
		(layers "F.Cu" "B.Cu")
		(net "GND")
	)
	(via
		(at 2.158746 -248.6787)
		(size 0.7112)
		(drill 0.4064)
		(layers "F.Cu" "B.Cu")
		(net "GND")
	)
	(via
		(at 35.686746 -159.0167)
		(size 0.7112)
		(drill 0.4064)
		(layers "F.Cu" "B.Cu")
		(net "GND")
	)
	(via
		(at 159.892746 -276.9997)
		(size 0.7112)
		(drill 0.4064)
		(layers "F.Cu" "B.Cu")
		(net "GND")
	)
	(via
		(at 206.577946 -28.1559)
		(size 0.7112)
		(drill 0.4064)
		(layers "F.Cu" "B.Cu")
		(net "GND")
	)
	(via
		(at 203.199746 -340.4997)
		(size 0.7112)
		(drill 0.4064)
		(layers "F.Cu" "B.Cu")
		(net "GND")
	)
	(via
		(at 62.484 -17.9832)
		(size 0.7112)
		(drill 0.4064)
		(layers "F.Cu" "B.Cu")
		(net "GND")
	)
	(via
		(at 65.150746 -434.3527)
		(size 0.7112)
		(drill 0.4064)
		(layers "F.Cu" "B.Cu")
		(net "GND")
	)
	(via
		(at 217.042746 -102.8827)
		(size 0.7112)
		(drill 0.4064)
		(layers "F.Cu" "B.Cu")
		(net "GND")
	)
	(via
		(at 158.622746 -15.6337)
		(size 0.7112)
		(drill 0.4064)
		(layers "F.Cu" "B.Cu")
		(net "GND")
	)
	(via
		(at 249.935746 -104.7877)
		(size 0.7112)
		(drill 0.4064)
		(layers "F.Cu" "B.Cu")
		(net "GND")
	)
	(via
		(at 109.727746 -407.8097)
		(size 0.7112)
		(drill 0.4064)
		(layers "F.Cu" "B.Cu")
		(net "GND")
	)
	(via
		(at 169.417746 -124.7267)
		(size 0.7112)
		(drill 0.4064)
		(layers "F.Cu" "B.Cu")
		(net "GND")
	)
	(via
		(at 184.403746 -31.5087)
		(size 0.7112)
		(drill 0.4064)
		(layers "F.Cu" "B.Cu")
		(net "GND")
	)
	(via
		(at 49.161446 -146.27225)
		(size 0.5588)
		(drill 0.3048)
		(layers "F.Cu" "B.Cu")
		(net "GND")
	)
	(via
		(at 183.260746 -156.8577)
		(size 0.7112)
		(drill 0.4064)
		(layers "F.Cu" "B.Cu")
		(net "GND")
	)
	(via
		(at 172.847 -71.2978)
		(size 0.7112)
		(drill 0.4064)
		(layers "F.Cu" "B.Cu")
		(net "GND")
	)
	(via
		(at 165.175946 -292.9001)
		(size 0.7112)
		(drill 0.4064)
		(layers "F.Cu" "B.Cu")
		(net "GND")
	)
	(via
		(at 171.449746 -152.7937)
		(size 0.7112)
		(drill 0.4064)
		(layers "F.Cu" "B.Cu")
		(net "GND")
	)
	(via
		(at 54.076346 -390.0297)
		(size 0.7112)
		(drill 0.4064)
		(layers "F.Cu" "B.Cu")
		(net "GND")
	)
	(via
		(at 131.952746 -119.7737)
		(size 0.7112)
		(drill 0.4064)
		(layers "F.Cu" "B.Cu")
		(net "GND")
	)
	(via
		(at 43.0022 -33.0962)
		(size 0.7112)
		(drill 0.4064)
		(layers "F.Cu" "B.Cu")
		(net "GND")
	)
	(via
		(at 6.679946 -207.0227)
		(size 0.5588)
		(drill 0.3048)
		(layers "F.Cu" "B.Cu")
		(net "GND")
	)
	(via
		(at 177.799746 -154.9527)
		(size 0.7112)
		(drill 0.4064)
		(layers "F.Cu" "B.Cu")
		(net "GND")
	)
	(via
		(at 175.386746 -443.2173)
		(size 0.7112)
		(drill 0.4064)
		(layers "F.Cu" "B.Cu")
		(net "GND")
	)
	(via
		(at 59.435492 -90.817446)
		(size 0.5588)
		(drill 0.3048)
		(layers "F.Cu" "B.Cu")
		(net "GND")
	)
	(via
		(at 243.585746 -24.3967)
		(size 0.5588)
		(drill 0.3048)
		(layers "F.Cu" "B.Cu")
		(net "GND")
	)
	(via
		(at 76.428346 -109.6899)
		(size 0.7112)
		(drill 0.4064)
		(layers "F.Cu" "B.Cu")
		(net "GND")
	)
	(via
		(at 152.628346 -314.6171)
		(size 0.7112)
		(drill 0.4064)
		(layers "F.Cu" "B.Cu")
		(net "GND")
	)
	(via
		(at 150.697946 -447.2813)
		(size 0.7112)
		(drill 0.4064)
		(layers "F.Cu" "B.Cu")
		(net "GND")
	)
	(via
		(at 133.984746 -300.1137)
		(size 0.7112)
		(drill 0.4064)
		(layers "F.Cu" "B.Cu")
		(net "GND")
	)
	(via
		(at 221.162626 -162.48507)
		(size 0.7112)
		(drill 0.4064)
		(layers "F.Cu" "B.Cu")
		(net "GND")
	)
	(via
		(at 217.164158 -462.024476)
		(size 0.7112)
		(drill 0.4064)
		(layers "F.Cu" "B.Cu")
		(net "GND")
	)
	(via
		(at 78.104746 -164.3507)
		(size 0.7112)
		(drill 0.4064)
		(layers "F.Cu" "B.Cu")
		(net "GND")
	)
	(via
		(at 203.326746 -239.7887)
		(size 0.7112)
		(drill 0.4064)
		(layers "F.Cu" "B.Cu")
		(net "GND")
	)
	(via
		(at 138.759946 -502.2215)
		(size 0.7112)
		(drill 0.4064)
		(layers "F.Cu" "B.Cu")
		(net "GND")
	)
	(via
		(at 187.807346 -174.7901)
		(size 0.7112)
		(drill 0.4064)
		(layers "F.Cu" "B.Cu")
		(net "GND")
	)
	(via
		(at 161.315146 -429.5521)
		(size 0.7112)
		(drill 0.4064)
		(layers "F.Cu" "B.Cu")
		(net "GND")
	)
	(via
		(at 175.005746 -49.9237)
		(size 0.7112)
		(drill 0.4064)
		(layers "F.Cu" "B.Cu")
		(net "GND")
	)
	(via
		(at 52.120546 -457.6953)
		(size 0.7112)
		(drill 0.4064)
		(layers "F.Cu" "B.Cu")
		(net "GND")
	)
	(via
		(at 76.250546 -212.1535)
		(size 0.7112)
		(drill 0.4064)
		(layers "F.Cu" "B.Cu")
		(net "GND")
	)
	(via
		(at 132.206746 -89.8017)
		(size 0.7112)
		(drill 0.4064)
		(layers "F.Cu" "B.Cu")
		(net "GND")
	)
	(via
		(at 41.554146 -480.5807)
		(size 0.7112)
		(drill 0.4064)
		(layers "F.Cu" "B.Cu")
		(net "GND")
	)
	(via
		(at 219.71 -191.0334)
		(size 0.7112)
		(drill 0.4064)
		(layers "F.Cu" "B.Cu")
		(net "GND")
	)
	(via
		(at 124.078746 -167.3987)
		(size 0.7112)
		(drill 0.4064)
		(layers "F.Cu" "B.Cu")
		(net "GND")
	)
	(via
		(at 81.813146 -108.4199)
		(size 0.7112)
		(drill 0.4064)
		(layers "F.Cu" "B.Cu")
		(net "GND")
	)
	(via
		(at 171.195746 -163.8681)
		(size 0.7112)
		(drill 0.4064)
		(layers "F.Cu" "B.Cu")
		(net "GND")
	)
	(via
		(at 187.502546 -34.9123)
		(size 0.7112)
		(drill 0.4064)
		(layers "F.Cu" "B.Cu")
		(net "GND")
	)
	(via
		(at 249.935746 -84.7217)
		(size 0.7112)
		(drill 0.4064)
		(layers "F.Cu" "B.Cu")
		(net "GND")
	)
	(via
		(at 208.1276 -437.3626)
		(size 0.7112)
		(drill 0.4064)
		(layers "F.Cu" "B.Cu")
		(net "GND")
	)
	(via
		(at 203.453746 -226.7077)
		(size 0.7112)
		(drill 0.4064)
		(layers "F.Cu" "B.Cu")
		(net "GND")
	)
	(via
		(at 35.8902 -474.0656)
		(size 0.5588)
		(drill 0.3048)
		(layers "F.Cu" "B.Cu")
		(net "GND")
	)
	(via
		(at 206.882746 -152.7937)
		(size 0.7112)
		(drill 0.4064)
		(layers "F.Cu" "B.Cu")
		(net "GND")
	)
	(via
		(at 83.819746 -504.8377)
		(size 0.7112)
		(drill 0.4064)
		(layers "F.Cu" "B.Cu")
		(net "GND")
	)
	(via
		(at 153.110946 -484.2129)
		(size 0.7112)
		(drill 0.4064)
		(layers "F.Cu" "B.Cu")
		(net "GND")
	)
	(via
		(at 19.557746 -388.1247)
		(size 0.7112)
		(drill 0.4064)
		(layers "F.Cu" "B.Cu")
		(net "GND")
	)
	(via
		(at 244.3734 -385.064)
		(size 0.7112)
		(drill 0.4064)
		(layers "F.Cu" "B.Cu")
		(net "GND")
	)
	(via
		(at 239.776 -353.5426)
		(size 0.7112)
		(drill 0.4064)
		(layers "F.Cu" "B.Cu")
		(net "GND")
	)
	(via
		(at 54.482746 -293.1795)
		(size 0.7112)
		(drill 0.4064)
		(layers "F.Cu" "B.Cu")
		(net "GND")
	)
	(via
		(at 149.478746 -279.7937)
		(size 0.7112)
		(drill 0.4064)
		(layers "F.Cu" "B.Cu")
		(net "GND")
	)
	(via
		(at 192.226946 -309.2831)
		(size 0.7112)
		(drill 0.4064)
		(layers "F.Cu" "B.Cu")
		(net "GND")
	)
	(via
		(at 236.854746 -48.6537)
		(size 0.7112)
		(drill 0.4064)
		(layers "F.Cu" "B.Cu")
		(net "GND")
	)
	(via
		(at 75.6412 -396.6464)
		(size 0.5588)
		(drill 0.3048)
		(layers "F.Cu" "B.Cu")
		(net "GND")
	)
	(via
		(at 65.074546 -232.7275)
		(size 0.7112)
		(drill 0.4064)
		(layers "F.Cu" "B.Cu")
		(net "GND")
	)
	(via
		(at 255.015746 -133.8199)
		(size 0.7112)
		(drill 0.4064)
		(layers "F.Cu" "B.Cu")
		(net "GND")
	)
	(via
		(at 176.783746 -336.1309)
		(size 0.7112)
		(drill 0.4064)
		(layers "F.Cu" "B.Cu")
		(net "GND")
	)
	(via
		(at 124.713746 -112.9157)
		(size 0.7112)
		(drill 0.4064)
		(layers "F.Cu" "B.Cu")
		(net "GND")
	)
	(via
		(at 8.838946 -494.4745)
		(size 0.5588)
		(drill 0.3048)
		(layers "F.Cu" "B.Cu")
		(net "GND")
	)
	(via
		(at 171.424346 -480.6569)
		(size 0.7112)
		(drill 0.4064)
		(layers "F.Cu" "B.Cu")
		(net "GND")
	)
	(via
		(at 93.293946 -501.1293)
		(size 0.7112)
		(drill 0.4064)
		(layers "F.Cu" "B.Cu")
		(net "GND")
	)
	(via
		(at 203.707746 -1.6637)
		(size 0.7112)
		(drill 0.4064)
		(layers "F.Cu" "B.Cu")
		(net "GND")
	)
	(via
		(at 73.507346 -100.5205)
		(size 0.7112)
		(drill 0.4064)
		(layers "F.Cu" "B.Cu")
		(net "GND")
	)
	(via
		(at 203.707746 -211.8487)
		(size 0.7112)
		(drill 0.4064)
		(layers "F.Cu" "B.Cu")
		(net "GND")
	)
	(via
		(at 83.768946 -246.5451)
		(size 0.7112)
		(drill 0.4064)
		(layers "F.Cu" "B.Cu")
		(net "GND")
	)
	(via
		(at 181.355746 -258.3307)
		(size 0.7112)
		(drill 0.4064)
		(layers "F.Cu" "B.Cu")
		(net "GND")
	)
	(via
		(at 64.134746 -241.0079)
		(size 0.7112)
		(drill 0.4064)
		(layers "F.Cu" "B.Cu")
		(net "GND")
	)
	(via
		(at 115.442746 -295.0337)
		(size 0.7112)
		(drill 0.4064)
		(layers "F.Cu" "B.Cu")
		(net "GND")
	)
	(via
		(at 126.796546 -343.0397)
		(size 0.7112)
		(drill 0.4064)
		(layers "F.Cu" "B.Cu")
		(net "GND")
	)
	(via
		(at 130.682746 -138.6967)
		(size 0.7112)
		(drill 0.4064)
		(layers "F.Cu" "B.Cu")
		(net "GND")
	)
	(via
		(at 146.811746 -185.9407)
		(size 0.7112)
		(drill 0.4064)
		(layers "F.Cu" "B.Cu")
		(net "GND")
	)
	(via
		(at 22.605746 -136.6647)
		(size 0.5588)
		(drill 0.3048)
		(layers "F.Cu" "B.Cu")
		(net "GND")
	)
	(via
		(at 95.275146 -408.4955)
		(size 0.7112)
		(drill 0.4064)
		(layers "F.Cu" "B.Cu")
		(net "GND")
	)
	(via
		(at 40.399716 -477.9772)
		(size 0.7112)
		(drill 0.4064)
		(layers "F.Cu" "B.Cu")
		(net "GND")
	)
	(via
		(at 223.8248 -165.6334)
		(size 0.7112)
		(drill 0.4064)
		(layers "F.Cu" "B.Cu")
		(net "GND")
	)
	(via
		(at 56.971946 -125.6411)
		(size 0.7112)
		(drill 0.4064)
		(layers "F.Cu" "B.Cu")
		(net "GND")
	)
	(via
		(at 112.470946 -36.1823)
		(size 0.7112)
		(drill 0.4064)
		(layers "F.Cu" "B.Cu")
		(net "GND")
	)
	(via
		(at 62.356746 -361.8357)
		(size 0.7112)
		(drill 0.4064)
		(layers "F.Cu" "B.Cu")
		(net "GND")
	)
	(via
		(at 106.882946 -502.2215)
		(size 0.7112)
		(drill 0.4064)
		(layers "F.Cu" "B.Cu")
		(net "GND")
	)
	(via
		(at 258.292346 -439.8391)
		(size 0.7112)
		(drill 0.4064)
		(layers "F.Cu" "B.Cu")
		(net "GND")
	)
	(via
		(at 190.499746 -240.4237)
		(size 0.7112)
		(drill 0.4064)
		(layers "F.Cu" "B.Cu")
		(net "GND")
	)
	(via
		(at 11.810746 -17.5387)
		(size 0.7112)
		(drill 0.3556)
		(layers "F.Cu" "B.Cu")
		(net "GND")
	)
	(via
		(at 2.869946 -469.9127)
		(size 0.7112)
		(drill 0.4064)
		(layers "F.Cu" "B.Cu")
		(net "GND")
	)
	(via
		(at 66.344546 -311.8993)
		(size 0.7112)
		(drill 0.4064)
		(layers "F.Cu" "B.Cu")
		(net "GND")
	)
	(via
		(at 69.8246 -283.3624)
		(size 0.7112)
		(drill 0.4064)
		(layers "F.Cu" "B.Cu")
		(net "GND")
	)
	(via
		(at 131.927346 -481.5205)
		(size 0.7112)
		(drill 0.4064)
		(layers "F.Cu" "B.Cu")
		(net "GND")
	)
	(via
		(at 168.173146 -393.6111)
		(size 0.7112)
		(drill 0.4064)
		(layers "F.Cu" "B.Cu")
		(net "GND")
	)
	(via
		(at 36.0172 -472.567)
		(size 0.5588)
		(drill 0.3048)
		(layers "F.Cu" "B.Cu")
		(net "GND")
	)
	(via
		(at 211.200746 -304.9397)
		(size 0.7112)
		(drill 0.4064)
		(layers "F.Cu" "B.Cu")
		(net "GND")
	)
	(via
		(at 259.587746 -136.9187)
		(size 0.7112)
		(drill 0.4064)
		(layers "F.Cu" "B.Cu")
		(net "GND")
	)
	(via
		(at 239.902746 -190.5127)
		(size 0.7112)
		(drill 0.4064)
		(layers "F.Cu" "B.Cu")
		(net "GND")
	)
	(via
		(at 68.478146 -234.6833)
		(size 0.7112)
		(drill 0.4064)
		(layers "F.Cu" "B.Cu")
		(net "GND")
	)
	(via
		(at 176.529746 -345.4527)
		(size 0.7112)
		(drill 0.4064)
		(layers "F.Cu" "B.Cu")
		(net "GND")
	)
	(via
		(at 167.426386 -455.238612)
		(size 0.7112)
		(drill 0.4064)
		(layers "F.Cu" "B.Cu")
		(net "GND")
	)
	(via
		(at 5.968746 -408.9527)
		(size 0.5588)
		(drill 0.3048)
		(layers "F.Cu" "B.Cu")
		(net "GND")
	)
	(via
		(at 87.375746 -48.2727)
		(size 0.7112)
		(drill 0.4064)
		(layers "F.Cu" "B.Cu")
		(net "GND")
	)
	(via
		(at 5.943346 -132.978906)
		(size 0.5588)
		(drill 0.3048)
		(layers "F.Cu" "B.Cu")
		(net "GND")
	)
	(via
		(at 38.531546 -294.2717)
		(size 0.7112)
		(drill 0.4064)
		(layers "F.Cu" "B.Cu")
		(net "GND")
	)
	(via
		(at 198.627746 -364.4011)
		(size 0.7112)
		(drill 0.4064)
		(layers "F.Cu" "B.Cu")
		(net "GND")
	)
	(via
		(at 217.677746 -500.3927)
		(size 0.7112)
		(drill 0.4064)
		(layers "F.Cu" "B.Cu")
		(net "GND")
	)
	(via
		(at 11.4046 -163.2712)
		(size 0.5588)
		(drill 0.3048)
		(layers "F.Cu" "B.Cu")
		(net "GND")
	)
	(via
		(at 251.129546 -44.2849)
		(size 0.7112)
		(drill 0.4064)
		(layers "F.Cu" "B.Cu")
		(net "GND")
	)
	(via
		(at 201.802746 -440.5757)
		(size 0.7112)
		(drill 0.4064)
		(layers "F.Cu" "B.Cu")
		(net "GND")
	)
	(via
		(at 165.887146 -204.0509)
		(size 0.7112)
		(drill 0.4064)
		(layers "F.Cu" "B.Cu")
		(net "GND")
	)
	(via
		(at 66.128646 -289.3568)
		(size 0.7112)
		(drill 0.4064)
		(layers "F.Cu" "B.Cu")
		(net "GND")
	)
	(via
		(at 183.438546 -397.3195)
		(size 0.7112)
		(drill 0.4064)
		(layers "F.Cu" "B.Cu")
		(net "GND")
	)
	(via
		(at 110.5662 -435.6862)
		(size 0.7112)
		(drill 0.4064)
		(layers "F.Cu" "B.Cu")
		(net "GND")
	)
	(via
		(at 35.331146 -179.6161)
		(size 0.7112)
		(drill 0.4064)
		(layers "F.Cu" "B.Cu")
		(net "GND")
	)
	(via
		(at 218.566746 -154.3177)
		(size 0.7112)
		(drill 0.4064)
		(layers "F.Cu" "B.Cu")
		(net "GND")
	)
	(via
		(at 89.179146 -429.5521)
		(size 0.7112)
		(drill 0.4064)
		(layers "F.Cu" "B.Cu")
		(net "GND")
	)
	(via
		(at 159.327342 -455.65187)
		(size 0.7112)
		(drill 0.4064)
		(layers "F.Cu" "B.Cu")
		(net "GND")
	)
	(via
		(at 3.886708 -41.021)
		(size 0.7112)
		(drill 0.4064)
		(layers "F.Cu" "B.Cu")
		(net "GND")
	)
	(via
		(at 62.865 -380.746)
		(size 0.7112)
		(drill 0.4064)
		(layers "F.Cu" "B.Cu")
		(net "GND")
	)
	(via
		(at 28.829 -343.408)
		(size 0.5588)
		(drill 0.3048)
		(layers "F.Cu" "B.Cu")
		(net "GND")
	)
	(via
		(at 149.478746 -1.6637)
		(size 0.7112)
		(drill 0.4064)
		(layers "F.Cu" "B.Cu")
		(net "GND")
	)
	(via
		(at 93.293946 -497.0653)
		(size 0.7112)
		(drill 0.4064)
		(layers "F.Cu" "B.Cu")
		(net "GND")
	)
	(via
		(at 231.368346 -393.5095)
		(size 0.7112)
		(drill 0.4064)
		(layers "F.Cu" "B.Cu")
		(net "GND")
	)
	(via
		(at 136.905746 -142.7607)
		(size 0.7112)
		(drill 0.4064)
		(layers "F.Cu" "B.Cu")
		(net "GND")
	)
	(via
		(at 254.253746 -494.3729)
		(size 0.7112)
		(drill 0.4064)
		(layers "F.Cu" "B.Cu")
		(net "GND")
	)
	(via
		(at 204.774546 -477.3295)
		(size 0.7112)
		(drill 0.4064)
		(layers "F.Cu" "B.Cu")
		(net "GND")
	)
	(via
		(at 86.715346 -141.9733)
		(size 0.7112)
		(drill 0.4064)
		(layers "F.Cu" "B.Cu")
		(net "GND")
	)
	(via
		(at 65.785746 -354.8253)
		(size 0.7112)
		(drill 0.4064)
		(layers "F.Cu" "B.Cu")
		(net "GND")
	)
	(via
		(at 203.707746 -216.6747)
		(size 0.7112)
		(drill 0.4064)
		(layers "F.Cu" "B.Cu")
		(net "GND")
	)
	(via
		(at 105.358946 -420.0525)
		(size 0.7112)
		(drill 0.4064)
		(layers "F.Cu" "B.Cu")
		(net "GND")
	)
	(via
		(at 191.769746 -176.2887)
		(size 0.7112)
		(drill 0.4064)
		(layers "F.Cu" "B.Cu")
		(net "GND")
	)
	(via
		(at 36.3728 -283.5402)
		(size 0.7112)
		(drill 0.4064)
		(layers "F.Cu" "B.Cu")
		(net "GND")
	)
	(via
		(at 152.348946 -392.3411)
		(size 0.7112)
		(drill 0.4064)
		(layers "F.Cu" "B.Cu")
		(net "GND")
	)
	(via
		(at 44.068746 -37.8587)
		(size 0.5588)
		(drill 0.3048)
		(layers "F.Cu" "B.Cu")
		(net "GND")
	)
	(via
		(at 131.825746 -105.8037)
		(size 0.7112)
		(drill 0.4064)
		(layers "F.Cu" "B.Cu")
		(net "GND")
	)
	(via
		(at 55.1942 -207.4672)
		(size 0.7112)
		(drill 0.4064)
		(layers "F.Cu" "B.Cu")
		(net "GND")
	)
	(via
		(at 40.11041 -360.79684)
		(size 0.7112)
		(drill 0.4064)
		(layers "F.Cu" "B.Cu")
		(net "GND")
	)
	(via
		(at 171.576746 -446.2907)
		(size 0.7112)
		(drill 0.4064)
		(layers "F.Cu" "B.Cu")
		(net "GND")
	)
	(via
		(at 230.377746 -56.9341)
		(size 0.7112)
		(drill 0.4064)
		(layers "F.Cu" "B.Cu")
		(net "GND")
	)
	(via
		(at 10.134346 -191.7319)
		(size 0.7112)
		(drill 0.4064)
		(layers "F.Cu" "B.Cu")
		(net "GND")
	)
	(via
		(at 165.861746 -364.6297)
		(size 0.7112)
		(drill 0.4064)
		(layers "F.Cu" "B.Cu")
		(net "GND")
	)
	(via
		(at 176.047146 -437.4769)
		(size 0.7112)
		(drill 0.4064)
		(layers "F.Cu" "B.Cu")
		(net "GND")
	)
	(via
		(at 15.354046 -468.0077)
		(size 0.5588)
		(drill 0.3048)
		(layers "F.Cu" "B.Cu")
		(net "GND")
	)
	(via
		(at 35.305746 -133.150102)
		(size 0.5588)
		(drill 0.3048)
		(layers "F.Cu" "B.Cu")
		(net "GND")
	)
	(via
		(at 131.292346 -77.9653)
		(size 0.7112)
		(drill 0.4064)
		(layers "F.Cu" "B.Cu")
		(net "GND")
	)
	(via
		(at 28.701746 -280.34996)
		(size 0.5588)
		(drill 0.3048)
		(layers "F.Cu" "B.Cu")
		(net "GND")
	)
	(via
		(at 208.076546 -343.8017)
		(size 0.7112)
		(drill 0.4064)
		(layers "F.Cu" "B.Cu")
		(net "GND")
	)
	(via
		(at 162.3568 -400.3548)
		(size 0.7112)
		(drill 0.4064)
		(layers "F.Cu" "B.Cu")
		(net "GND")
	)
	(via
		(at 69.214746 -113.0427)
		(size 0.7112)
		(drill 0.4064)
		(layers "F.Cu" "B.Cu")
		(net "GND")
	)
	(via
		(at 204.850746 -357.6447)
		(size 0.7112)
		(drill 0.4064)
		(layers "F.Cu" "B.Cu")
		(net "GND")
	)
	(via
		(at 135.254746 -428.8917)
		(size 0.7112)
		(drill 0.4064)
		(layers "F.Cu" "B.Cu")
		(net "GND")
	)
	(via
		(at 259.206746 -284.1117)
		(size 0.7112)
		(drill 0.4064)
		(layers "F.Cu" "B.Cu")
		(net "GND")
	)
	(via
		(at 72.135746 -471.4367)
		(size 0.7112)
		(drill 0.4064)
		(layers "F.Cu" "B.Cu")
		(net "GND")
	)
	(via
		(at 26.521918 -455.03592)
		(size 0.7112)
		(drill 0.4064)
		(layers "F.Cu" "B.Cu")
		(net "GND")
	)
	(via
		(at 121.564146 -273.1643)
		(size 0.7112)
		(drill 0.3556)
		(layers "F.Cu" "B.Cu")
		(net "GND")
	)
	(via
		(at 62.229746 -358.7877)
		(size 0.7112)
		(drill 0.4064)
		(layers "F.Cu" "B.Cu")
		(net "GND")
	)
	(via
		(at 22.072346 -61.6585)
		(size 0.7112)
		(drill 0.4064)
		(layers "F.Cu" "B.Cu")
		(net "GND")
	)
	(via
		(at 5.841746 -413.0167)
		(size 0.5588)
		(drill 0.3048)
		(layers "F.Cu" "B.Cu")
		(net "GND")
	)
	(via
		(at 30.555946 -456.2221)
		(size 0.7112)
		(drill 0.4064)
		(layers "F.Cu" "B.Cu")
		(net "GND")
	)
	(via
		(at 46.354746 -135.2677)
		(size 0.5588)
		(drill 0.3048)
		(layers "F.Cu" "B.Cu")
		(net "GND")
	)
	(via
		(at 5.968746 -361.0737)
		(size 0.5588)
		(drill 0.3048)
		(layers "F.Cu" "B.Cu")
		(net "GND")
	)
	(via
		(at 135.508746 -483.3747)
		(size 0.7112)
		(drill 0.4064)
		(layers "F.Cu" "B.Cu")
		(net "GND")
	)
	(via
		(at 142.493746 -240.9317)
		(size 0.7112)
		(drill 0.4064)
		(layers "F.Cu" "B.Cu")
		(net "GND")
	)
	(via
		(at 72.7964 -368.2238)
		(size 0.7112)
		(drill 0.4064)
		(layers "F.Cu" "B.Cu")
		(net "GND")
	)
	(via
		(at 19.125946 -66.4845)
		(size 0.7112)
		(drill 0.4064)
		(layers "F.Cu" "B.Cu")
		(net "GND")
	)
	(via
		(at 128.472946 -485.6607)
		(size 0.7112)
		(drill 0.4064)
		(layers "F.Cu" "B.Cu")
		(net "GND")
	)
	(via
		(at 117.855746 -279.9207)
		(size 0.7112)
		(drill 0.4064)
		(layers "F.Cu" "B.Cu")
		(net "GND")
	)
	(via
		(at 259.333746 -58.5597)
		(size 0.7112)
		(drill 0.4064)
		(layers "F.Cu" "B.Cu")
		(net "GND")
	)
	(via
		(at 248.0564 -446.3034)
		(size 0.7112)
		(drill 0.4064)
		(layers "F.Cu" "B.Cu")
		(net "GND")
	)
	(via
		(at 127.939546 -106.4895)
		(size 0.7112)
		(drill 0.4064)
		(layers "F.Cu" "B.Cu")
		(net "GND")
	)
	(via
		(at 93.979746 -55.6387)
		(size 0.7112)
		(drill 0.4064)
		(layers "F.Cu" "B.Cu")
		(net "GND")
	)
	(via
		(at 215.74125 -463.545428)
		(size 0.5588)
		(drill 0.3048)
		(layers "F.Cu" "B.Cu")
		(net "GND")
	)
	(via
		(at 250.951746 -495.0587)
		(size 0.7112)
		(drill 0.4064)
		(layers "F.Cu" "B.Cu")
		(net "GND")
	)
	(via
		(at 49.657 -436.118)
		(size 0.7112)
		(drill 0.4064)
		(layers "F.Cu" "B.Cu")
		(net "GND")
	)
	(via
		(at 259.079746 -255.5367)
		(size 0.7112)
		(drill 0.4064)
		(layers "F.Cu" "B.Cu")
		(net "GND")
	)
	(via
		(at 70.113906 -394.0302)
		(size 0.5588)
		(drill 0.3048)
		(layers "F.Cu" "B.Cu")
		(net "GND")
	)
	(via
		(at 84.226146 -261.3025)
		(size 0.7112)
		(drill 0.4064)
		(layers "F.Cu" "B.Cu")
		(net "GND")
	)
	(via
		(at 160.908746 -190.5381)
		(size 0.7112)
		(drill 0.4064)
		(layers "F.Cu" "B.Cu")
		(net "GND")
	)
	(via
		(at 180.974746 -1.5367)
		(size 0.7112)
		(drill 0.4064)
		(layers "F.Cu" "B.Cu")
		(net "GND")
	)
	(via
		(at 61.950346 -234.6071)
		(size 0.7112)
		(drill 0.4064)
		(layers "F.Cu" "B.Cu")
		(net "GND")
	)
	(via
		(at 152.780746 -234.3277)
		(size 0.7112)
		(drill 0.4064)
		(layers "F.Cu" "B.Cu")
		(net "GND")
	)
	(via
		(at 7.873746 -165.2397)
		(size 0.5588)
		(drill 0.3048)
		(layers "F.Cu" "B.Cu")
		(net "GND")
	)
	(via
		(at 217.169746 -117.9957)
		(size 0.7112)
		(drill 0.4064)
		(layers "F.Cu" "B.Cu")
		(net "GND")
	)
	(via
		(at 184.149746 -209.1309)
		(size 0.7112)
		(drill 0.4064)
		(layers "F.Cu" "B.Cu")
		(net "GND")
	)
	(via
		(at 78.866746 -55.0037)
		(size 0.7112)
		(drill 0.4064)
		(layers "F.Cu" "B.Cu")
		(net "GND")
	)
	(via
		(at 216.534746 -317.3857)
		(size 0.7112)
		(drill 0.4064)
		(layers "F.Cu" "B.Cu")
		(net "GND")
	)
	(via
		(at 76.834746 -228.3587)
		(size 0.7112)
		(drill 0.4064)
		(layers "F.Cu" "B.Cu")
		(net "GND")
	)
	(via
		(at 122.808746 -270.4719)
		(size 0.7112)
		(drill 0.4064)
		(layers "F.Cu" "B.Cu")
		(net "GND")
	)
	(via
		(at 120.014746 -411.6197)
		(size 0.7112)
		(drill 0.4064)
		(layers "F.Cu" "B.Cu")
		(net "GND")
	)
	(via
		(at 199.135746 -278.5237)
		(size 0.7112)
		(drill 0.4064)
		(layers "F.Cu" "B.Cu")
		(net "GND")
	)
	(via
		(at 23.748746 -85.7123)
		(size 0.7112)
		(drill 0.4064)
		(layers "F.Cu" "B.Cu")
		(net "GND")
	)
	(via
		(at 175.386746 -158.2547)
		(size 0.7112)
		(drill 0.4064)
		(layers "F.Cu" "B.Cu")
		(net "GND")
	)
	(via
		(at 111.124746 -73.5457)
		(size 0.7112)
		(drill 0.4064)
		(layers "F.Cu" "B.Cu")
		(net "GND")
	)
	(via
		(at 236.854746 -52.3367)
		(size 0.7112)
		(drill 0.4064)
		(layers "F.Cu" "B.Cu")
		(net "GND")
	)
	(via
		(at 138.709146 -372.7577)
		(size 0.7112)
		(drill 0.4064)
		(layers "F.Cu" "B.Cu")
		(net "GND")
	)
	(via
		(at 205.790546 -317.0809)
		(size 0.7112)
		(drill 0.4064)
		(layers "F.Cu" "B.Cu")
		(net "GND")
	)
	(via
		(at 129.539746 -97.1677)
		(size 0.7112)
		(drill 0.4064)
		(layers "F.Cu" "B.Cu")
		(net "GND")
	)
	(via
		(at 215.265 -62.6364)
		(size 0.5588)
		(drill 0.3048)
		(layers "F.Cu" "B.Cu")
		(net "GND")
	)
	(via
		(at 118.363746 -407.2763)
		(size 0.7112)
		(drill 0.4064)
		(layers "F.Cu" "B.Cu")
		(net "GND")
	)
	(via
		(at 74.675746 -156.4767)
		(size 0.7112)
		(drill 0.4064)
		(layers "F.Cu" "B.Cu")
		(net "GND")
	)
	(via
		(at 196.0372 -174.3964)
		(size 0.7112)
		(drill 0.4064)
		(layers "F.Cu" "B.Cu")
		(net "GND")
	)
	(via
		(at 23.621746 -220.6117)
		(size 0.5588)
		(drill 0.3048)
		(layers "F.Cu" "B.Cu")
		(net "GND")
	)
	(via
		(at 95.630746 -321.1957)
		(size 0.7112)
		(drill 0.4064)
		(layers "F.Cu" "B.Cu")
		(net "GND")
	)
	(via
		(at 69.341746 -308.3941)
		(size 0.7112)
		(drill 0.4064)
		(layers "F.Cu" "B.Cu")
		(net "GND")
	)
	(via
		(at 116.890546 -414.7439)
		(size 0.7112)
		(drill 0.4064)
		(layers "F.Cu" "B.Cu")
		(net "GND")
	)
	(via
		(at 137.667746 -27.4447)
		(size 0.7112)
		(drill 0.4064)
		(layers "F.Cu" "B.Cu")
		(net "GND")
	)
	(via
		(at 148.081746 -371.1575)
		(size 0.7112)
		(drill 0.4064)
		(layers "F.Cu" "B.Cu")
		(net "GND")
	)
	(via
		(at 238.302546 -486.9561)
		(size 0.7112)
		(drill 0.4064)
		(layers "F.Cu" "B.Cu")
		(net "GND")
	)
	(via
		(at 186.892946 -389.5471)
		(size 0.7112)
		(drill 0.4064)
		(layers "F.Cu" "B.Cu")
		(net "GND")
	)
	(via
		(at 222.3262 -165.227)
		(size 0.5588)
		(drill 0.3048)
		(layers "F.Cu" "B.Cu")
		(net "GND")
	)
	(via
		(at 136.016746 -138.4427)
		(size 0.7112)
		(drill 0.4064)
		(layers "F.Cu" "B.Cu")
		(net "GND")
	)
	(via
		(at 40.39997 -271.8816)
		(size 0.7112)
		(drill 0.4064)
		(layers "F.Cu" "B.Cu")
		(net "GND")
	)
	(via
		(at 239.902746 -186.8297)
		(size 0.7112)
		(drill 0.4064)
		(layers "F.Cu" "B.Cu")
		(net "GND")
	)
	(via
		(at 153.110946 -479.3869)
		(size 0.7112)
		(drill 0.4064)
		(layers "F.Cu" "B.Cu")
		(net "GND")
	)
	(via
		(at 226.694746 -318.1477)
		(size 0.7112)
		(drill 0.4064)
		(layers "F.Cu" "B.Cu")
		(net "GND")
	)
	(via
		(at 209.677 -350.266)
		(size 0.7112)
		(drill 0.4064)
		(layers "F.Cu" "B.Cu")
		(net "GND")
	)
	(via
		(at 227.202746 -361.5817)
		(size 0.7112)
		(drill 0.4064)
		(layers "F.Cu" "B.Cu")
		(net "GND")
	)
	(via
		(at 95.630746 -314.0837)
		(size 0.7112)
		(drill 0.4064)
		(layers "F.Cu" "B.Cu")
		(net "GND")
	)
	(via
		(at 2.285746 -264.4267)
		(size 0.7112)
		(drill 0.4064)
		(layers "F.Cu" "B.Cu")
		(net "GND")
	)
	(via
		(at 203.453746 -234.8357)
		(size 0.7112)
		(drill 0.4064)
		(layers "F.Cu" "B.Cu")
		(net "GND")
	)
	(via
		(at 133.603746 -320.8147)
		(size 0.7112)
		(drill 0.4064)
		(layers "F.Cu" "B.Cu")
		(net "GND")
	)
	(via
		(at 138.963146 -305.4985)
		(size 0.7112)
		(drill 0.4064)
		(layers "F.Cu" "B.Cu")
		(net "GND")
	)
	(via
		(at 177.164746 -297.8277)
		(size 0.7112)
		(drill 0.4064)
		(layers "F.Cu" "B.Cu")
		(net "GND")
	)
	(via
		(at 102.996746 -487.8197)
		(size 0.7112)
		(drill 0.4064)
		(layers "F.Cu" "B.Cu")
		(net "GND")
	)
	(via
		(at 129.184146 -348.1197)
		(size 0.7112)
		(drill 0.4064)
		(layers "F.Cu" "B.Cu")
		(net "GND")
	)
	(via
		(at 259.079746 -264.9347)
		(size 0.7112)
		(drill 0.4064)
		(layers "F.Cu" "B.Cu")
		(net "GND")
	)
	(via
		(at 109.8296 -426.7454)
		(size 0.7112)
		(drill 0.4064)
		(layers "F.Cu" "B.Cu")
		(net "GND")
	)
	(via
		(at 88.645746 -477.2787)
		(size 0.7112)
		(drill 0.4064)
		(layers "F.Cu" "B.Cu")
		(net "GND")
	)
	(via
		(at 176.529746 -352.5647)
		(size 0.7112)
		(drill 0.4064)
		(layers "F.Cu" "B.Cu")
		(net "GND")
	)
	(via
		(at 235.854494 -23.236174)
		(size 0.5588)
		(drill 0.3048)
		(layers "F.Cu" "B.Cu")
		(net "GND")
	)
	(via
		(at 7.3406 -109.0168)
		(size 0.5588)
		(drill 0.3048)
		(layers "F.Cu" "B.Cu")
		(net "GND")
	)
	(via
		(at 60.197746 -390.0297)
		(size 0.7112)
		(drill 0.4064)
		(layers "F.Cu" "B.Cu")
		(net "GND")
	)
	(via
		(at 153.923746 -279.9207)
		(size 0.7112)
		(drill 0.4064)
		(layers "F.Cu" "B.Cu")
		(net "GND")
	)
	(via
		(at 85.369146 -106.0577)
		(size 0.7112)
		(drill 0.4064)
		(layers "F.Cu" "B.Cu")
		(net "GND")
	)
	(via
		(at 209.778346 -132.4483)
		(size 0.7112)
		(drill 0.4064)
		(layers "F.Cu" "B.Cu")
		(net "GND")
	)
	(via
		(at 6.02615 -166.997634)
		(size 0.5588)
		(drill 0.3048)
		(layers "F.Cu" "B.Cu")
		(net "GND")
	)
	(via
		(at 196.722746 -130.4417)
		(size 0.7112)
		(drill 0.4064)
		(layers "F.Cu" "B.Cu")
		(net "GND")
	)
	(via
		(at 19.59991 -337.14309)
		(size 0.7112)
		(drill 0.4064)
		(layers "F.Cu" "B.Cu")
		(net "GND")
	)
	(via
		(at 158.622746 -41.1607)
		(size 0.7112)
		(drill 0.4064)
		(layers "F.Cu" "B.Cu")
		(net "GND")
	)
	(via
		(at 6.222746 -352.974402)
		(size 0.5588)
		(drill 0.3048)
		(layers "F.Cu" "B.Cu")
		(net "GND")
	)
	(via
		(at 131.927346 -476.6945)
		(size 0.7112)
		(drill 0.4064)
		(layers "F.Cu" "B.Cu")
		(net "GND")
	)
	(via
		(at 33.019746 -443.7507)
		(size 0.7112)
		(drill 0.4064)
		(layers "F.Cu" "B.Cu")
		(net "GND")
	)
	(via
		(at 210.692746 -315.6077)
		(size 0.7112)
		(drill 0.4064)
		(layers "F.Cu" "B.Cu")
		(net "GND")
	)
	(via
		(at 57.4802 -367.7412)
		(size 0.7112)
		(drill 0.4064)
		(layers "F.Cu" "B.Cu")
		(net "GND")
	)
	(via
		(at 25.653746 -312.682128)
		(size 0.7112)
		(drill 0.4064)
		(layers "F.Cu" "B.Cu")
		(net "GND")
	)
	(via
		(at 120.167146 -290.7157)
		(size 0.7112)
		(drill 0.4064)
		(layers "F.Cu" "B.Cu")
		(net "GND")
	)
	(via
		(at 104.342946 -109.5121)
		(size 0.7112)
		(drill 0.4064)
		(layers "F.Cu" "B.Cu")
		(net "GND")
	)
	(via
		(at 16.128746 -135.3947)
		(size 0.5588)
		(drill 0.3048)
		(layers "F.Cu" "B.Cu")
		(net "GND")
	)
	(via
		(at 114.833146 -198.4883)
		(size 0.7112)
		(drill 0.4064)
		(layers "F.Cu" "B.Cu")
		(net "GND")
	)
	(via
		(at 255.853946 -109.8423)
		(size 0.7112)
		(drill 0.4064)
		(layers "F.Cu" "B.Cu")
		(net "GND")
	)
	(via
		(at 5.968746 -420.8907)
		(size 0.5588)
		(drill 0.3048)
		(layers "F.Cu" "B.Cu")
		(net "GND")
	)
	(via
		(at 71.399146 -330.9239)
		(size 0.7112)
		(drill 0.4064)
		(layers "F.Cu" "B.Cu")
		(net "GND")
	)
	(via
		(at 149.478746 -11.8237)
		(size 0.7112)
		(drill 0.4064)
		(layers "F.Cu" "B.Cu")
		(net "GND")
	)
	(via
		(at 27.178 -1.524)
		(size 0.7112)
		(drill 0.4064)
		(layers "F.Cu" "B.Cu")
		(net "GND")
	)
	(via
		(at 73.100946 -201.8919)
		(size 0.7112)
		(drill 0.4064)
		(layers "F.Cu" "B.Cu")
		(net "GND")
	)
	(via
		(at 172.338746 -174.8917)
		(size 0.7112)
		(drill 0.4064)
		(layers "F.Cu" "B.Cu")
		(net "GND")
	)
	(via
		(at 199.770746 -55.6387)
		(size 0.7112)
		(drill 0.4064)
		(layers "F.Cu" "B.Cu")
		(net "GND")
	)
	(via
		(at 54.244748 -489.232702)
		(size 0.5588)
		(drill 0.3048)
		(layers "F.Cu" "B.Cu")
		(net "GND")
	)
	(via
		(at 171.805346 -482.8921)
		(size 0.7112)
		(drill 0.4064)
		(layers "F.Cu" "B.Cu")
		(net "GND")
	)
	(via
		(at 209.930746 -408.6987)
		(size 0.7112)
		(drill 0.4064)
		(layers "F.Cu" "B.Cu")
		(net "GND")
	)
	(via
		(at 45.6692 -316.0014)
		(size 0.7112)
		(drill 0.4064)
		(layers "F.Cu" "B.Cu")
		(net "GND")
	)
	(via
		(at 247.0912 -401.1168)
		(size 0.7112)
		(drill 0.4064)
		(layers "F.Cu" "B.Cu")
		(net "GND")
	)
	(via
		(at 112.140746 -355.4857)
		(size 0.7112)
		(drill 0.4064)
		(layers "F.Cu" "B.Cu")
		(net "GND")
	)
	(via
		(at 59.5122 -349.4278)
		(size 0.7112)
		(drill 0.4064)
		(layers "F.Cu" "B.Cu")
		(net "GND")
	)
	(via
		(at 191.871346 -326.6821)
		(size 0.7112)
		(drill 0.4064)
		(layers "F.Cu" "B.Cu")
		(net "GND")
	)
	(via
		(at 110.311946 -483.6287)
		(size 0.7112)
		(drill 0.4064)
		(layers "F.Cu" "B.Cu")
		(net "GND")
	)
	(via
		(at 233.654346 -230.2129)
		(size 0.7112)
		(drill 0.4064)
		(layers "F.Cu" "B.Cu")
		(net "GND")
	)
	(via
		(at 156.590746 -488.2007)
		(size 0.7112)
		(drill 0.4064)
		(layers "F.Cu" "B.Cu")
		(net "GND")
	)
	(via
		(at 23.489666 -436.416704)
		(size 0.5588)
		(drill 0.3048)
		(layers "F.Cu" "B.Cu")
		(net "GND")
	)
	(via
		(at 22.0726 -249.3264)
		(size 0.7112)
		(drill 0.4064)
		(layers "F.Cu" "B.Cu")
		(net "GND")
	)
	(via
		(at 45.872146 -361.7087)
		(size 0.7112)
		(drill 0.4064)
		(layers "F.Cu" "B.Cu")
		(net "GND")
	)
	(via
		(at 196.697346 -13.7287)
		(size 0.7112)
		(drill 0.4064)
		(layers "F.Cu" "B.Cu")
		(net "GND")
	)
	(via
		(at 45.2628 -353.9236)
		(size 0.7112)
		(drill 0.4064)
		(layers "F.Cu" "B.Cu")
		(net "GND")
	)
	(via
		(at 18.7706 -1.5748)
		(size 0.7112)
		(drill 0.4064)
		(layers "F.Cu" "B.Cu")
		(net "GND")
	)
	(via
		(at 237.489746 -151.1427)
		(size 0.7112)
		(drill 0.4064)
		(layers "F.Cu" "B.Cu")
		(net "GND")
	)
	(via
		(at 226.313746 -343.9287)
		(size 0.7112)
		(drill 0.4064)
		(layers "F.Cu" "B.Cu")
		(net "GND")
	)
	(via
		(at 58.635646 -184.4167)
		(size 0.5588)
		(drill 0.3048)
		(layers "F.Cu" "B.Cu")
		(net "GND")
	)
	(via
		(at 259.842 -501.142)
		(size 0.7112)
		(drill 0.4064)
		(layers "F.Cu" "B.Cu")
		(net "GND")
	)
	(via
		(at 106.044746 -20.0787)
		(size 0.7112)
		(drill 0.4064)
		(layers "F.Cu" "B.Cu")
		(net "GND")
	)
	(via
		(at 185.343546 -162.6489)
		(size 0.7112)
		(drill 0.4064)
		(layers "F.Cu" "B.Cu")
		(net "GND")
	)
	(via
		(at 210.311746 -455.0537)
		(size 0.7112)
		(drill 0.4064)
		(layers "F.Cu" "B.Cu")
		(net "GND")
	)
	(via
		(at 210.362546 -322.0339)
		(size 0.7112)
		(drill 0.4064)
		(layers "F.Cu" "B.Cu")
		(net "GND")
	)
	(via
		(at 67.868546 -237.5789)
		(size 0.7112)
		(drill 0.4064)
		(layers "F.Cu" "B.Cu")
		(net "GND")
	)
	(via
		(at 142.646146 -492.7473)
		(size 0.7112)
		(drill 0.4064)
		(layers "F.Cu" "B.Cu")
		(net "GND")
	)
	(via
		(at 83.032346 -484.4415)
		(size 0.7112)
		(drill 0.4064)
		(layers "F.Cu" "B.Cu")
		(net "GND")
	)
	(via
		(at 229.437946 -460.9465)
		(size 0.7112)
		(drill 0.4064)
		(layers "F.Cu" "B.Cu")
		(net "GND")
	)
	(via
		(at 12.0396 -437.3118)
		(size 0.5588)
		(drill 0.3048)
		(layers "F.Cu" "B.Cu")
		(net "GND")
	)
	(via
		(at 197.611746 -75.1967)
		(size 0.5588)
		(drill 0.3048)
		(layers "F.Cu" "B.Cu")
		(net "GND")
	)
	(via
		(at 205.561946 -471.5129)
		(size 0.7112)
		(drill 0.4064)
		(layers "F.Cu" "B.Cu")
		(net "GND")
	)
	(via
		(at 27.305 -340.487)
		(size 0.5588)
		(drill 0.3048)
		(layers "F.Cu" "B.Cu")
		(net "GND")
	)
	(via
		(at 210.311746 -254.8001)
		(size 0.7112)
		(drill 0.4064)
		(layers "F.Cu" "B.Cu")
		(net "GND")
	)
	(via
		(at 205.307946 -298.6659)
		(size 0.7112)
		(drill 0.4064)
		(layers "F.Cu" "B.Cu")
		(net "GND")
	)
	(via
		(at 100.304346 -90.8685)
		(size 0.7112)
		(drill 0.4064)
		(layers "F.Cu" "B.Cu")
		(net "GND")
	)
	(via
		(at 221.522544 -69.576696)
		(size 0.5588)
		(drill 0.3048)
		(layers "F.Cu" "B.Cu")
		(net "GND")
	)
	(via
		(at 181.152546 -124.3203)
		(size 0.7112)
		(drill 0.4064)
		(layers "F.Cu" "B.Cu")
		(net "GND")
	)
	(via
		(at 238.048546 -474.9673)
		(size 0.7112)
		(drill 0.4064)
		(layers "F.Cu" "B.Cu")
		(net "GND")
	)
	(via
		(at 67.309746 -218.0463)
		(size 0.7112)
		(drill 0.4064)
		(layers "F.Cu" "B.Cu")
		(net "GND")
	)
	(via
		(at 217.042746 -98.4377)
		(size 0.7112)
		(drill 0.4064)
		(layers "F.Cu" "B.Cu")
		(net "GND")
	)
	(via
		(at 245.414546 -125.0569)
		(size 0.7112)
		(drill 0.4064)
		(layers "F.Cu" "B.Cu")
		(net "GND")
	)
	(via
		(at 35.51301 -369.427252)
		(size 0.5588)
		(drill 0.3048)
		(layers "F.Cu" "B.Cu")
		(net "GND")
	)
	(via
		(at 77.723746 -35.8267)
		(size 0.7112)
		(drill 0.3556)
		(layers "F.Cu" "B.Cu")
		(net "GND")
	)
	(via
		(at 94.868746 -360.9467)
		(size 0.7112)
		(drill 0.4064)
		(layers "F.Cu" "B.Cu")
		(net "GND")
	)
	(via
		(at 227.913946 -300.3423)
		(size 0.7112)
		(drill 0.4064)
		(layers "F.Cu" "B.Cu")
		(net "GND")
	)
	(via
		(at 75.793346 -178.6763)
		(size 0.7112)
		(drill 0.4064)
		(layers "F.Cu" "B.Cu")
		(net "GND")
	)
	(via
		(at 163.601146 -110.8583)
		(size 0.7112)
		(drill 0.4064)
		(layers "F.Cu" "B.Cu")
		(net "GND")
	)
	(via
		(at 128.142746 -147.4597)
		(size 0.7112)
		(drill 0.4064)
		(layers "F.Cu" "B.Cu")
		(net "GND")
	)
	(via
		(at 144.271746 -393.6873)
		(size 0.7112)
		(drill 0.4064)
		(layers "F.Cu" "B.Cu")
		(net "GND")
	)
	(via
		(at 62.992 -376.428)
		(size 0.7112)
		(drill 0.4064)
		(layers "F.Cu" "B.Cu")
		(net "GND")
	)
	(via
		(at 203.326746 -244.6147)
		(size 0.7112)
		(drill 0.4064)
		(layers "F.Cu" "B.Cu")
		(net "GND")
	)
	(via
		(at 249.681746 -51.7017)
		(size 0.7112)
		(drill 0.4064)
		(layers "F.Cu" "B.Cu")
		(net "GND")
	)
	(via
		(at 126.999746 -471.1573)
		(size 0.7112)
		(drill 0.4064)
		(layers "F.Cu" "B.Cu")
		(net "GND")
	)
	(via
		(at 92.201746 -48.2727)
		(size 0.7112)
		(drill 0.4064)
		(layers "F.Cu" "B.Cu")
		(net "GND")
	)
	(via
		(at 175.767746 -421.7797)
		(size 0.7112)
		(drill 0.4064)
		(layers "F.Cu" "B.Cu")
		(net "GND")
	)
	(via
		(at 95.9358 -413.766)
		(size 0.7112)
		(drill 0.4064)
		(layers "F.Cu" "B.Cu")
		(net "GND")
	)
	(via
		(at 176.428146 -193.9163)
		(size 0.7112)
		(drill 0.4064)
		(layers "F.Cu" "B.Cu")
		(net "GND")
	)
	(via
		(at 193.903346 -355.9683)
		(size 0.7112)
		(drill 0.4064)
		(layers "F.Cu" "B.Cu")
		(net "GND")
	)
	(via
		(at 76.199746 -267.2969)
		(size 0.7112)
		(drill 0.4064)
		(layers "F.Cu" "B.Cu")
		(net "GND")
	)
	(via
		(at 127.126746 -20.2057)
		(size 0.7112)
		(drill 0.4064)
		(layers "F.Cu" "B.Cu")
		(net "GND")
	)
	(via
		(at 236.981746 -123.3297)
		(size 0.7112)
		(drill 0.4064)
		(layers "F.Cu" "B.Cu")
		(net "GND")
	)
	(via
		(at 96.672146 -96.7867)
		(size 0.7112)
		(drill 0.4064)
		(layers "F.Cu" "B.Cu")
		(net "GND")
	)
	(via
		(at 152.145746 -267.3477)
		(size 0.7112)
		(drill 0.4064)
		(layers "F.Cu" "B.Cu")
		(net "GND")
	)
	(via
		(at 19.329146 -105.2195)
		(size 0.7112)
		(drill 0.4064)
		(layers "F.Cu" "B.Cu")
		(net "GND")
	)
	(via
		(at 230.377746 -61.7601)
		(size 0.7112)
		(drill 0.4064)
		(layers "F.Cu" "B.Cu")
		(net "GND")
	)
	(via
		(at 128.752346 -228.8413)
		(size 0.7112)
		(drill 0.4064)
		(layers "F.Cu" "B.Cu")
		(net "GND")
	)
	(via
		(at 120.471946 -392.3665)
		(size 0.7112)
		(drill 0.4064)
		(layers "F.Cu" "B.Cu")
		(net "GND")
	)
	(via
		(at 41.147746 -215.4047)
		(size 0.7112)
		(drill 0.4064)
		(layers "F.Cu" "B.Cu")
		(net "GND")
	)
	(via
		(at 64.515746 -267.2207)
		(size 0.7112)
		(drill 0.4064)
		(layers "F.Cu" "B.Cu")
		(net "GND")
	)
	(via
		(at 4.445 -292.227)
		(size 0.7112)
		(drill 0.4064)
		(layers "F.Cu" "B.Cu")
		(net "GND")
	)
	(via
		(at 165.810946 -20.4851)
		(size 0.7112)
		(drill 0.4064)
		(layers "F.Cu" "B.Cu")
		(net "GND")
	)
	(via
		(at 108.152946 -367.7793)
		(size 0.7112)
		(drill 0.4064)
		(layers "F.Cu" "B.Cu")
		(net "GND")
	)
	(via
		(at 214.502746 -454.1647)
		(size 0.7112)
		(drill 0.4064)
		(layers "F.Cu" "B.Cu")
		(net "GND")
	)
	(via
		(at 196.468746 -279.6667)
		(size 0.7112)
		(drill 0.4064)
		(layers "F.Cu" "B.Cu")
		(net "GND")
	)
	(via
		(at 86.080346 -110.1979)
		(size 0.7112)
		(drill 0.4064)
		(layers "F.Cu" "B.Cu")
		(net "GND")
	)
	(via
		(at 6.80339 -417.090606)
		(size 0.5588)
		(drill 0.3048)
		(layers "F.Cu" "B.Cu")
		(net "GND")
	)
	(via
		(at 215.011 -37.973)
		(size 0.5588)
		(drill 0.3048)
		(layers "F.Cu" "B.Cu")
		(net "GND")
	)
	(via
		(at 75.666346 -339.3821)
		(size 0.7112)
		(drill 0.4064)
		(layers "F.Cu" "B.Cu")
		(net "GND")
	)
	(via
		(at 33.045146 -82.8421)
		(size 0.7112)
		(drill 0.4064)
		(layers "F.Cu" "B.Cu")
		(net "GND")
	)
	(via
		(at 77.7494 -32.131)
		(size 0.7112)
		(drill 0.4064)
		(layers "F.Cu" "B.Cu")
		(net "GND")
	)
	(via
		(at 49.657 -343.535)
		(size 0.7112)
		(drill 0.4064)
		(layers "F.Cu" "B.Cu")
		(net "GND")
	)
	(via
		(at 225.2726 -407.4414)
		(size 0.7112)
		(drill 0.4064)
		(layers "F.Cu" "B.Cu")
		(net "GND")
	)
	(via
		(at 255.345946 -77.5843)
		(size 0.7112)
		(drill 0.4064)
		(layers "F.Cu" "B.Cu")
		(net "GND")
	)
	(via
		(at 46.227746 -162.9537)
		(size 0.7112)
		(drill 0.4064)
		(layers "F.Cu" "B.Cu")
		(net "GND")
	)
	(via
		(at 48.7934 -460.629)
		(size 0.7112)
		(drill 0.4064)
		(layers "F.Cu" "B.Cu")
		(net "GND")
	)
	(via
		(at 125.501146 -258.4069)
		(size 0.7112)
		(drill 0.4064)
		(layers "F.Cu" "B.Cu")
		(net "GND")
	)
	(via
		(at 110.362746 -345.5035)
		(size 0.7112)
		(drill 0.4064)
		(layers "F.Cu" "B.Cu")
		(net "GND")
	)
	(via
		(at 117.728746 -7.5057)
		(size 0.7112)
		(drill 0.3556)
		(layers "F.Cu" "B.Cu")
		(net "GND")
	)
	(via
		(at 249.808746 -89.6747)
		(size 0.7112)
		(drill 0.4064)
		(layers "F.Cu" "B.Cu")
		(net "GND")
	)
	(via
		(at 239.521746 -218.4527)
		(size 0.7112)
		(drill 0.4064)
		(layers "F.Cu" "B.Cu")
		(net "GND")
	)
	(via
		(at 245.820946 -154.0129)
		(size 0.7112)
		(drill 0.4064)
		(layers "F.Cu" "B.Cu")
		(net "GND")
	)
	(via
		(at 51.9176 -428.8028)
		(size 0.7112)
		(drill 0.4064)
		(layers "F.Cu" "B.Cu")
		(net "GND")
	)
	(via
		(at 50.418746 -224.564702)
		(size 0.7112)
		(drill 0.4064)
		(layers "F.Cu" "B.Cu")
		(net "GND")
	)
	(via
		(at 94.868746 -363.2327)
		(size 0.7112)
		(drill 0.4064)
		(layers "F.Cu" "B.Cu")
		(net "GND")
	)
	(via
		(at 84.708746 -122.6947)
		(size 0.7112)
		(drill 0.4064)
		(layers "F.Cu" "B.Cu")
		(net "GND")
	)
	(via
		(at 111.505746 -96.9137)
		(size 0.7112)
		(drill 0.4064)
		(layers "F.Cu" "B.Cu")
		(net "GND")
	)
	(via
		(at 35.052 -345.19235)
		(size 0.5588)
		(drill 0.3048)
		(layers "F.Cu" "B.Cu")
		(net "GND")
	)
	(via
		(at 180.721 -461.6958)
		(size 0.7112)
		(drill 0.4064)
		(layers "F.Cu" "B.Cu")
		(net "GND")
	)
	(via
		(at 219.455746 -79.6417)
		(size 0.7112)
		(drill 0.4064)
		(layers "F.Cu" "B.Cu")
		(net "GND")
	)
	(via
		(at 186.689746 -269.8877)
		(size 0.7112)
		(drill 0.4064)
		(layers "F.Cu" "B.Cu")
		(net "GND")
	)
	(via
		(at 253.771146 -308.4703)
		(size 0.7112)
		(drill 0.4064)
		(layers "F.Cu" "B.Cu")
		(net "GND")
	)
	(via
		(at 131.825746 -129.1717)
		(size 0.7112)
		(drill 0.4064)
		(layers "F.Cu" "B.Cu")
		(net "GND")
	)
	(via
		(at 159.257746 -504.7107)
		(size 0.7112)
		(drill 0.4064)
		(layers "F.Cu" "B.Cu")
		(net "GND")
	)
	(via
		(at 55.371746 -63.6397)
		(size 0.7112)
		(drill 0.4064)
		(layers "F.Cu" "B.Cu")
		(net "GND")
	)
	(via
		(at 30.733746 -301.7647)
		(size 0.7112)
		(drill 0.4064)
		(layers "F.Cu" "B.Cu")
		(net "GND")
	)
	(via
		(at 214.375746 -386.9817)
		(size 0.7112)
		(drill 0.4064)
		(layers "F.Cu" "B.Cu")
		(net "GND")
	)
	(via
		(at 198.246746 -381.0127)
		(size 0.7112)
		(drill 0.4064)
		(layers "F.Cu" "B.Cu")
		(net "GND")
	)
	(via
		(at 53.502052 -15.991586)
		(size 0.5588)
		(drill 0.3048)
		(layers "F.Cu" "B.Cu")
		(net "GND")
	)
	(via
		(at 62.7634 -12.1666)
		(size 0.7112)
		(drill 0.4064)
		(layers "F.Cu" "B.Cu")
		(net "GND")
	)
	(via
		(at 259.714746 -457.7207)
		(size 0.7112)
		(drill 0.4064)
		(layers "F.Cu" "B.Cu")
		(net "GND")
	)
	(via
		(at 42.900346 -498.0305)
		(size 0.7112)
		(drill 0.4064)
		(layers "F.Cu" "B.Cu")
		(net "GND")
	)
	(via
		(at 95.529146 -399.5039)
		(size 0.7112)
		(drill 0.4064)
		(layers "F.Cu" "B.Cu")
		(net "GND")
	)
	(via
		(at 208.101946 -100.1395)
		(size 0.7112)
		(drill 0.4064)
		(layers "F.Cu" "B.Cu")
		(net "GND")
	)
	(via
		(at 40.399716 -471.1827)
		(size 0.7112)
		(drill 0.4064)
		(layers "F.Cu" "B.Cu")
		(net "GND")
	)
	(via
		(at 245.5164 -391.4648)
		(size 0.7112)
		(drill 0.4064)
		(layers "F.Cu" "B.Cu")
		(net "GND")
	)
	(via
		(at 224.662746 -198.5137)
		(size 0.7112)
		(drill 0.4064)
		(layers "F.Cu" "B.Cu")
		(net "GND")
	)
	(via
		(at 179.679346 -233.3117)
		(size 0.7112)
		(drill 0.4064)
		(layers "F.Cu" "B.Cu")
		(net "GND")
	)
	(via
		(at 84.327746 -140.9827)
		(size 0.7112)
		(drill 0.4064)
		(layers "F.Cu" "B.Cu")
		(net "GND")
	)
	(via
		(at 248.030746 -346.0877)
		(size 0.7112)
		(drill 0.4064)
		(layers "F.Cu" "B.Cu")
		(net "GND")
	)
	(via
		(at 26.7462 -243.9162)
		(size 0.7112)
		(drill 0.4064)
		(layers "F.Cu" "B.Cu")
		(net "GND")
	)
	(via
		(at 23.113746 -412.6357)
		(size 0.7112)
		(drill 0.4064)
		(layers "F.Cu" "B.Cu")
		(net "GND")
	)
	(via
		(at 64.693546 -205.1431)
		(size 0.7112)
		(drill 0.4064)
		(layers "F.Cu" "B.Cu")
		(net "GND")
	)
	(via
		(at 157.606746 -154.6987)
		(size 0.7112)
		(drill 0.4064)
		(layers "F.Cu" "B.Cu")
		(net "GND")
	)
	(via
		(at 42.0624 -268.586712)
		(size 0.7112)
		(drill 0.4064)
		(layers "F.Cu" "B.Cu")
		(net "GND")
	)
	(via
		(at 19.938746 -166.1287)
		(size 0.5588)
		(drill 0.3048)
		(layers "F.Cu" "B.Cu")
		(net "GND")
	)
	(via
		(at 74.0156 -396.621)
		(size 0.5588)
		(drill 0.3048)
		(layers "F.Cu" "B.Cu")
		(net "GND")
	)
	(via
		(at 91.287346 -146.3167)
		(size 0.7112)
		(drill 0.4064)
		(layers "F.Cu" "B.Cu")
		(net "GND")
	)
	(via
		(at 126.999746 -36.9697)
		(size 0.7112)
		(drill 0.4064)
		(layers "F.Cu" "B.Cu")
		(net "GND")
	)
	(via
		(at 72.923146 -254.0381)
		(size 0.7112)
		(drill 0.4064)
		(layers "F.Cu" "B.Cu")
		(net "GND")
	)
	(via
		(at 228.218746 -218.9607)
		(size 0.7112)
		(drill 0.4064)
		(layers "F.Cu" "B.Cu")
		(net "GND")
	)
	(via
		(at 127.558546 -397.8275)
		(size 0.7112)
		(drill 0.4064)
		(layers "F.Cu" "B.Cu")
		(net "GND")
	)
	(via
		(at 252.602746 -247.2817)
		(size 0.7112)
		(drill 0.4064)
		(layers "F.Cu" "B.Cu")
		(net "GND")
	)
	(via
		(at 171.576746 -10.6807)
		(size 0.7112)
		(drill 0.4064)
		(layers "F.Cu" "B.Cu")
		(net "GND")
	)
	(via
		(at 246.379746 -233.2355)
		(size 0.7112)
		(drill 0.4064)
		(layers "F.Cu" "B.Cu")
		(net "GND")
	)
	(via
		(at 58.927746 -113.1697)
		(size 0.7112)
		(drill 0.4064)
		(layers "F.Cu" "B.Cu")
		(net "GND")
	)
	(via
		(at 120.421146 -45.9867)
		(size 0.7112)
		(drill 0.4064)
		(layers "F.Cu" "B.Cu")
		(net "GND")
	)
	(via
		(at 236.972094 -21.737574)
		(size 0.5588)
		(drill 0.3048)
		(layers "F.Cu" "B.Cu")
		(net "GND")
	)
	(via
		(at 232.308146 -386.4991)
		(size 0.7112)
		(drill 0.4064)
		(layers "F.Cu" "B.Cu")
		(net "GND")
	)
	(via
		(at 245.5672 -394.5382)
		(size 0.7112)
		(drill 0.4064)
		(layers "F.Cu" "B.Cu")
		(net "GND")
	)
	(via
		(at 179.831746 -211.4677)
		(size 0.7112)
		(drill 0.4064)
		(layers "F.Cu" "B.Cu")
		(net "GND")
	)
	(via
		(at 218.490546 -133.3627)
		(size 0.7112)
		(drill 0.4064)
		(layers "F.Cu" "B.Cu")
		(net "GND")
	)
	(via
		(at 206.3877 -379.4887)
		(size 0.5588)
		(drill 0.3048)
		(layers "F.Cu" "B.Cu")
		(net "GND")
	)
	(via
		(at 38.734746 -371.58676)
		(size 0.5588)
		(drill 0.3048)
		(layers "F.Cu" "B.Cu")
		(net "GND")
	)
	(via
		(at 84.455 -386.0038)
		(size 0.7112)
		(drill 0.4064)
		(layers "F.Cu" "B.Cu")
		(net "GND")
	)
	(via
		(at 220.014546 -233.7689)
		(size 0.7112)
		(drill 0.4064)
		(layers "F.Cu" "B.Cu")
		(net "GND")
	)
	(via
		(at 191.160146 -235.5469)
		(size 0.7112)
		(drill 0.4064)
		(layers "F.Cu" "B.Cu")
		(net "GND")
	)
	(via
		(at 61.1886 -502.666)
		(size 0.7112)
		(drill 0.4064)
		(layers "F.Cu" "B.Cu")
		(net "GND")
	)
	(via
		(at 110.870746 -12.7889)
		(size 0.7112)
		(drill 0.4064)
		(layers "F.Cu" "B.Cu")
		(net "GND")
	)
	(via
		(at 226.567746 -37.0967)
		(size 0.7112)
		(drill 0.4064)
		(layers "F.Cu" "B.Cu")
		(net "GND")
	)
	(via
		(at 69.7738 -33.401)
		(size 0.7112)
		(drill 0.4064)
		(layers "F.Cu" "B.Cu")
		(net "GND")
	)
	(via
		(at 17.272 -120.8024)
		(size 0.5588)
		(drill 0.3048)
		(layers "F.Cu" "B.Cu")
		(net "GND")
	)
	(via
		(at 200.786746 -485.9147)
		(size 0.7112)
		(drill 0.4064)
		(layers "F.Cu" "B.Cu")
		(net "GND")
	)
	(via
		(at 252.983746 -1.5367)
		(size 0.7112)
		(drill 0.4064)
		(layers "F.Cu" "B.Cu")
		(net "GND")
	)
	(via
		(at 24.430736 -38.37051)
		(size 0.7112)
		(drill 0.4064)
		(layers "F.Cu" "B.Cu")
		(net "GND")
	)
	(via
		(at 19.59991 -28.142946)
		(size 0.7112)
		(drill 0.4064)
		(layers "F.Cu" "B.Cu")
		(net "GND")
	)
	(via
		(at 232.790746 -29.2227)
		(size 0.5588)
		(drill 0.3048)
		(layers "F.Cu" "B.Cu")
		(net "GND")
	)
	(via
		(at 61.264546 -474.2561)
		(size 0.7112)
		(drill 0.4064)
		(layers "F.Cu" "B.Cu")
		(net "GND")
	)
	(via
		(at 234.200446 -248.55805)
		(size 0.5588)
		(drill 0.3048)
		(layers "F.Cu" "B.Cu")
		(net "GND")
	)
	(via
		(at 45.898054 -435.8767)
		(size 0.7112)
		(drill 0.4064)
		(layers "F.Cu" "B.Cu")
		(net "GND")
	)
	(via
		(at 98.196146 -88.5063)
		(size 0.7112)
		(drill 0.4064)
		(layers "F.Cu" "B.Cu")
		(net "GND")
	)
	(via
		(at 83.464146 -153.0223)
		(size 0.7112)
		(drill 0.4064)
		(layers "F.Cu" "B.Cu")
		(net "GND")
	)
	(via
		(at 13.334746 -36.8427)
		(size 0.7112)
		(drill 0.4064)
		(layers "F.Cu" "B.Cu")
		(net "GND")
	)
	(via
		(at 197.866 -378.0536)
		(size 0.7112)
		(drill 0.4064)
		(layers "F.Cu" "B.Cu")
		(net "GND")
	)
	(via
		(at 55.371746 -257.0607)
		(size 0.7112)
		(drill 0.4064)
		(layers "F.Cu" "B.Cu")
		(net "GND")
	)
	(via
		(at 87.121746 -42.9387)
		(size 0.7112)
		(drill 0.3556)
		(layers "F.Cu" "B.Cu")
		(net "GND")
	)
	(via
		(at 250.062746 -128.0287)
		(size 0.7112)
		(drill 0.4064)
		(layers "F.Cu" "B.Cu")
		(net "GND")
	)
	(via
		(at 183.895746 -198.9709)
		(size 0.7112)
		(drill 0.4064)
		(layers "F.Cu" "B.Cu")
		(net "GND")
	)
	(via
		(at 65.328546 -162.5727)
		(size 0.7112)
		(drill 0.4064)
		(layers "F.Cu" "B.Cu")
		(net "GND")
	)
	(via
		(at 40.399716 -374.9548)
		(size 0.7112)
		(drill 0.4064)
		(layers "F.Cu" "B.Cu")
		(net "GND")
	)
	(via
		(at 108.076746 -327.7997)
		(size 0.7112)
		(drill 0.4064)
		(layers "F.Cu" "B.Cu")
		(net "GND")
	)
	(via
		(at 5.943346 -98.978466)
		(size 0.5588)
		(drill 0.3048)
		(layers "F.Cu" "B.Cu")
		(net "GND")
	)
	(via
		(at 163.728146 -105.9053)
		(size 0.7112)
		(drill 0.4064)
		(layers "F.Cu" "B.Cu")
		(net "GND")
	)
	(via
		(at 82.105246 -190.24854)
		(size 0.5588)
		(drill 0.3048)
		(layers "F.Cu" "B.Cu")
		(net "GND")
	)
	(via
		(at 218.0336 -89.4842)
		(size 0.7112)
		(drill 0.4064)
		(layers "F.Cu" "B.Cu")
		(net "GND")
	)
	(via
		(at 59.181746 -500.6467)
		(size 0.7112)
		(drill 0.4064)
		(layers "F.Cu" "B.Cu")
		(net "GND")
	)
	(via
		(at 105.282746 -459.8543)
		(size 0.7112)
		(drill 0.4064)
		(layers "F.Cu" "B.Cu")
		(net "GND")
	)
	(via
		(at 51.104546 -67.7545)
		(size 0.7112)
		(drill 0.4064)
		(layers "F.Cu" "B.Cu")
		(net "GND")
	)
	(via
		(at 118.795546 -196.2785)
		(size 0.7112)
		(drill 0.4064)
		(layers "F.Cu" "B.Cu")
		(net "GND")
	)
	(via
		(at 199.628506 -494.4872)
		(size 0.5588)
		(drill 0.3048)
		(layers "F.Cu" "B.Cu")
		(net "GND")
	)
	(via
		(at 136.727946 -437.1467)
		(size 0.7112)
		(drill 0.4064)
		(layers "F.Cu" "B.Cu")
		(net "GND")
	)
	(via
		(at 246.506746 -223.4565)
		(size 0.7112)
		(drill 0.4064)
		(layers "F.Cu" "B.Cu")
		(net "GND")
	)
	(via
		(at 42.493946 -93.8149)
		(size 0.7112)
		(drill 0.4064)
		(layers "F.Cu" "B.Cu")
		(net "GND")
	)
	(via
		(at 186.562746 -397.1417)
		(size 0.7112)
		(drill 0.4064)
		(layers "F.Cu" "B.Cu")
		(net "GND")
	)
	(via
		(at 91.363546 -159.3977)
		(size 0.7112)
		(drill 0.4064)
		(layers "F.Cu" "B.Cu")
		(net "GND")
	)
	(via
		(at 210.184746 -41.5417)
		(size 0.5588)
		(drill 0.3048)
		(layers "F.Cu" "B.Cu")
		(net "GND")
	)
	(via
		(at 198.322946 -479.7679)
		(size 0.7112)
		(drill 0.4064)
		(layers "F.Cu" "B.Cu")
		(net "GND")
	)
	(via
		(at 78.866746 -1.2827)
		(size 0.7112)
		(drill 0.4064)
		(layers "F.Cu" "B.Cu")
		(net "GND")
	)
	(via
		(at 174.497746 -475.0435)
		(size 0.7112)
		(drill 0.4064)
		(layers "F.Cu" "B.Cu")
		(net "GND")
	)
	(via
		(at 190.753746 -250.5837)
		(size 0.7112)
		(drill 0.4064)
		(layers "F.Cu" "B.Cu")
		(net "GND")
	)
	(via
		(at 2.285746 -244.2337)
		(size 0.7112)
		(drill 0.4064)
		(layers "F.Cu" "B.Cu")
		(net "GND")
	)
	(via
		(at 103.250746 -480.8347)
		(size 0.7112)
		(drill 0.4064)
		(layers "F.Cu" "B.Cu")
		(net "GND")
	)
	(via
		(at 79.121 -504.825)
		(size 0.7112)
		(drill 0.4064)
		(layers "F.Cu" "B.Cu")
		(net "GND")
	)
	(via
		(at 239.775746 -204.7367)
		(size 0.7112)
		(drill 0.4064)
		(layers "F.Cu" "B.Cu")
		(net "GND")
	)
	(via
		(at 241.604546 -315.7855)
		(size 0.7112)
		(drill 0.4064)
		(layers "F.Cu" "B.Cu")
		(net "GND")
	)
	(via
		(at 228.2952 -24.384)
		(size 0.5588)
		(drill 0.3048)
		(layers "F.Cu" "B.Cu")
		(net "GND")
	)
	(via
		(at 212.978746 -89.4207)
		(size 0.7112)
		(drill 0.4064)
		(layers "F.Cu" "B.Cu")
		(net "GND")
	)
	(via
		(at 188.988446 -455.075036)
		(size 0.7112)
		(drill 0.4064)
		(layers "F.Cu" "B.Cu")
		(net "GND")
	)
	(via
		(at 137.667746 -31.8897)
		(size 0.7112)
		(drill 0.4064)
		(layers "F.Cu" "B.Cu")
		(net "GND")
	)
	(via
		(at 101.726746 -34.0487)
		(size 0.7112)
		(drill 0.4064)
		(layers "F.Cu" "B.Cu")
		(net "GND")
	)
	(via
		(at 149.351746 -6.3627)
		(size 0.7112)
		(drill 0.4064)
		(layers "F.Cu" "B.Cu")
		(net "GND")
	)
	(via
		(at 55.117746 -245.7577)
		(size 0.7112)
		(drill 0.4064)
		(layers "F.Cu" "B.Cu")
		(net "GND")
	)
	(via
		(at 75.590146 -131.9149)
		(size 0.7112)
		(drill 0.4064)
		(layers "F.Cu" "B.Cu")
		(net "GND")
	)
	(via
		(at 5.968746 -100.985066)
		(size 0.5588)
		(drill 0.3048)
		(layers "F.Cu" "B.Cu")
		(net "GND")
	)
	(via
		(at 72.770746 -346.4687)
		(size 0.7112)
		(drill 0.4064)
		(layers "F.Cu" "B.Cu")
		(net "GND")
	)
	(via
		(at 235.076746 -396.8877)
		(size 0.7112)
		(drill 0.4064)
		(layers "F.Cu" "B.Cu")
		(net "GND")
	)
	(via
		(at 147.980146 -441.9727)
		(size 0.7112)
		(drill 0.4064)
		(layers "F.Cu" "B.Cu")
		(net "GND")
	)
	(via
		(at 214.578946 -5.0419)
		(size 0.7112)
		(drill 0.4064)
		(layers "F.Cu" "B.Cu")
		(net "GND")
	)
	(via
		(at 52.1208 -433.832)
		(size 0.7112)
		(drill 0.4064)
		(layers "F.Cu" "B.Cu")
		(net "GND")
	)
	(via
		(at 245.668546 -130.3909)
		(size 0.7112)
		(drill 0.4064)
		(layers "F.Cu" "B.Cu")
		(net "GND")
	)
	(via
		(at 180.009546 -315.8617)
		(size 0.7112)
		(drill 0.4064)
		(layers "F.Cu" "B.Cu")
		(net "GND")
	)
	(via
		(at 18.03781 -31.411164)
		(size 0.7112)
		(drill 0.4064)
		(layers "F.Cu" "B.Cu")
		(net "GND")
	)
	(via
		(at 15.259304 -151.327358)
		(size 0.5588)
		(drill 0.3048)
		(layers "F.Cu" "B.Cu")
		(net "GND")
	)
	(via
		(at 65.404746 -134.6327)
		(size 0.7112)
		(drill 0.4064)
		(layers "F.Cu" "B.Cu")
		(net "GND")
	)
	(via
		(at 31.5214 -265.9634)
		(size 0.5588)
		(drill 0.3048)
		(layers "F.Cu" "B.Cu")
		(net "GND")
	)
	(via
		(at 38.978586 -108.583476)
		(size 0.5588)
		(drill 0.3048)
		(layers "F.Cu" "B.Cu")
		(net "GND")
	)
	(via
		(at 6.222746 -378.9807)
		(size 0.5588)
		(drill 0.3048)
		(layers "F.Cu" "B.Cu")
		(net "GND")
	)
	(via
		(at 77.977746 -14.0843)
		(size 0.7112)
		(drill 0.4064)
		(layers "F.Cu" "B.Cu")
		(net "GND")
	)
	(via
		(at 174.777146 -237.8329)
		(size 0.7112)
		(drill 0.4064)
		(layers "F.Cu" "B.Cu")
		(net "GND")
	)
	(via
		(at 191.516 -393.954)
		(size 0.5588)
		(drill 0.3048)
		(layers "F.Cu" "B.Cu")
		(net "GND")
	)
	(via
		(at 107.771946 -262.6487)
		(size 0.7112)
		(drill 0.4064)
		(layers "F.Cu" "B.Cu")
		(net "GND")
	)
	(via
		(at 30.733746 -312.0517)
		(size 0.7112)
		(drill 0.4064)
		(layers "F.Cu" "B.Cu")
		(net "GND")
	)
	(via
		(at 25.526746 -375.8311)
		(size 0.5588)
		(drill 0.3048)
		(layers "F.Cu" "B.Cu")
		(net "GND")
	)
	(via
		(at 216.535 -371.5004)
		(size 0.5588)
		(drill 0.3048)
		(layers "F.Cu" "B.Cu")
		(net "GND")
	)
	(via
		(at 203.199746 -344.9447)
		(size 0.7112)
		(drill 0.4064)
		(layers "F.Cu" "B.Cu")
		(net "GND")
	)
	(via
		(at 29.209746 -307.432202)
		(size 0.5588)
		(drill 0.3048)
		(layers "F.Cu" "B.Cu")
		(net "GND")
	)
	(via
		(at 4.393946 -196.5833)
		(size 0.7112)
		(drill 0.4064)
		(layers "F.Cu" "B.Cu")
		(net "GND")
	)
	(via
		(at 218.053412 -69.6087)
		(size 0.5588)
		(drill 0.3048)
		(layers "F.Cu" "B.Cu")
		(net "GND")
	)
	(via
		(at 119.760746 -125.4633)
		(size 0.7112)
		(drill 0.4064)
		(layers "F.Cu" "B.Cu")
		(net "GND")
	)
	(via
		(at 252.907546 -472.1733)
		(size 0.7112)
		(drill 0.4064)
		(layers "F.Cu" "B.Cu")
		(net "GND")
	)
	(via
		(at 200.659746 -152.9207)
		(size 0.7112)
		(drill 0.4064)
		(layers "F.Cu" "B.Cu")
		(net "GND")
	)
	(via
		(at 250.951746 -500.8753)
		(size 0.7112)
		(drill 0.4064)
		(layers "F.Cu" "B.Cu")
		(net "GND")
	)
	(via
		(at 26.669746 -312.6867)
		(size 0.7112)
		(drill 0.4064)
		(layers "F.Cu" "B.Cu")
		(net "GND")
	)
	(via
		(at 48.310546 -45.3771)
		(size 0.7112)
		(drill 0.4064)
		(layers "F.Cu" "B.Cu")
		(net "GND")
	)
	(via
		(at 123.646946 -239.0267)
		(size 0.7112)
		(drill 0.4064)
		(layers "F.Cu" "B.Cu")
		(net "GND")
	)
	(via
		(at 167.715946 -496.7097)
		(size 0.7112)
		(drill 0.4064)
		(layers "F.Cu" "B.Cu")
		(net "GND")
	)
	(via
		(at 202.564746 -12.3317)
		(size 0.7112)
		(drill 0.4064)
		(layers "F.Cu" "B.Cu")
		(net "GND")
	)
	(via
		(at 69.341746 -249.1867)
		(size 0.7112)
		(drill 0.4064)
		(layers "F.Cu" "B.Cu")
		(net "GND")
	)
	(via
		(at 234.340146 -427.2661)
		(size 0.7112)
		(drill 0.4064)
		(layers "F.Cu" "B.Cu")
		(net "GND")
	)
	(via
		(at 138.937746 -492.4679)
		(size 0.7112)
		(drill 0.4064)
		(layers "F.Cu" "B.Cu")
		(net "GND")
	)
	(via
		(at 166.623746 -87.3887)
		(size 0.7112)
		(drill 0.4064)
		(layers "F.Cu" "B.Cu")
		(net "GND")
	)
	(via
		(at 35.56 -149.2758)
		(size 0.7112)
		(drill 0.4064)
		(layers "F.Cu" "B.Cu")
		(net "GND")
	)
	(via
		(at 62.102746 -160.5407)
		(size 0.7112)
		(drill 0.4064)
		(layers "F.Cu" "B.Cu")
		(net "GND")
	)
	(via
		(at 135.076946 -461.8863)
		(size 0.7112)
		(drill 0.4064)
		(layers "F.Cu" "B.Cu")
		(net "GND")
	)
	(via
		(at 156.590746 -481.0887)
		(size 0.7112)
		(drill 0.4064)
		(layers "F.Cu" "B.Cu")
		(net "GND")
	)
	(via
		(at 184.784746 -287.6931)
		(size 0.7112)
		(drill 0.4064)
		(layers "F.Cu" "B.Cu")
		(net "GND")
	)
	(via
		(at 36.321746 -35.8267)
		(size 0.7112)
		(drill 0.4064)
		(layers "F.Cu" "B.Cu")
		(net "GND")
	)
	(via
		(at 235.203746 -346.7227)
		(size 0.7112)
		(drill 0.4064)
		(layers "F.Cu" "B.Cu")
		(net "GND")
	)
	(via
		(at 221.509844 -378.57684)
		(size 0.5588)
		(drill 0.3048)
		(layers "F.Cu" "B.Cu")
		(net "GND")
	)
	(via
		(at 72.491346 -249.6693)
		(size 0.7112)
		(drill 0.4064)
		(layers "F.Cu" "B.Cu")
		(net "GND")
	)
	(via
		(at 13.461746 -475.3737)
		(size 0.7112)
		(drill 0.4064)
		(layers "F.Cu" "B.Cu")
		(net "GND")
	)
	(via
		(at 157.022546 -326.9615)
		(size 0.7112)
		(drill 0.4064)
		(layers "F.Cu" "B.Cu")
		(net "GND")
	)
	(via
		(at 141.604746 -366.5347)
		(size 0.7112)
		(drill 0.4064)
		(layers "F.Cu" "B.Cu")
		(net "GND")
	)
	(via
		(at 48.386746 -128.908302)
		(size 0.7112)
		(drill 0.4064)
		(layers "F.Cu" "B.Cu")
		(net "GND")
	)
	(via
		(at 239.521746 -214.7697)
		(size 0.7112)
		(drill 0.4064)
		(layers "F.Cu" "B.Cu")
		(net "GND")
	)
	(via
		(at 160.730946 -462.3943)
		(size 0.7112)
		(drill 0.4064)
		(layers "F.Cu" "B.Cu")
		(net "GND")
	)
	(via
		(at 235.203746 -350.4057)
		(size 0.7112)
		(drill 0.4064)
		(layers "F.Cu" "B.Cu")
		(net "GND")
	)
	(via
		(at 196.138546 -238.6711)
		(size 0.7112)
		(drill 0.4064)
		(layers "F.Cu" "B.Cu")
		(net "GND")
	)
	(via
		(at 145.668746 -167.2717)
		(size 0.7112)
		(drill 0.4064)
		(layers "F.Cu" "B.Cu")
		(net "GND")
	)
	(via
		(at 55.5752 -169.8498)
		(size 0.7112)
		(drill 0.4064)
		(layers "F.Cu" "B.Cu")
		(net "GND")
	)
	(via
		(at 160.146746 -315.9633)
		(size 0.7112)
		(drill 0.4064)
		(layers "F.Cu" "B.Cu")
		(net "GND")
	)
	(via
		(at 221.5134 -33.7058)
		(size 0.7112)
		(drill 0.4064)
		(layers "F.Cu" "B.Cu")
		(net "GND")
	)
	(via
		(at 254.888746 -138.7729)
		(size 0.7112)
		(drill 0.4064)
		(layers "F.Cu" "B.Cu")
		(net "GND")
	)
	(via
		(at 115.315746 -106.0577)
		(size 0.7112)
		(drill 0.4064)
		(layers "F.Cu" "B.Cu")
		(net "GND")
	)
	(via
		(at 239.394746 -227.8507)
		(size 0.7112)
		(drill 0.4064)
		(layers "F.Cu" "B.Cu")
		(net "GND")
	)
	(via
		(at 221.843346 -498.7671)
		(size 0.7112)
		(drill 0.4064)
		(layers "F.Cu" "B.Cu")
		(net "GND")
	)
	(via
		(at 233.425746 -171.0817)
		(size 0.7112)
		(drill 0.4064)
		(layers "F.Cu" "B.Cu")
		(net "GND")
	)
	(via
		(at 136.905746 -471.4113)
		(size 0.7112)
		(drill 0.4064)
		(layers "F.Cu" "B.Cu")
		(net "GND")
	)
	(via
		(at 38.185852 -369.305332)
		(size 0.5588)
		(drill 0.3048)
		(layers "F.Cu" "B.Cu")
		(net "GND")
	)
	(via
		(at 84.670646 -353.8474)
		(size 0.7112)
		(drill 0.4064)
		(layers "F.Cu" "B.Cu")
		(net "GND")
	)
	(via
		(at 168.909746 -204.4827)
		(size 0.7112)
		(drill 0.4064)
		(layers "F.Cu" "B.Cu")
		(net "GND")
	)
	(via
		(at 206.577946 -12.5349)
		(size 0.7112)
		(drill 0.4064)
		(layers "F.Cu" "B.Cu")
		(net "GND")
	)
	(via
		(at 7.619746 -101.265736)
		(size 0.5588)
		(drill 0.3048)
		(layers "F.Cu" "B.Cu")
		(net "GND")
	)
	(via
		(at 77.088746 -445.4017)
		(size 0.7112)
		(drill 0.4064)
		(layers "F.Cu" "B.Cu")
		(net "GND")
	)
	(via
		(at 126.923546 -390.8933)
		(size 0.7112)
		(drill 0.4064)
		(layers "F.Cu" "B.Cu")
		(net "GND")
	)
	(via
		(at 213.740746 -34.4297)
		(size 0.5588)
		(drill 0.3048)
		(layers "F.Cu" "B.Cu")
		(net "GND")
	)
	(via
		(at 120.065546 -455.2061)
		(size 0.7112)
		(drill 0.4064)
		(layers "F.Cu" "B.Cu")
		(net "GND")
	)
	(via
		(at 8.813546 -422.4782)
		(size 0.5588)
		(drill 0.3048)
		(layers "F.Cu" "B.Cu")
		(net "GND")
	)
	(via
		(at 212.242146 -143.2687)
		(size 0.7112)
		(drill 0.4064)
		(layers "F.Cu" "B.Cu")
		(net "GND")
	)
	(via
		(at 234.949746 -373.6467)
		(size 0.7112)
		(drill 0.4064)
		(layers "F.Cu" "B.Cu")
		(net "GND")
	)
	(via
		(at 52.5526 -438.5818)
		(size 0.7112)
		(drill 0.4064)
		(layers "F.Cu" "B.Cu")
		(net "GND")
	)
	(via
		(at 60.1472 -194.5132)
		(size 0.5588)
		(drill 0.3048)
		(layers "F.Cu" "B.Cu")
		(net "GND")
	)
	(via
		(at 6.731 -504.698)
		(size 0.7112)
		(drill 0.4064)
		(layers "F.Cu" "B.Cu")
		(net "GND")
	)
	(via
		(at 149.580346 -478.1169)
		(size 0.7112)
		(drill 0.4064)
		(layers "F.Cu" "B.Cu")
		(net "GND")
	)
	(via
		(at 31.495746 -374.1547)
		(size 0.5588)
		(drill 0.3048)
		(layers "F.Cu" "B.Cu")
		(net "GND")
	)
	(via
		(at 139.445746 -283.4767)
		(size 0.7112)
		(drill 0.4064)
		(layers "F.Cu" "B.Cu")
		(net "GND")
	)
	(via
		(at 51.536346 -328.0283)
		(size 0.7112)
		(drill 0.4064)
		(layers "F.Cu" "B.Cu")
		(net "GND")
	)
	(via
		(at 152.272746 -20.2057)
		(size 0.7112)
		(drill 0.3556)
		(layers "F.Cu" "B.Cu")
		(net "GND")
	)
	(via
		(at 245.490746 -140.2207)
		(size 0.5588)
		(drill 0.3048)
		(layers "F.Cu" "B.Cu")
		(net "GND")
	)
	(via
		(at 143.763746 -50.7873)
		(size 0.7112)
		(drill 0.4064)
		(layers "F.Cu" "B.Cu")
		(net "GND")
	)
	(via
		(at 1.778 -292.481)
		(size 0.7112)
		(drill 0.4064)
		(layers "F.Cu" "B.Cu")
		(net "GND")
	)
	(via
		(at 249.935746 -76.5937)
		(size 0.7112)
		(drill 0.4064)
		(layers "F.Cu" "B.Cu")
		(net "GND")
	)
	(via
		(at 40.160956 -224.35566)
		(size 0.7112)
		(drill 0.4064)
		(layers "F.Cu" "B.Cu")
		(net "GND")
	)
	(via
		(at 5.968746 -122.98553)
		(size 0.5588)
		(drill 0.3048)
		(layers "F.Cu" "B.Cu")
		(net "GND")
	)
	(via
		(at 17.500346 -113.1443)
		(size 0.7112)
		(drill 0.4064)
		(layers "F.Cu" "B.Cu")
		(net "GND")
	)
	(via
		(at 191.77 -463.55)
		(size 0.5588)
		(drill 0.3048)
		(layers "F.Cu" "B.Cu")
		(net "GND")
	)
	(via
		(at 3.758946 -190.8683)
		(size 0.7112)
		(drill 0.4064)
		(layers "F.Cu" "B.Cu")
		(net "GND")
	)
	(via
		(at 5.968746 -160.985454)
		(size 0.5588)
		(drill 0.3048)
		(layers "F.Cu" "B.Cu")
		(net "GND")
	)
	(via
		(at 218.439746 -181.1147)
		(size 0.7112)
		(drill 0.4064)
		(layers "F.Cu" "B.Cu")
		(net "GND")
	)
	(via
		(at 163.448746 -138.8745)
		(size 0.7112)
		(drill 0.4064)
		(layers "F.Cu" "B.Cu")
		(net "GND")
	)
	(via
		(at 184.403746 -19.6977)
		(size 0.7112)
		(drill 0.4064)
		(layers "F.Cu" "B.Cu")
		(net "GND")
	)
	(via
		(at 183.184546 -437.8325)
		(size 0.7112)
		(drill 0.4064)
		(layers "F.Cu" "B.Cu")
		(net "GND")
	)
	(via
		(at 72.034146 -26.9875)
		(size 0.7112)
		(drill 0.4064)
		(layers "F.Cu" "B.Cu")
		(net "GND")
	)
	(via
		(at 68.198746 -433.4637)
		(size 0.7112)
		(drill 0.3556)
		(layers "F.Cu" "B.Cu")
		(net "GND")
	)
	(via
		(at 60.451746 -439.5597)
		(size 0.7112)
		(drill 0.4064)
		(layers "F.Cu" "B.Cu")
		(net "GND")
	)
	(via
		(at 225.297746 -230.4669)
		(size 0.7112)
		(drill 0.4064)
		(layers "F.Cu" "B.Cu")
		(net "GND")
	)
	(via
		(at 76.072746 -282.8417)
		(size 0.7112)
		(drill 0.4064)
		(layers "F.Cu" "B.Cu")
		(net "GND")
	)
	(via
		(at 230.758746 -1.6637)
		(size 0.7112)
		(drill 0.4064)
		(layers "F.Cu" "B.Cu")
		(net "GND")
	)
	(via
		(at 249.707146 -21.2471)
		(size 0.7112)
		(drill 0.4064)
		(layers "F.Cu" "B.Cu")
		(net "GND")
	)
	(via
		(at 7.5184 -384.8862)
		(size 0.5588)
		(drill 0.3048)
		(layers "F.Cu" "B.Cu")
		(net "GND")
	)
	(via
		(at 24.256746 -90.2843)
		(size 0.7112)
		(drill 0.4064)
		(layers "F.Cu" "B.Cu")
		(net "GND")
	)
	(via
		(at 152.475946 -92.8751)
		(size 0.7112)
		(drill 0.4064)
		(layers "F.Cu" "B.Cu")
		(net "GND")
	)
	(via
		(at 222.0214 -371.2464)
		(size 0.5588)
		(drill 0.3048)
		(layers "F.Cu" "B.Cu")
		(net "GND")
	)
	(via
		(at 88.239346 -76.6953)
		(size 0.7112)
		(drill 0.4064)
		(layers "F.Cu" "B.Cu")
		(net "GND")
	)
	(via
		(at 133.603746 -64.7827)
		(size 0.7112)
		(drill 0.4064)
		(layers "F.Cu" "B.Cu")
		(net "GND")
	)
	(via
		(at 151.383746 -158.5087)
		(size 0.7112)
		(drill 0.4064)
		(layers "F.Cu" "B.Cu")
		(net "GND")
	)
	(via
		(at 195.055744 -391.245344)
		(size 0.5588)
		(drill 0.3048)
		(layers "F.Cu" "B.Cu")
		(net "GND")
	)
	(via
		(at 120.014746 -116.3447)
		(size 0.7112)
		(drill 0.4064)
		(layers "F.Cu" "B.Cu")
		(net "GND")
	)
	(via
		(at 144.271746 -306.4637)
		(size 0.7112)
		(drill 0.4064)
		(layers "F.Cu" "B.Cu")
		(net "GND")
	)
	(via
		(at 196.976746 -140.6017)
		(size 0.7112)
		(drill 0.4064)
		(layers "F.Cu" "B.Cu")
		(net "GND")
	)
	(via
		(at 105.917746 -16.1417)
		(size 0.7112)
		(drill 0.4064)
		(layers "F.Cu" "B.Cu")
		(net "GND")
	)
	(via
		(at 95.884746 -305.0667)
		(size 0.7112)
		(drill 0.4064)
		(layers "F.Cu" "B.Cu")
		(net "GND")
	)
	(via
		(at 99.948746 -446.9257)
		(size 0.7112)
		(drill 0.4064)
		(layers "F.Cu" "B.Cu")
		(net "GND")
	)
	(via
		(at 117.474746 -232.2957)
		(size 0.7112)
		(drill 0.4064)
		(layers "F.Cu" "B.Cu")
		(net "GND")
	)
	(via
		(at 214.832946 -302.3743)
		(size 0.7112)
		(drill 0.4064)
		(layers "F.Cu" "B.Cu")
		(net "GND")
	)
	(via
		(at 51.993546 -236.0803)
		(size 0.7112)
		(drill 0.4064)
		(layers "F.Cu" "B.Cu")
		(net "GND")
	)
	(via
		(at 79.511906 -89.4969)
		(size 0.5588)
		(drill 0.3048)
		(layers "F.Cu" "B.Cu")
		(net "GND")
	)
	(via
		(at 108.204 -23.749)
		(size 0.5588)
		(drill 0.3048)
		(layers "F.Cu" "B.Cu")
		(net "GND")
	)
	(via
		(at 154.177746 -202.4507)
		(size 0.7112)
		(drill 0.4064)
		(layers "F.Cu" "B.Cu")
		(net "GND")
	)
	(via
		(at 73.380346 -208.4197)
		(size 0.7112)
		(drill 0.4064)
		(layers "F.Cu" "B.Cu")
		(net "GND")
	)
	(via
		(at 134.746746 -329.4507)
		(size 0.7112)
		(drill 0.4064)
		(layers "F.Cu" "B.Cu")
		(net "GND")
	)
	(via
		(at 152.653746 -254.5207)
		(size 0.7112)
		(drill 0.4064)
		(layers "F.Cu" "B.Cu")
		(net "GND")
	)
	(via
		(at 77.393546 -370.2177)
		(size 0.7112)
		(drill 0.4064)
		(layers "F.Cu" "B.Cu")
		(net "GND")
	)
	(via
		(at 124.078746 -175.5267)
		(size 0.7112)
		(drill 0.4064)
		(layers "F.Cu" "B.Cu")
		(net "GND")
	)
	(via
		(at 187.400946 -362.8009)
		(size 0.7112)
		(drill 0.4064)
		(layers "F.Cu" "B.Cu")
		(net "GND")
	)
	(via
		(at 255.345946 -73.9013)
		(size 0.7112)
		(drill 0.4064)
		(layers "F.Cu" "B.Cu")
		(net "GND")
	)
	(via
		(at 197.357746 -418.5031)
		(size 0.7112)
		(drill 0.4064)
		(layers "F.Cu" "B.Cu")
		(net "GND")
	)
	(via
		(at 59.080146 -303.7205)
		(size 0.7112)
		(drill 0.4064)
		(layers "F.Cu" "B.Cu")
		(net "GND")
	)
	(via
		(at 180.720746 -64.1477)
		(size 0.7112)
		(drill 0.4064)
		(layers "F.Cu" "B.Cu")
		(net "GND")
	)
	(via
		(at 166.369746 -351.8027)
		(size 0.7112)
		(drill 0.4064)
		(layers "F.Cu" "B.Cu")
		(net "GND")
	)
	(via
		(at 80.644746 -49.0093)
		(size 0.7112)
		(drill 0.4064)
		(layers "F.Cu" "B.Cu")
		(net "GND")
	)
	(via
		(at 98.958146 -23.1013)
		(size 0.7112)
		(drill 0.4064)
		(layers "F.Cu" "B.Cu")
		(net "GND")
	)
	(via
		(at 252.348746 -465.7217)
		(size 0.7112)
		(drill 0.4064)
		(layers "F.Cu" "B.Cu")
		(net "GND")
	)
	(via
		(at 176.859946 -501.9675)
		(size 0.7112)
		(drill 0.4064)
		(layers "F.Cu" "B.Cu")
		(net "GND")
	)
	(via
		(at 76.047346 -245.3513)
		(size 0.7112)
		(drill 0.4064)
		(layers "F.Cu" "B.Cu")
		(net "GND")
	)
	(via
		(at 259.333746 -201.1807)
		(size 0.7112)
		(drill 0.4064)
		(layers "F.Cu" "B.Cu")
		(net "GND")
	)
	(via
		(at 226.2378 -33.655)
		(size 0.7112)
		(drill 0.4064)
		(layers "F.Cu" "B.Cu")
		(net "GND")
	)
	(via
		(at 182.117746 -291.6301)
		(size 0.7112)
		(drill 0.4064)
		(layers "F.Cu" "B.Cu")
		(net "GND")
	)
	(via
		(at 247.0658 -389.8392)
		(size 0.7112)
		(drill 0.4064)
		(layers "F.Cu" "B.Cu")
		(net "GND")
	)
	(via
		(at 254.888746 -143.5989)
		(size 0.7112)
		(drill 0.4064)
		(layers "F.Cu" "B.Cu")
		(net "GND")
	)
	(via
		(at 5.912358 -376.9487)
		(size 0.5588)
		(drill 0.3048)
		(layers "F.Cu" "B.Cu")
		(net "GND")
	)
	(via
		(at 198.881746 -423.6847)
		(size 0.7112)
		(drill 0.4064)
		(layers "F.Cu" "B.Cu")
		(net "GND")
	)
	(via
		(at 132.409946 -41.2623)
		(size 0.7112)
		(drill 0.4064)
		(layers "F.Cu" "B.Cu")
		(net "GND")
	)
	(via
		(at 6.095746 -154.7495)
		(size 0.5588)
		(drill 0.3048)
		(layers "F.Cu" "B.Cu")
		(net "GND")
	)
	(via
		(at 131.444746 -471.2843)
		(size 0.7112)
		(drill 0.4064)
		(layers "F.Cu" "B.Cu")
		(net "GND")
	)
	(via
		(at 227.456746 -377.9647)
		(size 0.7112)
		(drill 0.4064)
		(layers "F.Cu" "B.Cu")
		(net "GND")
	)
	(via
		(at 76.758546 -232.3211)
		(size 0.7112)
		(drill 0.4064)
		(layers "F.Cu" "B.Cu")
		(net "GND")
	)
	(via
		(at 221.176342 -158.67507)
		(size 0.7112)
		(drill 0.4064)
		(layers "F.Cu" "B.Cu")
		(net "GND")
	)
	(via
		(at 7.111746 -363.2327)
		(size 0.5588)
		(drill 0.3048)
		(layers "F.Cu" "B.Cu")
		(net "GND")
	)
	(via
		(at 167.893746 -1.7907)
		(size 0.7112)
		(drill 0.4064)
		(layers "F.Cu" "B.Cu")
		(net "GND")
	)
	(via
		(at 33.908746 -113.0427)
		(size 0.7112)
		(drill 0.4064)
		(layers "F.Cu" "B.Cu")
		(net "GND")
	)
	(via
		(at 16.636746 -14.9987)
		(size 0.7112)
		(drill 0.4064)
		(layers "F.Cu" "B.Cu")
		(net "GND")
	)
	(via
		(at 214.070946 -432.0921)
		(size 0.7112)
		(drill 0.4064)
		(layers "F.Cu" "B.Cu")
		(net "GND")
	)
	(via
		(at 95.25 -238.506)
		(size 0.7112)
		(drill 0.4064)
		(layers "F.Cu" "B.Cu")
		(net "GND")
	)
	(via
		(at 237.108746 -105.4227)
		(size 0.7112)
		(drill 0.4064)
		(layers "F.Cu" "B.Cu")
		(net "GND")
	)
	(via
		(at 24.231346 -105.7529)
		(size 0.7112)
		(drill 0.4064)
		(layers "F.Cu" "B.Cu")
		(net "GND")
	)
	(via
		(at 206.908146 -417.2331)
		(size 0.7112)
		(drill 0.4064)
		(layers "F.Cu" "B.Cu")
		(net "GND")
	)
	(via
		(at 238.645446 -44.49445)
		(size 0.5588)
		(drill 0.3048)
		(layers "F.Cu" "B.Cu")
		(net "GND")
	)
	(via
		(at 178.8922 -464.4136)
		(size 0.7112)
		(drill 0.4064)
		(layers "F.Cu" "B.Cu")
		(net "GND")
	)
	(via
		(at 259.333746 -64.0207)
		(size 0.7112)
		(drill 0.4064)
		(layers "F.Cu" "B.Cu")
		(net "GND")
	)
	(via
		(at 149.605746 -47.0027)
		(size 0.7112)
		(drill 0.4064)
		(layers "F.Cu" "B.Cu")
		(net "GND")
	)
	(via
		(at 74.803 -86.106)
		(size 0.5588)
		(drill 0.3048)
		(layers "F.Cu" "B.Cu")
		(net "GND")
	)
	(via
		(at 169.290746 -138.9507)
		(size 0.7112)
		(drill 0.4064)
		(layers "F.Cu" "B.Cu")
		(net "GND")
	)
	(via
		(at 200.532746 -311.1627)
		(size 0.7112)
		(drill 0.4064)
		(layers "F.Cu" "B.Cu")
		(net "GND")
	)
	(via
		(at 5.841746 -143.6497)
		(size 0.5588)
		(drill 0.3048)
		(layers "F.Cu" "B.Cu")
		(net "GND")
	)
	(via
		(at 87.477346 -339.8901)
		(size 0.7112)
		(drill 0.4064)
		(layers "F.Cu" "B.Cu")
		(net "GND")
	)
	(via
		(at 126.237746 -457.0857)
		(size 0.7112)
		(drill 0.4064)
		(layers "F.Cu" "B.Cu")
		(net "GND")
	)
	(via
		(at 72.923146 -262.9027)
		(size 0.7112)
		(drill 0.4064)
		(layers "F.Cu" "B.Cu")
		(net "GND")
	)
	(via
		(at 193.947034 -75.087988)
		(size 0.5588)
		(drill 0.3048)
		(layers "F.Cu" "B.Cu")
		(net "GND")
	)
	(via
		(at 122.580146 -368.2873)
		(size 0.7112)
		(drill 0.4064)
		(layers "F.Cu" "B.Cu")
		(net "GND")
	)
	(via
		(at 72.034146 -217.7923)
		(size 0.7112)
		(drill 0.4064)
		(layers "F.Cu" "B.Cu")
		(net "GND")
	)
	(via
		(at 230.225346 -79.8195)
		(size 0.7112)
		(drill 0.4064)
		(layers "F.Cu" "B.Cu")
		(net "GND")
	)
	(via
		(at 160.908746 -410.3243)
		(size 0.7112)
		(drill 0.4064)
		(layers "F.Cu" "B.Cu")
		(net "GND")
	)
	(via
		(at 154.304746 -184.5437)
		(size 0.7112)
		(drill 0.4064)
		(layers "F.Cu" "B.Cu")
		(net "GND")
	)
	(via
		(at 47.802546 -502.4755)
		(size 0.7112)
		(drill 0.4064)
		(layers "F.Cu" "B.Cu")
		(net "GND")
	)
	(via
		(at 234.060746 -257.4417)
		(size 0.7112)
		(drill 0.4064)
		(layers "F.Cu" "B.Cu")
		(net "GND")
	)
	(via
		(at 219.3798 -474.2942)
		(size 0.5588)
		(drill 0.3048)
		(layers "F.Cu" "B.Cu")
		(net "GND")
	)
	(via
		(at 185.419746 -1.6637)
		(size 0.7112)
		(drill 0.4064)
		(layers "F.Cu" "B.Cu")
		(net "GND")
	)
	(via
		(at 196.722746 -135.2677)
		(size 0.7112)
		(drill 0.4064)
		(layers "F.Cu" "B.Cu")
		(net "GND")
	)
	(via
		(at 134.314946 -50.7873)
		(size 0.7112)
		(drill 0.4064)
		(layers "F.Cu" "B.Cu")
		(net "GND")
	)
	(via
		(at 175.513746 -329.0697)
		(size 0.7112)
		(drill 0.3556)
		(layers "F.Cu" "B.Cu")
		(net "GND")
	)
	(via
		(at 43.001946 -242.9129)
		(size 0.7112)
		(drill 0.4064)
		(layers "F.Cu" "B.Cu")
		(net "GND")
	)
	(via
		(at 192.633346 -474.5609)
		(size 0.7112)
		(drill 0.4064)
		(layers "F.Cu" "B.Cu")
		(net "GND")
	)
	(via
		(at 169.087546 -339.6615)
		(size 0.7112)
		(drill 0.4064)
		(layers "F.Cu" "B.Cu")
		(net "GND")
	)
	(via
		(at 240.994946 -261.3533)
		(size 0.7112)
		(drill 0.4064)
		(layers "F.Cu" "B.Cu")
		(net "GND")
	)
	(via
		(at 7.873746 -166.6875)
		(size 0.5588)
		(drill 0.3048)
		(layers "F.Cu" "B.Cu")
		(net "GND")
	)
	(via
		(at 137.515346 -217.0303)
		(size 0.7112)
		(drill 0.4064)
		(layers "F.Cu" "B.Cu")
		(net "GND")
	)
	(via
		(at 78.257146 -477.6597)
		(size 0.7112)
		(drill 0.4064)
		(layers "F.Cu" "B.Cu")
		(net "GND")
	)
	(via
		(at 68.452746 -156.6037)
		(size 0.7112)
		(drill 0.4064)
		(layers "F.Cu" "B.Cu")
		(net "GND")
	)
	(via
		(at 2.921 -504.698)
		(size 0.7112)
		(drill 0.4064)
		(layers "F.Cu" "B.Cu")
		(net "GND")
	)
	(via
		(at 128.828546 -318.0969)
		(size 0.7112)
		(drill 0.4064)
		(layers "F.Cu" "B.Cu")
		(net "GND")
	)
	(via
		(at 149.351746 -41.6687)
		(size 0.7112)
		(drill 0.4064)
		(layers "F.Cu" "B.Cu")
		(net "GND")
	)
	(via
		(at 67.182746 -210.5787)
		(size 0.7112)
		(drill 0.4064)
		(layers "F.Cu" "B.Cu")
		(net "GND")
	)
	(via
		(at 6.298946 -252.0315)
		(size 0.7112)
		(drill 0.4064)
		(layers "F.Cu" "B.Cu")
		(net "GND")
	)
	(via
		(at 3.936746 -87.0077)
		(size 0.7112)
		(drill 0.4064)
		(layers "F.Cu" "B.Cu")
		(net "GND")
	)
	(via
		(at 137.185146 -77.8637)
		(size 0.7112)
		(drill 0.4064)
		(layers "F.Cu" "B.Cu")
		(net "GND")
	)
	(via
		(at 236.981746 -95.1357)
		(size 0.7112)
		(drill 0.4064)
		(layers "F.Cu" "B.Cu")
		(net "GND")
	)
	(via
		(at 224.5106 -434.213)
		(size 0.7112)
		(drill 0.4064)
		(layers "F.Cu" "B.Cu")
		(net "GND")
	)
	(via
		(at 235.076746 -364.6297)
		(size 0.7112)
		(drill 0.4064)
		(layers "F.Cu" "B.Cu")
		(net "GND")
	)
	(via
		(at 191.871346 -330.3651)
		(size 0.7112)
		(drill 0.4064)
		(layers "F.Cu" "B.Cu")
		(net "GND")
	)
	(via
		(at 119.481346 -26.3017)
		(size 0.7112)
		(drill 0.4064)
		(layers "F.Cu" "B.Cu")
		(net "GND")
	)
	(via
		(at 210.6168 -436.8292)
		(size 0.7112)
		(drill 0.4064)
		(layers "F.Cu" "B.Cu")
		(net "GND")
	)
	(via
		(at 65.023746 -471.4113)
		(size 0.7112)
		(drill 0.4064)
		(layers "F.Cu" "B.Cu")
		(net "GND")
	)
	(via
		(at 158.749746 -11.3157)
		(size 0.7112)
		(drill 0.4064)
		(layers "F.Cu" "B.Cu")
		(net "GND")
	)
	(via
		(at 254.635 -496.189)
		(size 0.7112)
		(drill 0.4064)
		(layers "F.Cu" "B.Cu")
		(net "GND")
	)
	(via
		(at 5.968746 -370.9797)
		(size 0.5588)
		(drill 0.3048)
		(layers "F.Cu" "B.Cu")
		(net "GND")
	)
	(via
		(at 203.479146 -468.5665)
		(size 0.7112)
		(drill 0.4064)
		(layers "F.Cu" "B.Cu")
		(net "GND")
	)
	(via
		(at 237.997746 -504.5837)
		(size 0.7112)
		(drill 0.4064)
		(layers "F.Cu" "B.Cu")
		(net "GND")
	)
	(via
		(at 132.714746 -222.5167)
		(size 0.7112)
		(drill 0.4064)
		(layers "F.Cu" "B.Cu")
		(net "GND")
	)
	(via
		(at 157.733746 -104.5337)
		(size 0.7112)
		(drill 0.4064)
		(layers "F.Cu" "B.Cu")
		(net "GND")
	)
	(via
		(at 43.687746 -170.8023)
		(size 0.7112)
		(drill 0.4064)
		(layers "F.Cu" "B.Cu")
		(net "GND")
	)
	(via
		(at 220.598746 -358.1527)
		(size 0.7112)
		(drill 0.4064)
		(layers "F.Cu" "B.Cu")
		(net "GND")
	)
	(via
		(at 3.885946 -445.3255)
		(size 0.7112)
		(drill 0.4064)
		(layers "F.Cu" "B.Cu")
		(net "GND")
	)
	(via
		(at 19.405346 -208.3943)
		(size 0.7112)
		(drill 0.4064)
		(layers "F.Cu" "B.Cu")
		(net "GND")
	)
	(via
		(at 188.468 -396.24)
		(size 0.7112)
		(drill 0.4064)
		(layers "F.Cu" "B.Cu")
		(net "GND")
	)
	(via
		(at 229.300786 -383.43459)
		(size 0.7112)
		(drill 0.4064)
		(layers "F.Cu" "B.Cu")
		(net "GND")
	)
	(via
		(at 117.906546 -355.9683)
		(size 0.7112)
		(drill 0.4064)
		(layers "F.Cu" "B.Cu")
		(net "GND")
	)
	(via
		(at 22.250146 -102.6033)
		(size 0.7112)
		(drill 0.4064)
		(layers "F.Cu" "B.Cu")
		(net "GND")
	)
	(via
		(at 222.1738 -62.2046)
		(size 0.5588)
		(drill 0.3048)
		(layers "F.Cu" "B.Cu")
		(net "GND")
	)
	(via
		(at 90.779346 -132.3975)
		(size 0.7112)
		(drill 0.4064)
		(layers "F.Cu" "B.Cu")
		(net "GND")
	)
	(via
		(at 88.391746 -493.9157)
		(size 0.7112)
		(drill 0.4064)
		(layers "F.Cu" "B.Cu")
		(net "GND")
	)
	(via
		(at 236.727746 -61.7347)
		(size 0.7112)
		(drill 0.4064)
		(layers "F.Cu" "B.Cu")
		(net "GND")
	)
	(via
		(at 59.435746 -257.1877)
		(size 0.7112)
		(drill 0.4064)
		(layers "F.Cu" "B.Cu")
		(net "GND")
	)
	(via
		(at 249.808746 -94.5007)
		(size 0.7112)
		(drill 0.4064)
		(layers "F.Cu" "B.Cu")
		(net "GND")
	)
	(via
		(at 259.206746 -219.7227)
		(size 0.7112)
		(drill 0.4064)
		(layers "F.Cu" "B.Cu")
		(net "GND")
	)
	(via
		(at 112.902746 -71.8947)
		(size 0.7112)
		(drill 0.4064)
		(layers "F.Cu" "B.Cu")
		(net "GND")
	)
	(via
		(at 135.254746 -495.1857)
		(size 0.7112)
		(drill 0.4064)
		(layers "F.Cu" "B.Cu")
		(net "GND")
	)
	(via
		(at 121.919746 -143.9037)
		(size 0.7112)
		(drill 0.4064)
		(layers "F.Cu" "B.Cu")
		(net "GND")
	)
	(via
		(at 81.723992 -87.197946)
		(size 0.7112)
		(drill 0.4064)
		(layers "F.Cu" "B.Cu")
		(net "GND")
	)
	(via
		(at 222.706946 -108.2675)
		(size 0.7112)
		(drill 0.4064)
		(layers "F.Cu" "B.Cu")
		(net "GND")
	)
	(via
		(at 54.863746 -264.0457)
		(size 0.7112)
		(drill 0.4064)
		(layers "F.Cu" "B.Cu")
		(net "GND")
	)
	(via
		(at 122.834146 -422.2877)
		(size 0.7112)
		(drill 0.4064)
		(layers "F.Cu" "B.Cu")
		(net "GND")
	)
	(via
		(at 166.725346 -331.9907)
		(size 0.7112)
		(drill 0.4064)
		(layers "F.Cu" "B.Cu")
		(net "GND")
	)
	(via
		(at 237.616746 -133.2357)
		(size 0.7112)
		(drill 0.4064)
		(layers "F.Cu" "B.Cu")
		(net "GND")
	)
	(via
		(at 103.250746 -476.0087)
		(size 0.7112)
		(drill 0.4064)
		(layers "F.Cu" "B.Cu")
		(net "GND")
	)
	(via
		(at 197.713346 -26.7335)
		(size 0.7112)
		(drill 0.4064)
		(layers "F.Cu" "B.Cu")
		(net "GND")
	)
	(via
		(at 109.499146 -121.7549)
		(size 0.7112)
		(drill 0.4064)
		(layers "F.Cu" "B.Cu")
		(net "GND")
	)
	(via
		(at 112.724946 -409.5115)
		(size 0.7112)
		(drill 0.4064)
		(layers "F.Cu" "B.Cu")
		(net "GND")
	)
	(via
		(at 149.377146 -399.3007)
		(size 0.7112)
		(drill 0.4064)
		(layers "F.Cu" "B.Cu")
		(net "GND")
	)
	(via
		(at 68.452746 -160.2867)
		(size 0.7112)
		(drill 0.4064)
		(layers "F.Cu" "B.Cu")
		(net "GND")
	)
	(via
		(at 26.161746 -301.7647)
		(size 0.7112)
		(drill 0.4064)
		(layers "F.Cu" "B.Cu")
		(net "GND")
	)
	(via
		(at 53.263546 -502.6025)
		(size 0.7112)
		(drill 0.4064)
		(layers "F.Cu" "B.Cu")
		(net "GND")
	)
	(via
		(at 75.793346 -256.0701)
		(size 0.7112)
		(drill 0.4064)
		(layers "F.Cu" "B.Cu")
		(net "GND")
	)
	(via
		(at 67.4878 -415.3154)
		(size 0.7112)
		(drill 0.4064)
		(layers "F.Cu" "B.Cu")
		(net "GND")
	)
	(via
		(at 62.966346 -306.9971)
		(size 0.7112)
		(drill 0.4064)
		(layers "F.Cu" "B.Cu")
		(net "GND")
	)
	(via
		(at 182.879746 -407.6827)
		(size 0.7112)
		(drill 0.4064)
		(layers "F.Cu" "B.Cu")
		(net "GND")
	)
	(via
		(at 176.529746 -15.9131)
		(size 0.7112)
		(drill 0.4064)
		(layers "F.Cu" "B.Cu")
		(net "GND")
	)
	(via
		(at 185.114946 -490.9947)
		(size 0.7112)
		(drill 0.4064)
		(layers "F.Cu" "B.Cu")
		(net "GND")
	)
	(via
		(at 259.079746 -246.6467)
		(size 0.7112)
		(drill 0.4064)
		(layers "F.Cu" "B.Cu")
		(net "GND")
	)
	(via
		(at 53.1368 -412.496)
		(size 0.7112)
		(drill 0.4064)
		(layers "F.Cu" "B.Cu")
		(net "GND")
	)
	(via
		(at 221.446344 -364.60684)
		(size 0.7112)
		(drill 0.4064)
		(layers "F.Cu" "B.Cu")
		(net "GND")
	)
	(via
		(at 240.4618 -362.331)
		(size 0.7112)
		(drill 0.4064)
		(layers "F.Cu" "B.Cu")
		(net "GND")
	)
	(via
		(at 132.587746 -227.4697)
		(size 0.7112)
		(drill 0.4064)
		(layers "F.Cu" "B.Cu")
		(net "GND")
	)
	(via
		(at 217.03792 -474.364812)
		(size 0.5588)
		(drill 0.3048)
		(layers "F.Cu" "B.Cu")
		(net "GND")
	)
	(via
		(at 69.671946 -231.8893)
		(size 0.7112)
		(drill 0.4064)
		(layers "F.Cu" "B.Cu")
		(net "GND")
	)
	(via
		(at 100.075746 -453.2757)
		(size 0.7112)
		(drill 0.4064)
		(layers "F.Cu" "B.Cu")
		(net "GND")
	)
	(via
		(at 204.114146 -307.6067)
		(size 0.7112)
		(drill 0.4064)
		(layers "F.Cu" "B.Cu")
		(net "GND")
	)
	(via
		(at 6.984746 -420.8907)
		(size 0.5588)
		(drill 0.3048)
		(layers "F.Cu" "B.Cu")
		(net "GND")
	)
	(via
		(at 239.140746 -451.1675)
		(size 0.7112)
		(drill 0.4064)
		(layers "F.Cu" "B.Cu")
		(net "GND")
	)
	(via
		(at 205.307946 -445.8335)
		(size 0.7112)
		(drill 0.4064)
		(layers "F.Cu" "B.Cu")
		(net "GND")
	)
	(via
		(at 157.606746 -158.3817)
		(size 0.7112)
		(drill 0.4064)
		(layers "F.Cu" "B.Cu")
		(net "GND")
	)
	(via
		(at 159.003746 -1.7907)
		(size 0.7112)
		(drill 0.4064)
		(layers "F.Cu" "B.Cu")
		(net "GND")
	)
	(via
		(at 6.8834 -379.5522)
		(size 0.5588)
		(drill 0.3048)
		(layers "F.Cu" "B.Cu")
		(net "GND")
	)
	(via
		(at 62.483746 -344.9447)
		(size 0.7112)
		(drill 0.4064)
		(layers "F.Cu" "B.Cu")
		(net "GND")
	)
	(via
		(at 45.110146 -474.1545)
		(size 0.7112)
		(drill 0.4064)
		(layers "F.Cu" "B.Cu")
		(net "GND")
	)
	(via
		(at 199.892412 -75.826366)
		(size 0.5588)
		(drill 0.3048)
		(layers "F.Cu" "B.Cu")
		(net "GND")
	)
	(via
		(at 124.713746 -108.4707)
		(size 0.7112)
		(drill 0.4064)
		(layers "F.Cu" "B.Cu")
		(net "GND")
	)
	(via
		(at 27.235912 -337.960208)
		(size 0.5588)
		(drill 0.3048)
		(layers "F.Cu" "B.Cu")
		(net "GND")
	)
	(via
		(at 49.910746 -311.0357)
		(size 0.7112)
		(drill 0.4064)
		(layers "F.Cu" "B.Cu")
		(net "GND")
	)
	(via
		(at 22.732746 -239.4839)
		(size 0.5588)
		(drill 0.3048)
		(layers "F.Cu" "B.Cu")
		(net "GND")
	)
	(via
		(at 28.066746 -346.7227)
		(size 0.5588)
		(drill 0.3048)
		(layers "F.Cu" "B.Cu")
		(net "GND")
	)
	(via
		(at 170.484546 -308.2925)
		(size 0.7112)
		(drill 0.4064)
		(layers "F.Cu" "B.Cu")
		(net "GND")
	)
	(via
		(at 152.221946 -87.5411)
		(size 0.7112)
		(drill 0.4064)
		(layers "F.Cu" "B.Cu")
		(net "GND")
	)
	(via
		(at 16.636746 -10.5537)
		(size 0.7112)
		(drill 0.4064)
		(layers "F.Cu" "B.Cu")
		(net "GND")
	)
	(via
		(at 153.415746 -33.9725)
		(size 0.7112)
		(drill 0.4064)
		(layers "F.Cu" "B.Cu")
		(net "GND")
	)
	(via
		(at 209.651346 -137.4013)
		(size 0.7112)
		(drill 0.4064)
		(layers "F.Cu" "B.Cu")
		(net "GND")
	)
	(via
		(at 139.547346 -323.8119)
		(size 0.7112)
		(drill 0.4064)
		(layers "F.Cu" "B.Cu")
		(net "GND")
	)
	(via
		(at 124.027946 -388.8867)
		(size 0.7112)
		(drill 0.4064)
		(layers "F.Cu" "B.Cu")
		(net "GND")
	)
	(via
		(at 69.671946 -324.2183)
		(size 0.7112)
		(drill 0.4064)
		(layers "F.Cu" "B.Cu")
		(net "GND")
	)
	(via
		(at 56.667146 -300.4185)
		(size 0.7112)
		(drill 0.4064)
		(layers "F.Cu" "B.Cu")
		(net "GND")
	)
	(via
		(at 123.392946 -228.8667)
		(size 0.7112)
		(drill 0.4064)
		(layers "F.Cu" "B.Cu")
		(net "GND")
	)
	(via
		(at 77.393546 -268.4907)
		(size 0.7112)
		(drill 0.4064)
		(layers "F.Cu" "B.Cu")
		(net "GND")
	)
	(via
		(at 167.969946 -487.1847)
		(size 0.7112)
		(drill 0.4064)
		(layers "F.Cu" "B.Cu")
		(net "GND")
	)
	(via
		(at 182.092346 -370.8019)
		(size 0.7112)
		(drill 0.4064)
		(layers "F.Cu" "B.Cu")
		(net "GND")
	)
	(via
		(at 234.200446 -145.89125)
		(size 0.5588)
		(drill 0.3048)
		(layers "F.Cu" "B.Cu")
		(net "GND")
	)
	(via
		(at 78.815946 -314.9727)
		(size 0.7112)
		(drill 0.4064)
		(layers "F.Cu" "B.Cu")
		(net "GND")
	)
	(via
		(at 19.303746 -141.38656)
		(size 0.7112)
		(drill 0.4064)
		(layers "F.Cu" "B.Cu")
		(net "GND")
	)
	(via
		(at 259.460746 -128.0287)
		(size 0.7112)
		(drill 0.4064)
		(layers "F.Cu" "B.Cu")
		(net "GND")
	)
	(via
		(at 179.577746 -201.3077)
		(size 0.7112)
		(drill 0.4064)
		(layers "F.Cu" "B.Cu")
		(net "GND")
	)
	(via
		(at 153.669746 -19.1389)
		(size 0.7112)
		(drill 0.4064)
		(layers "F.Cu" "B.Cu")
		(net "GND")
	)
	(via
		(at 152.856946 -491.1979)
		(size 0.7112)
		(drill 0.4064)
		(layers "F.Cu" "B.Cu")
		(net "GND")
	)
	(via
		(at 106.730546 -162.1917)
		(size 0.7112)
		(drill 0.4064)
		(layers "F.Cu" "B.Cu")
		(net "GND")
	)
	(via
		(at 93.928946 -477.5327)
		(size 0.7112)
		(drill 0.4064)
		(layers "F.Cu" "B.Cu")
		(net "GND")
	)
	(via
		(at 95.122746 -347.1037)
		(size 0.7112)
		(drill 0.4064)
		(layers "F.Cu" "B.Cu")
		(net "GND")
	)
	(via
		(at 124.078746 -171.0817)
		(size 0.7112)
		(drill 0.4064)
		(layers "F.Cu" "B.Cu")
		(net "GND")
	)
	(via
		(at 90.779346 -134.7597)
		(size 0.7112)
		(drill 0.4064)
		(layers "F.Cu" "B.Cu")
		(net "GND")
	)
	(via
		(at 157.352746 -458.0001)
		(size 0.7112)
		(drill 0.4064)
		(layers "F.Cu" "B.Cu")
		(net "GND")
	)
	(via
		(at 117.474746 -265.1379)
		(size 0.7112)
		(drill 0.4064)
		(layers "F.Cu" "B.Cu")
		(net "GND")
	)
	(via
		(at 40.513 -206.9338)
		(size 0.5588)
		(drill 0.3048)
		(layers "F.Cu" "B.Cu")
		(net "GND")
	)
	(via
		(at 232.384346 -500.9515)
		(size 0.7112)
		(drill 0.4064)
		(layers "F.Cu" "B.Cu")
		(net "GND")
	)
	(via
		(at 259.333746 -113.2967)
		(size 0.7112)
		(drill 0.4064)
		(layers "F.Cu" "B.Cu")
		(net "GND")
	)
	(via
		(at 94.868746 -356.1207)
		(size 0.7112)
		(drill 0.4064)
		(layers "F.Cu" "B.Cu")
		(net "GND")
	)
	(via
		(at 63.4492 -63.1952)
		(size 0.7112)
		(drill 0.4064)
		(layers "F.Cu" "B.Cu")
		(net "GND")
	)
	(via
		(at 213.105746 -489.8517)
		(size 0.7112)
		(drill 0.4064)
		(layers "F.Cu" "B.Cu")
		(net "GND")
	)
	(via
		(at 53.085746 -378.7775)
		(size 0.7112)
		(drill 0.4064)
		(layers "F.Cu" "B.Cu")
		(net "GND")
	)
	(via
		(at 151.180546 -462.51114)
		(size 0.7112)
		(drill 0.4064)
		(layers "F.Cu" "B.Cu")
		(net "GND")
	)
	(via
		(at 176.783746 -26.0731)
		(size 0.7112)
		(drill 0.4064)
		(layers "F.Cu" "B.Cu")
		(net "GND")
	)
	(via
		(at 195.89115 -391.026396)
		(size 0.5588)
		(drill 0.3048)
		(layers "F.Cu" "B.Cu")
		(net "GND")
	)
	(via
		(at 121.818146 -215.2777)
		(size 0.7112)
		(drill 0.4064)
		(layers "F.Cu" "B.Cu")
		(net "GND")
	)
	(via
		(at 171.195746 -263.2837)
		(size 0.7112)
		(drill 0.4064)
		(layers "F.Cu" "B.Cu")
		(net "GND")
	)
	(via
		(at 234.060746 -504.5837)
		(size 0.7112)
		(drill 0.4064)
		(layers "F.Cu" "B.Cu")
		(net "GND")
	)
	(via
		(at 40.005 -456.5396)
		(size 0.7112)
		(drill 0.4064)
		(layers "F.Cu" "B.Cu")
		(net "GND")
	)
	(via
		(at 127.355346 -415.1757)
		(size 0.7112)
		(drill 0.4064)
		(layers "F.Cu" "B.Cu")
		(net "GND")
	)
	(via
		(at 242.010946 -78.7781)
		(size 0.7112)
		(drill 0.4064)
		(layers "F.Cu" "B.Cu")
		(net "GND")
	)
	(via
		(at 259.333746 -21.7297)
		(size 0.7112)
		(drill 0.4064)
		(layers "F.Cu" "B.Cu")
		(net "GND")
	)
	(via
		(at 192.404746 -16.0147)
		(size 0.7112)
		(drill 0.4064)
		(layers "F.Cu" "B.Cu")
		(net "GND")
	)
	(via
		(at 237.108746 -85.3567)
		(size 0.7112)
		(drill 0.4064)
		(layers "F.Cu" "B.Cu")
		(net "GND")
	)
	(via
		(at 110.057946 -493.1537)
		(size 0.7112)
		(drill 0.4064)
		(layers "F.Cu" "B.Cu")
		(net "GND")
	)
	(via
		(at 35.7632 -273.3802)
		(size 0.5588)
		(drill 0.3048)
		(layers "F.Cu" "B.Cu")
		(net "GND")
	)
	(via
		(at 6.984746 -352.4377)
		(size 0.5588)
		(drill 0.3048)
		(layers "F.Cu" "B.Cu")
		(net "GND")
	)
	(via
		(at 130.047746 -504.8377)
		(size 0.7112)
		(drill 0.4064)
		(layers "F.Cu" "B.Cu")
		(net "GND")
	)
	(via
		(at 70.179946 -95.5167)
		(size 0.7112)
		(drill 0.4064)
		(layers "F.Cu" "B.Cu")
		(net "GND")
	)
	(via
		(at 237.108746 -109.1057)
		(size 0.7112)
		(drill 0.4064)
		(layers "F.Cu" "B.Cu")
		(net "GND")
	)
	(via
		(at 68.579746 -263.4107)
		(size 0.7112)
		(drill 0.4064)
		(layers "F.Cu" "B.Cu")
		(net "GND")
	)
	(via
		(at 191.769746 -504.8377)
		(size 0.7112)
		(drill 0.4064)
		(layers "F.Cu" "B.Cu")
		(net "GND")
	)
	(via
		(at 167.969946 -480.0727)
		(size 0.7112)
		(drill 0.4064)
		(layers "F.Cu" "B.Cu")
		(net "GND")
	)
	(via
		(at 216.2302 -165.5318)
		(size 0.5588)
		(drill 0.3048)
		(layers "F.Cu" "B.Cu")
		(net "GND")
	)
	(via
		(at 165.074346 -35.1409)
		(size 0.7112)
		(drill 0.4064)
		(layers "F.Cu" "B.Cu")
		(net "GND")
	)
	(via
		(at 248.259346 -11.1887)
		(size 0.7112)
		(drill 0.4064)
		(layers "F.Cu" "B.Cu")
		(net "GND")
	)
	(via
		(at 138.937746 -499.5799)
		(size 0.7112)
		(drill 0.4064)
		(layers "F.Cu" "B.Cu")
		(net "GND")
	)
	(via
		(at 7.2644 -126.8222)
		(size 0.5588)
		(drill 0.3048)
		(layers "F.Cu" "B.Cu")
		(net "GND")
	)
	(via
		(at 148.157946 -318.8335)
		(size 0.7112)
		(drill 0.4064)
		(layers "F.Cu" "B.Cu")
		(net "GND")
	)
	(via
		(at 127.126746 -27.5717)
		(size 0.7112)
		(drill 0.4064)
		(layers "F.Cu" "B.Cu")
		(net "GND")
	)
	(via
		(at 12.318746 -66.1797)
		(size 0.7112)
		(drill 0.4064)
		(layers "F.Cu" "B.Cu")
		(net "GND")
	)
	(via
		(at 245.414546 -120.2309)
		(size 0.7112)
		(drill 0.4064)
		(layers "F.Cu" "B.Cu")
		(net "GND")
	)
	(via
		(at 70.814946 -242.8621)
		(size 0.7112)
		(drill 0.4064)
		(layers "F.Cu" "B.Cu")
		(net "GND")
	)
	(via
		(at 237.235746 -100.4697)
		(size 0.7112)
		(drill 0.4064)
		(layers "F.Cu" "B.Cu")
		(net "GND")
	)
	(via
		(at 216.534746 -411.8229)
		(size 0.7112)
		(drill 0.4064)
		(layers "F.Cu" "B.Cu")
		(net "GND")
	)
	(via
		(at 213.867746 -284.1117)
		(size 0.7112)
		(drill 0.4064)
		(layers "F.Cu" "B.Cu")
		(net "GND")
	)
	(via
		(at 55.879746 -164.3507)
		(size 0.7112)
		(drill 0.4064)
		(layers "F.Cu" "B.Cu")
		(net "GND")
	)
	(via
		(at 71.957946 -290.7919)
		(size 0.7112)
		(drill 0.4064)
		(layers "F.Cu" "B.Cu")
		(net "GND")
	)
	(via
		(at 233.552746 -186.1947)
		(size 0.7112)
		(drill 0.4064)
		(layers "F.Cu" "B.Cu")
		(net "GND")
	)
	(via
		(at 95.630746 -450.9897)
		(size 0.7112)
		(drill 0.4064)
		(layers "F.Cu" "B.Cu")
		(net "GND")
	)
	(via
		(at 86.385146 -225.3869)
		(size 0.7112)
		(drill 0.4064)
		(layers "F.Cu" "B.Cu")
		(net "GND")
	)
	(via
		(at 95.122746 -349.3897)
		(size 0.7112)
		(drill 0.4064)
		(layers "F.Cu" "B.Cu")
		(net "GND")
	)
	(via
		(at 192.150746 -434.8861)
		(size 0.7112)
		(drill 0.4064)
		(layers "F.Cu" "B.Cu")
		(net "GND")
	)
	(via
		(at 84.327746 -145.4277)
		(size 0.7112)
		(drill 0.4064)
		(layers "F.Cu" "B.Cu")
		(net "GND")
	)
	(via
		(at 85.546946 -482.0793)
		(size 0.7112)
		(drill 0.4064)
		(layers "F.Cu" "B.Cu")
		(net "GND")
	)
	(via
		(at 180.720746 -87.5157)
		(size 0.7112)
		(drill 0.4064)
		(layers "F.Cu" "B.Cu")
		(net "GND")
	)
	(via
		(at 87.731346 -177.5333)
		(size 0.7112)
		(drill 0.4064)
		(layers "F.Cu" "B.Cu")
		(net "GND")
	)
	(via
		(at 177.291746 -468.5157)
		(size 0.7112)
		(drill 0.4064)
		(layers "F.Cu" "B.Cu")
		(net "GND")
	)
	(via
		(at 216.153746 -62.6237)
		(size 0.5588)
		(drill 0.3048)
		(layers "F.Cu" "B.Cu")
		(net "GND")
	)
	(via
		(at 200.152 -454.152)
		(size 0.5588)
		(drill 0.3048)
		(layers "F.Cu" "B.Cu")
		(net "GND")
	)
	(via
		(at 235.076746 -283.9847)
		(size 0.7112)
		(drill 0.4064)
		(layers "F.Cu" "B.Cu")
		(net "GND")
	)
	(via
		(at 220.598746 -353.7077)
		(size 0.7112)
		(drill 0.4064)
		(layers "F.Cu" "B.Cu")
		(net "GND")
	)
	(via
		(at 244.9576 -358.0638)
		(size 0.7112)
		(drill 0.4064)
		(layers "F.Cu" "B.Cu")
		(net "GND")
	)
	(via
		(at 199.008746 -464.0707)
		(size 0.5588)
		(drill 0.3048)
		(layers "F.Cu" "B.Cu")
		(net "GND")
	)
	(via
		(at 14.223746 -503.5677)
		(size 0.7112)
		(drill 0.4064)
		(layers "F.Cu" "B.Cu")
		(net "GND")
	)
	(via
		(at 154.304746 -192.6717)
		(size 0.7112)
		(drill 0.4064)
		(layers "F.Cu" "B.Cu")
		(net "GND")
	)
	(via
		(at 200.913746 -303.4157)
		(size 0.7112)
		(drill 0.4064)
		(layers "F.Cu" "B.Cu")
		(net "GND")
	)
	(via
		(at 158.241746 -170.7007)
		(size 0.7112)
		(drill 0.4064)
		(layers "F.Cu" "B.Cu")
		(net "GND")
	)
	(via
		(at 89.255346 -119.5705)
		(size 0.7112)
		(drill 0.4064)
		(layers "F.Cu" "B.Cu")
		(net "GND")
	)
	(via
		(at 178.383946 -356.7303)
		(size 0.7112)
		(drill 0.4064)
		(layers "F.Cu" "B.Cu")
		(net "GND")
	)
	(via
		(at 162.305746 -329.0697)
		(size 0.7112)
		(drill 0.4064)
		(layers "F.Cu" "B.Cu")
		(net "GND")
	)
	(via
		(at 7.9756 -478.8408)
		(size 0.7112)
		(drill 0.4064)
		(layers "F.Cu" "B.Cu")
		(net "GND")
	)
	(via
		(at 221.433644 -55.606696)
		(size 0.7112)
		(drill 0.4064)
		(layers "F.Cu" "B.Cu")
		(net "GND")
	)
	(via
		(at 3.885946 -437.7563)
		(size 0.7112)
		(drill 0.4064)
		(layers "F.Cu" "B.Cu")
		(net "GND")
	)
	(via
		(at 171.424346 -485.4829)
		(size 0.7112)
		(drill 0.4064)
		(layers "F.Cu" "B.Cu")
		(net "GND")
	)
	(via
		(at 110.997746 -286.5247)
		(size 0.7112)
		(drill 0.4064)
		(layers "F.Cu" "B.Cu")
		(net "GND")
	)
	(via
		(at 145.541746 -432.7017)
		(size 0.7112)
		(drill 0.4064)
		(layers "F.Cu" "B.Cu")
		(net "GND")
	)
	(via
		(at 133.730746 -457.4921)
		(size 0.7112)
		(drill 0.4064)
		(layers "F.Cu" "B.Cu")
		(net "GND")
	)
	(via
		(at 129.5654 -401.2692)
		(size 0.7112)
		(drill 0.4064)
		(layers "F.Cu" "B.Cu")
		(net "GND")
	)
	(via
		(at 150.748746 -126.7587)
		(size 0.7112)
		(drill 0.4064)
		(layers "F.Cu" "B.Cu")
		(net "GND")
	)
	(via
		(at 159.383476 -464.583272)
		(size 0.7112)
		(drill 0.4064)
		(layers "F.Cu" "B.Cu")
		(net "GND")
	)
	(via
		(at 244.3226 -399.3896)
		(size 0.7112)
		(drill 0.4064)
		(layers "F.Cu" "B.Cu")
		(net "GND")
	)
	(via
		(at 235.820712 -21.263356)
		(size 0.5588)
		(drill 0.3048)
		(layers "F.Cu" "B.Cu")
		(net "GND")
	)
	(via
		(at 127.736346 -55.1561)
		(size 0.7112)
		(drill 0.4064)
		(layers "F.Cu" "B.Cu")
		(net "GND")
	)
	(via
		(at 5.841746 -384.9497)
		(size 0.5588)
		(drill 0.3048)
		(layers "F.Cu" "B.Cu")
		(net "GND")
	)
	(via
		(at 3.809746 -492.7727)
		(size 0.5588)
		(drill 0.3048)
		(layers "F.Cu" "B.Cu")
		(net "GND")
	)
	(via
		(at 174.421546 -416.2171)
		(size 0.7112)
		(drill 0.4064)
		(layers "F.Cu" "B.Cu")
		(net "GND")
	)
	(via
		(at 153.796746 -55.2577)
		(size 0.7112)
		(drill 0.4064)
		(layers "F.Cu" "B.Cu")
		(net "GND")
	)
	(via
		(at 40.131746 -467.606888)
		(size 0.7112)
		(drill 0.4064)
		(layers "F.Cu" "B.Cu")
		(net "GND")
	)
	(via
		(at 62.026546 -247.2055)
		(size 0.7112)
		(drill 0.4064)
		(layers "F.Cu" "B.Cu")
		(net "GND")
	)
	(via
		(at 123.189746 -451.8787)
		(size 0.7112)
		(drill 0.4064)
		(layers "F.Cu" "B.Cu")
		(net "GND")
	)
	(via
		(at 115.950746 -131.5847)
		(size 0.7112)
		(drill 0.4064)
		(layers "F.Cu" "B.Cu")
		(net "GND")
	)
	(via
		(at 49.288446 -455.3204)
		(size 0.5588)
		(drill 0.3048)
		(layers "F.Cu" "B.Cu")
		(net "GND")
	)
	(via
		(at 221.446344 -368.41684)
		(size 0.7112)
		(drill 0.4064)
		(layers "F.Cu" "B.Cu")
		(net "GND")
	)
	(via
		(at 233.781346 -220.8149)
		(size 0.7112)
		(drill 0.4064)
		(layers "F.Cu" "B.Cu")
		(net "GND")
	)
	(via
		(at 42.697146 -275.2217)
		(size 0.7112)
		(drill 0.4064)
		(layers "F.Cu" "B.Cu")
		(net "GND")
	)
	(via
		(at 212.343746 -198.5137)
		(size 0.7112)
		(drill 0.4064)
		(layers "F.Cu" "B.Cu")
		(net "GND")
	)
	(via
		(at 107.263946 -354.3173)
		(size 0.7112)
		(drill 0.4064)
		(layers "F.Cu" "B.Cu")
		(net "GND")
	)
	(via
		(at 36.194746 -484.116888)
		(size 0.7112)
		(drill 0.4064)
		(layers "F.Cu" "B.Cu")
		(net "GND")
	)
	(via
		(at 142.900146 -480.9363)
		(size 0.7112)
		(drill 0.4064)
		(layers "F.Cu" "B.Cu")
		(net "GND")
	)
	(via
		(at 52.882546 -291.0459)
		(size 0.7112)
		(drill 0.4064)
		(layers "F.Cu" "B.Cu")
		(net "GND")
	)
	(via
		(at 179.07 -460.2226)
		(size 0.7112)
		(drill 0.4064)
		(layers "F.Cu" "B.Cu")
		(net "GND")
	)
	(via
		(at 66.420746 -1.1557)
		(size 0.7112)
		(drill 0.4064)
		(layers "F.Cu" "B.Cu")
		(net "GND")
	)
	(via
		(at 17.0942 -114.3508)
		(size 0.7112)
		(drill 0.4064)
		(layers "F.Cu" "B.Cu")
		(net "GND")
	)
	(via
		(at 150.012146 -376.7963)
		(size 0.7112)
		(drill 0.4064)
		(layers "F.Cu" "B.Cu")
		(net "GND")
	)
	(via
		(at 101.421946 -502.0945)
		(size 0.7112)
		(drill 0.4064)
		(layers "F.Cu" "B.Cu")
		(net "GND")
	)
	(via
		(at 34.1122 -164.1856)
		(size 0.5588)
		(drill 0.3048)
		(layers "F.Cu" "B.Cu")
		(net "GND")
	)
	(via
		(at 6.603746 -176.49698)
		(size 0.5588)
		(drill 0.3048)
		(layers "F.Cu" "B.Cu")
		(net "GND")
	)
	(via
		(at 5.701538 -310.704738)
		(size 0.7112)
		(drill 0.4064)
		(layers "F.Cu" "B.Cu")
		(net "GND")
	)
	(via
		(at 118.566946 -16.4465)
		(size 0.7112)
		(drill 0.4064)
		(layers "F.Cu" "B.Cu")
		(net "GND")
	)
	(via
		(at 17.9832 -137.2362)
		(size 0.7112)
		(drill 0.4064)
		(layers "F.Cu" "B.Cu")
		(net "GND")
	)
	(via
		(at 221.995746 -210.9597)
		(size 0.7112)
		(drill 0.4064)
		(layers "F.Cu" "B.Cu")
		(net "GND")
	)
	(via
		(at 145.541746 -430.4157)
		(size 0.7112)
		(drill 0.4064)
		(layers "F.Cu" "B.Cu")
		(net "GND")
	)
	(via
		(at 92.709746 -504.7107)
		(size 0.7112)
		(drill 0.4064)
		(layers "F.Cu" "B.Cu")
		(net "GND")
	)
	(via
		(at 235.203746 -354.8507)
		(size 0.7112)
		(drill 0.4064)
		(layers "F.Cu" "B.Cu")
		(net "GND")
	)
	(via
		(at 245.566946 -480.6061)
		(size 0.7112)
		(drill 0.4064)
		(layers "F.Cu" "B.Cu")
		(net "GND")
	)
	(via
		(at 2.158746 -502.8057)
		(size 0.7112)
		(drill 0.4064)
		(layers "F.Cu" "B.Cu")
		(net "GND")
	)
	(via
		(at 206.5782 -407.4414)
		(size 0.7112)
		(drill 0.4064)
		(layers "F.Cu" "B.Cu")
		(net "GND")
	)
	(via
		(at 246.125746 -180.2257)
		(size 0.7112)
		(drill 0.4064)
		(layers "F.Cu" "B.Cu")
		(net "GND")
	)
	(via
		(at 208.660746 -79.7687)
		(size 0.7112)
		(drill 0.4064)
		(layers "F.Cu" "B.Cu")
		(net "GND")
	)
	(via
		(at 142.366746 -250.7107)
		(size 0.7112)
		(drill 0.4064)
		(layers "F.Cu" "B.Cu")
		(net "GND")
	)
	(via
		(at 137.515346 -221.8563)
		(size 0.7112)
		(drill 0.4064)
		(layers "F.Cu" "B.Cu")
		(net "GND")
	)
	(via
		(at 140.080746 -1.6637)
		(size 0.7112)
		(drill 0.4064)
		(layers "F.Cu" "B.Cu")
		(net "GND")
	)
	(via
		(at 83.819746 -495.877342)
		(size 0.5588)
		(drill 0.3048)
		(layers "F.Cu" "B.Cu")
		(net "GND")
	)
	(via
		(at 164.439346 -188.5061)
		(size 0.7112)
		(drill 0.4064)
		(layers "F.Cu" "B.Cu")
		(net "GND")
	)
	(via
		(at 62.484 -14.351)
		(size 0.7112)
		(drill 0.4064)
		(layers "F.Cu" "B.Cu")
		(net "GND")
	)
	(via
		(at 76.072746 -278.9047)
		(size 0.7112)
		(drill 0.4064)
		(layers "F.Cu" "B.Cu")
		(net "GND")
	)
	(via
		(at 119.049546 -346.1639)
		(size 0.7112)
		(drill 0.4064)
		(layers "F.Cu" "B.Cu")
		(net "GND")
	)
	(via
		(at 45.6438 -108.1532)
		(size 0.5588)
		(drill 0.3048)
		(layers "F.Cu" "B.Cu")
		(net "GND")
	)
	(via
		(at 86.207346 -90.9447)
		(size 0.7112)
		(drill 0.4064)
		(layers "F.Cu" "B.Cu")
		(net "GND")
	)
	(via
		(at 246.888 -397.764)
		(size 0.7112)
		(drill 0.4064)
		(layers "F.Cu" "B.Cu")
		(net "GND")
	)
	(via
		(at 30.861 -275.2344)
		(size 0.5588)
		(drill 0.3048)
		(layers "F.Cu" "B.Cu")
		(net "GND")
	)
	(via
		(at 6.06933 -60.70473)
		(size 0.7112)
		(drill 0.4064)
		(layers "F.Cu" "B.Cu")
		(net "GND")
	)
	(via
		(at 173.481746 -81.0387)
		(size 0.7112)
		(drill 0.4064)
		(layers "F.Cu" "B.Cu")
		(net "GND")
	)
	(via
		(at 77.444346 -217.4621)
		(size 0.7112)
		(drill 0.4064)
		(layers "F.Cu" "B.Cu")
		(net "GND")
	)
	(via
		(at 246.379746 -228.4095)
		(size 0.7112)
		(drill 0.4064)
		(layers "F.Cu" "B.Cu")
		(net "GND")
	)
	(via
		(at 105.536746 -295.0337)
		(size 0.7112)
		(drill 0.4064)
		(layers "F.Cu" "B.Cu")
		(net "GND")
	)
	(via
		(at 32.384746 -479.8187)
		(size 0.7112)
		(drill 0.4064)
		(layers "F.Cu" "B.Cu")
		(net "GND")
	)
	(via
		(at 224.662746 -504.5837)
		(size 0.7112)
		(drill 0.4064)
		(layers "F.Cu" "B.Cu")
		(net "GND")
	)
	(via
		(at 144.271746 -301.6377)
		(size 0.7112)
		(drill 0.4064)
		(layers "F.Cu" "B.Cu")
		(net "GND")
	)
	(via
		(at 174.065946 -394.1953)
		(size 0.7112)
		(drill 0.4064)
		(layers "F.Cu" "B.Cu")
		(net "GND")
	)
	(via
		(at 150.621746 -103.5177)
		(size 0.7112)
		(drill 0.4064)
		(layers "F.Cu" "B.Cu")
		(net "GND")
	)
	(via
		(at 183.768746 -166.3319)
		(size 0.7112)
		(drill 0.4064)
		(layers "F.Cu" "B.Cu")
		(net "GND")
	)
	(via
		(at 73.659746 -394.8811)
		(size 0.5588)
		(drill 0.3048)
		(layers "F.Cu" "B.Cu")
		(net "GND")
	)
	(via
		(at 55.371746 -399.9357)
		(size 0.7112)
		(drill 0.4064)
		(layers "F.Cu" "B.Cu")
		(net "GND")
	)
	(via
		(at 119.125746 -336.2833)
		(size 0.7112)
		(drill 0.4064)
		(layers "F.Cu" "B.Cu")
		(net "GND")
	)
	(via
		(at 84.607146 -249.7963)
		(size 0.7112)
		(drill 0.4064)
		(layers "F.Cu" "B.Cu")
		(net "GND")
	)
	(via
		(at 70.510146 -247.7135)
		(size 0.7112)
		(drill 0.4064)
		(layers "F.Cu" "B.Cu")
		(net "GND")
	)
	(via
		(at 185.800746 -145.3007)
		(size 0.7112)
		(drill 0.4064)
		(layers "F.Cu" "B.Cu")
		(net "GND")
	)
	(via
		(at 176.783746 -127.3937)
		(size 0.7112)
		(drill 0.4064)
		(layers "F.Cu" "B.Cu")
		(net "GND")
	)
	(via
		(at 230.860346 -414.0327)
		(size 0.7112)
		(drill 0.4064)
		(layers "F.Cu" "B.Cu")
		(net "GND")
	)
	(via
		(at 49.656746 -324.8787)
		(size 0.7112)
		(drill 0.4064)
		(layers "F.Cu" "B.Cu")
		(net "GND")
	)
	(via
		(at 162.813746 -461.1497)
		(size 0.7112)
		(drill 0.4064)
		(layers "F.Cu" "B.Cu")
		(net "GND")
	)
	(via
		(at 76.199746 -430.7967)
		(size 0.7112)
		(drill 0.4064)
		(layers "F.Cu" "B.Cu")
		(net "GND")
	)
	(via
		(at 144.525746 -504.7107)
		(size 0.7112)
		(drill 0.4064)
		(layers "F.Cu" "B.Cu")
		(net "GND")
	)
	(via
		(at 249.554746 -61.0997)
		(size 0.7112)
		(drill 0.4064)
		(layers "F.Cu" "B.Cu")
		(net "GND")
	)
	(via
		(at 186.689746 -265.4427)
		(size 0.7112)
		(drill 0.4064)
		(layers "F.Cu" "B.Cu")
		(net "GND")
	)
	(via
		(at 176.859946 -482.3079)
		(size 0.7112)
		(drill 0.4064)
		(layers "F.Cu" "B.Cu")
		(net "GND")
	)
	(via
		(at 171.449746 -35.6997)
		(size 0.7112)
		(drill 0.4064)
		(layers "F.Cu" "B.Cu")
		(net "GND")
	)
	(via
		(at 240.334546 -499.5291)
		(size 0.7112)
		(drill 0.4064)
		(layers "F.Cu" "B.Cu")
		(net "GND")
	)
	(via
		(at 160.019746 -259.0927)
		(size 0.7112)
		(drill 0.4064)
		(layers "F.Cu" "B.Cu")
		(net "GND")
	)
	(via
		(at 98.246946 -11.43)
		(size 0.5588)
		(drill 0.3048)
		(layers "F.Cu" "B.Cu")
		(net "GND")
	)
	(via
		(at 152.856946 -496.0239)
		(size 0.7112)
		(drill 0.4064)
		(layers "F.Cu" "B.Cu")
		(net "GND")
	)
	(via
		(at 147.522946 -418.1221)
		(size 0.7112)
		(drill 0.4064)
		(layers "F.Cu" "B.Cu")
		(net "GND")
	)
	(via
		(at 7.518146 -97.252536)
		(size 0.5588)
		(drill 0.3048)
		(layers "F.Cu" "B.Cu")
		(net "GND")
	)
	(via
		(at 250.062746 -99.8347)
		(size 0.7112)
		(drill 0.4064)
		(layers "F.Cu" "B.Cu")
		(net "GND")
	)
	(via
		(at 76.326746 -331.5589)
		(size 0.7112)
		(drill 0.4064)
		(layers "F.Cu" "B.Cu")
		(net "GND")
	)
	(via
		(at 225.043746 -5.3721)
		(size 0.7112)
		(drill 0.4064)
		(layers "F.Cu" "B.Cu")
		(net "GND")
	)
	(via
		(at 53.212746 -104.7877)
		(size 0.7112)
		(drill 0.4064)
		(layers "F.Cu" "B.Cu")
		(net "GND")
	)
	(via
		(at 221.487746 -386.19684)
		(size 0.5588)
		(drill 0.3048)
		(layers "F.Cu" "B.Cu")
		(net "GND")
	)
	(via
		(at 258.952746 -300.4947)
		(size 0.7112)
		(drill 0.4064)
		(layers "F.Cu" "B.Cu")
		(net "GND")
	)
	(via
		(at 28.320746 -478.1677)
		(size 0.7112)
		(drill 0.4064)
		(layers "F.Cu" "B.Cu")
		(net "GND")
	)
	(via
		(at 15.621 -504.825)
		(size 0.7112)
		(drill 0.4064)
		(layers "F.Cu" "B.Cu")
		(net "GND")
	)
	(via
		(at 28.320746 -476.8977)
		(size 0.7112)
		(drill 0.4064)
		(layers "F.Cu" "B.Cu")
		(net "GND")
	)
	(via
		(at 208.025746 -1.5367)
		(size 0.7112)
		(drill 0.4064)
		(layers "F.Cu" "B.Cu")
		(net "GND")
	)
	(via
		(at 221.513146 -322.1101)
		(size 0.7112)
		(drill 0.4064)
		(layers "F.Cu" "B.Cu")
		(net "GND")
	)
	(via
		(at 32.003746 -334.1497)
		(size 0.5588)
		(drill 0.3048)
		(layers "F.Cu" "B.Cu")
		(net "GND")
	)
	(via
		(at 54.990746 -267.4747)
		(size 0.7112)
		(drill 0.4064)
		(layers "F.Cu" "B.Cu")
		(net "GND")
	)
	(via
		(at 181.355746 -262.0137)
		(size 0.7112)
		(drill 0.4064)
		(layers "F.Cu" "B.Cu")
		(net "GND")
	)
	(via
		(at 16.128746 -136.7917)
		(size 0.5588)
		(drill 0.3048)
		(layers "F.Cu" "B.Cu")
		(net "GND")
	)
	(via
		(at 235.076746 -280.3017)
		(size 0.7112)
		(drill 0.4064)
		(layers "F.Cu" "B.Cu")
		(net "GND")
	)
	(via
		(at 64.007746 -300.8757)
		(size 0.7112)
		(drill 0.4064)
		(layers "F.Cu" "B.Cu")
		(net "GND")
	)
	(via
		(at 247.903746 -287.7947)
		(size 0.7112)
		(drill 0.4064)
		(layers "F.Cu" "B.Cu")
		(net "GND")
	)
	(via
		(at 222.182182 -268.171168)
		(size 0.5588)
		(drill 0.3048)
		(layers "F.Cu" "B.Cu")
		(net "GND")
	)
	(via
		(at 235.854494 -24.175974)
		(size 0.5588)
		(drill 0.3048)
		(layers "F.Cu" "B.Cu")
		(net "GND")
	)
	(via
		(at 51.409346 -381.1905)
		(size 0.7112)
		(drill 0.4064)
		(layers "F.Cu" "B.Cu")
		(net "GND")
	)
	(via
		(at 91.236546 -175.4251)
		(size 0.7112)
		(drill 0.4064)
		(layers "F.Cu" "B.Cu")
		(net "GND")
	)
	(via
		(at 221.335346 -307.5559)
		(size 0.7112)
		(drill 0.4064)
		(layers "F.Cu" "B.Cu")
		(net "GND")
	)
	(via
		(at 105.536746 -298.7167)
		(size 0.7112)
		(drill 0.4064)
		(layers "F.Cu" "B.Cu")
		(net "GND")
	)
	(via
		(at 219.481146 -427.6217)
		(size 0.7112)
		(drill 0.4064)
		(layers "F.Cu" "B.Cu")
		(net "GND")
	)
	(via
		(at 5.968746 -156.985462)
		(size 0.5588)
		(drill 0.3048)
		(layers "F.Cu" "B.Cu")
		(net "GND")
	)
	(via
		(at 179.704746 -196.3547)
		(size 0.7112)
		(drill 0.4064)
		(layers "F.Cu" "B.Cu")
		(net "GND")
	)
	(via
		(at 28.447746 -301.7647)
		(size 0.7112)
		(drill 0.4064)
		(layers "F.Cu" "B.Cu")
		(net "GND")
	)
	(via
		(at 117.347746 -250.2027)
		(size 0.7112)
		(drill 0.4064)
		(layers "F.Cu" "B.Cu")
		(net "GND")
	)
	(via
		(at 115.925346 -367.2713)
		(size 0.7112)
		(drill 0.4064)
		(layers "F.Cu" "B.Cu")
		(net "GND")
	)
	(via
		(at 107.314746 -88.4301)
		(size 0.7112)
		(drill 0.4064)
		(layers "F.Cu" "B.Cu")
		(net "GND")
	)
	(via
		(at 25.908 -340.614)
		(size 0.5588)
		(drill 0.3048)
		(layers "F.Cu" "B.Cu")
		(net "GND")
	)
	(via
		(at 146.303746 -479.5647)
		(size 0.7112)
		(drill 0.4064)
		(layers "F.Cu" "B.Cu")
		(net "GND")
	)
	(via
		(at 58.8772 -80.877156)
		(size 0.5588)
		(drill 0.3048)
		(layers "F.Cu" "B.Cu")
		(net "GND")
	)
	(via
		(at 228.675946 -476.7453)
		(size 0.7112)
		(drill 0.4064)
		(layers "F.Cu" "B.Cu")
		(net "GND")
	)
	(via
		(at 59.130946 -324.1421)
		(size 0.7112)
		(drill 0.4064)
		(layers "F.Cu" "B.Cu")
		(net "GND")
	)
	(via
		(at 42.366946 -377.8123)
		(size 0.7112)
		(drill 0.4064)
		(layers "F.Cu" "B.Cu")
		(net "GND")
	)
	(via
		(at 171.576746 -22.6187)
		(size 0.7112)
		(drill 0.4064)
		(layers "F.Cu" "B.Cu")
		(net "GND")
	)
	(via
		(at 227.990146 -492.4425)
		(size 0.7112)
		(drill 0.4064)
		(layers "F.Cu" "B.Cu")
		(net "GND")
	)
	(via
		(at 242.264946 -502.3993)
		(size 0.7112)
		(drill 0.4064)
		(layers "F.Cu" "B.Cu")
		(net "GND")
	)
	(via
		(at 219.7862 -395.6558)
		(size 0.7112)
		(drill 0.4064)
		(layers "F.Cu" "B.Cu")
		(net "GND")
	)
	(via
		(at 152.272746 -348.1197)
		(size 0.7112)
		(drill 0.4064)
		(layers "F.Cu" "B.Cu")
		(net "GND")
	)
	(via
		(at 127.761746 -89.8017)
		(size 0.7112)
		(drill 0.4064)
		(layers "F.Cu" "B.Cu")
		(net "GND")
	)
	(via
		(at 187.578746 -137.0457)
		(size 0.7112)
		(drill 0.4064)
		(layers "F.Cu" "B.Cu")
		(net "GND")
	)
	(via
		(at 164.464746 -166.8907)
		(size 0.7112)
		(drill 0.4064)
		(layers "F.Cu" "B.Cu")
		(net "GND")
	)
	(via
		(at 255.523746 -153.5049)
		(size 0.7112)
		(drill 0.4064)
		(layers "F.Cu" "B.Cu")
		(net "GND")
	)
	(via
		(at 173.608746 -66.8147)
		(size 0.7112)
		(drill 0.4064)
		(layers "F.Cu" "B.Cu")
		(net "GND")
	)
	(via
		(at 123.773946 -182.1053)
		(size 0.7112)
		(drill 0.4064)
		(layers "F.Cu" "B.Cu")
		(net "GND")
	)
	(via
		(at 76.174346 -95.6691)
		(size 0.7112)
		(drill 0.4064)
		(layers "F.Cu" "B.Cu")
		(net "GND")
	)
	(via
		(at 118.871746 -430.7967)
		(size 0.7112)
		(drill 0.4064)
		(layers "F.Cu" "B.Cu")
		(net "GND")
	)
	(via
		(at 34.162746 -123.9647)
		(size 0.7112)
		(drill 0.4064)
		(layers "F.Cu" "B.Cu")
		(net "GND")
	)
	(via
		(at 217.499946 -191.3001)
		(size 0.7112)
		(drill 0.4064)
		(layers "F.Cu" "B.Cu")
		(net "GND")
	)
	(via
		(at 179.222146 -480.5299)
		(size 0.7112)
		(drill 0.4064)
		(layers "F.Cu" "B.Cu")
		(net "GND")
	)
	(via
		(at 157.987746 -109.8677)
		(size 0.7112)
		(drill 0.4064)
		(layers "F.Cu" "B.Cu")
		(net "GND")
	)
	(via
		(at 255.345946 -82.0293)
		(size 0.7112)
		(drill 0.4064)
		(layers "F.Cu" "B.Cu")
		(net "GND")
	)
	(via
		(at 120.395746 -340.9823)
		(size 0.7112)
		(drill 0.4064)
		(layers "F.Cu" "B.Cu")
		(net "GND")
	)
	(via
		(at 260.1722 -353.9744)
		(size 0.7112)
		(drill 0.4064)
		(layers "F.Cu" "B.Cu")
		(net "GND")
	)
	(via
		(at 62.1538 -477.1898)
		(size 0.7112)
		(drill 0.4064)
		(layers "F.Cu" "B.Cu")
		(net "GND")
	)
	(via
		(at 172.211746 -342.2777)
		(size 0.7112)
		(drill 0.4064)
		(layers "F.Cu" "B.Cu")
		(net "GND")
	)
	(via
		(at 159.384746 -471.4113)
		(size 0.7112)
		(drill 0.4064)
		(layers "F.Cu" "B.Cu")
		(net "GND")
	)
	(via
		(at 143.763746 -313.4487)
		(size 0.7112)
		(drill 0.4064)
		(layers "F.Cu" "B.Cu")
		(net "GND")
	)
	(via
		(at 74.650346 -214.3379)
		(size 0.7112)
		(drill 0.4064)
		(layers "F.Cu" "B.Cu")
		(net "GND")
	)
	(via
		(at 195.935346 -374.5357)
		(size 0.7112)
		(drill 0.4064)
		(layers "F.Cu" "B.Cu")
		(net "GND")
	)
	(via
		(at 216.026746 -322.0847)
		(size 0.7112)
		(drill 0.4064)
		(layers "F.Cu" "B.Cu")
		(net "GND")
	)
	(via
		(at 112.140746 -363.6137)
		(size 0.7112)
		(drill 0.4064)
		(layers "F.Cu" "B.Cu")
		(net "GND")
	)
	(via
		(at 159.892746 -220.6117)
		(size 0.7112)
		(drill 0.4064)
		(layers "F.Cu" "B.Cu")
		(net "GND")
	)
	(via
		(at 84.327746 -167.9067)
		(size 0.7112)
		(drill 0.4064)
		(layers "F.Cu" "B.Cu")
		(net "GND")
	)
	(via
		(at 258.571746 -492.0107)
		(size 0.7112)
		(drill 0.4064)
		(layers "F.Cu" "B.Cu")
		(net "GND")
	)
	(via
		(at 241.604546 -304.6095)
		(size 0.7112)
		(drill 0.4064)
		(layers "F.Cu" "B.Cu")
		(net "GND")
	)
	(via
		(at 131.190746 -1.6637)
		(size 0.7112)
		(drill 0.4064)
		(layers "F.Cu" "B.Cu")
		(net "GND")
	)
	(via
		(at 135.254746 -497.4717)
		(size 0.7112)
		(drill 0.4064)
		(layers "F.Cu" "B.Cu")
		(net "GND")
	)
	(via
		(at 168.655746 -222.6437)
		(size 0.7112)
		(drill 0.4064)
		(layers "F.Cu" "B.Cu")
		(net "GND")
	)
	(via
		(at 258.952746 -304.4317)
		(size 0.7112)
		(drill 0.4064)
		(layers "F.Cu" "B.Cu")
		(net "GND")
	)
	(via
		(at 130.936746 -72.1487)
		(size 0.7112)
		(drill 0.4064)
		(layers "F.Cu" "B.Cu")
		(net "GND")
	)
	(via
		(at 218.642946 -345.16695)
		(size 0.5588)
		(drill 0.3048)
		(layers "F.Cu" "B.Cu")
		(net "GND")
	)
	(via
		(at 251.333508 -418.084)
		(size 0.5588)
		(drill 0.3048)
		(layers "F.Cu" "B.Cu")
		(net "GND")
	)
	(via
		(at 90.169746 -71.7677)
		(size 0.7112)
		(drill 0.4064)
		(layers "F.Cu" "B.Cu")
		(net "GND")
	)
	(via
		(at 53.339746 -108.2421)
		(size 0.7112)
		(drill 0.4064)
		(layers "F.Cu" "B.Cu")
		(net "GND")
	)
	(via
		(at 172.414946 -501.8405)
		(size 0.7112)
		(drill 0.4064)
		(layers "F.Cu" "B.Cu")
		(net "GND")
	)
	(via
		(at 91.287346 -170.0403)
		(size 0.7112)
		(drill 0.4064)
		(layers "F.Cu" "B.Cu")
		(net "GND")
	)
	(via
		(at 87.350346 -445.1731)
		(size 0.7112)
		(drill 0.4064)
		(layers "F.Cu" "B.Cu")
		(net "GND")
	)
	(via
		(at 255.930146 -461.8863)
		(size 0.7112)
		(drill 0.4064)
		(layers "F.Cu" "B.Cu")
		(net "GND")
	)
	(via
		(at 27.6606 -149.2504)
		(size 0.7112)
		(drill 0.4064)
		(layers "F.Cu" "B.Cu")
		(net "GND")
	)
	(via
		(at 52.308252 -18.422112)
		(size 0.5588)
		(drill 0.3048)
		(layers "F.Cu" "B.Cu")
		(net "GND")
	)
	(via
		(at 42.366946 -357.9749)
		(size 0.7112)
		(drill 0.4064)
		(layers "F.Cu" "B.Cu")
		(net "GND")
	)
	(via
		(at 206.882746 -144.6657)
		(size 0.7112)
		(drill 0.4064)
		(layers "F.Cu" "B.Cu")
		(net "GND")
	)
	(via
		(at 130.555746 -265.6967)
		(size 0.7112)
		(drill 0.4064)
		(layers "F.Cu" "B.Cu")
		(net "GND")
	)
	(via
		(at 114.096546 -401.0787)
		(size 0.7112)
		(drill 0.4064)
		(layers "F.Cu" "B.Cu")
		(net "GND")
	)
	(via
		(at 171.449746 -425.8437)
		(size 0.7112)
		(drill 0.4064)
		(layers "F.Cu" "B.Cu")
		(net "GND")
	)
	(via
		(at 13.334746 -33.1597)
		(size 0.7112)
		(drill 0.4064)
		(layers "F.Cu" "B.Cu")
		(net "GND")
	)
	(via
		(at 55.372 -410.0322)
		(size 0.7112)
		(drill 0.4064)
		(layers "F.Cu" "B.Cu")
		(net "GND")
	)
	(via
		(at 156.336746 -500.0117)
		(size 0.7112)
		(drill 0.4064)
		(layers "F.Cu" "B.Cu")
		(net "GND")
	)
	(via
		(at 112.420146 -230.0351)
		(size 0.7112)
		(drill 0.4064)
		(layers "F.Cu" "B.Cu")
		(net "GND")
	)
	(via
		(at 75.717146 -248.2215)
		(size 0.7112)
		(drill 0.4064)
		(layers "F.Cu" "B.Cu")
		(net "GND")
	)
	(via
		(at 194.563746 -484.6447)
		(size 0.7112)
		(drill 0.4064)
		(layers "F.Cu" "B.Cu")
		(net "GND")
	)
	(via
		(at 34.163 -281.4574)
		(size 0.7112)
		(drill 0.4064)
		(layers "F.Cu" "B.Cu")
		(net "GND")
	)
	(via
		(at 105.917746 -41.6687)
		(size 0.7112)
		(drill 0.4064)
		(layers "F.Cu" "B.Cu")
		(net "GND")
	)
	(via
		(at 258.825746 -295.5417)
		(size 0.7112)
		(drill 0.4064)
		(layers "F.Cu" "B.Cu")
		(net "GND")
	)
	(via
		(at 29.21 -504.698)
		(size 0.7112)
		(drill 0.4064)
		(layers "F.Cu" "B.Cu")
		(net "GND")
	)
	(via
		(at 10.159746 -91.3257)
		(size 0.7112)
		(drill 0.4064)
		(layers "F.Cu" "B.Cu")
		(net "GND")
	)
	(via
		(at 246.8118 -407.5938)
		(size 0.7112)
		(drill 0.4064)
		(layers "F.Cu" "B.Cu")
		(net "GND")
	)
	(via
		(at 68.655946 -474.2815)
		(size 0.7112)
		(drill 0.4064)
		(layers "F.Cu" "B.Cu")
		(net "GND")
	)
	(via
		(at 160.197546 -475.6785)
		(size 0.7112)
		(drill 0.4064)
		(layers "F.Cu" "B.Cu")
		(net "GND")
	)
	(via
		(at 197.484746 -162.0647)
		(size 0.7112)
		(drill 0.4064)
		(layers "F.Cu" "B.Cu")
		(net "GND")
	)
	(via
		(at 5.536946 -325.8185)
		(size 0.7112)
		(drill 0.4064)
		(layers "F.Cu" "B.Cu")
		(net "GND")
	)
	(via
		(at 97.027746 -12.7381)
		(size 0.5588)
		(drill 0.3048)
		(layers "F.Cu" "B.Cu")
		(net "GND")
	)
	(via
		(at 155.549346 -270.9291)
		(size 0.7112)
		(drill 0.4064)
		(layers "F.Cu" "B.Cu")
		(net "GND")
	)
	(via
		(at 19.430746 -382.7907)
		(size 0.7112)
		(drill 0.4064)
		(layers "F.Cu" "B.Cu")
		(net "GND")
	)
	(via
		(at 62.5348 -16.7132)
		(size 0.7112)
		(drill 0.4064)
		(layers "F.Cu" "B.Cu")
		(net "GND")
	)
	(via
		(at 82.244946 -218.4019)
		(size 0.7112)
		(drill 0.4064)
		(layers "F.Cu" "B.Cu")
		(net "GND")
	)
	(via
		(at 89.407746 -471.2843)
		(size 0.7112)
		(drill 0.4064)
		(layers "F.Cu" "B.Cu")
		(net "GND")
	)
	(via
		(at 184.987946 -479.7679)
		(size 0.7112)
		(drill 0.4064)
		(layers "F.Cu" "B.Cu")
		(net "GND")
	)
	(via
		(at 65.024 -287.782)
		(size 0.5588)
		(drill 0.3048)
		(layers "F.Cu" "B.Cu")
		(net "GND")
	)
	(via
		(at 71.373746 -146.4437)
		(size 0.7112)
		(drill 0.4064)
		(layers "F.Cu" "B.Cu")
		(net "GND")
	)
	(via
		(at 244.1956 -388.2898)
		(size 0.7112)
		(drill 0.4064)
		(layers "F.Cu" "B.Cu")
		(net "GND")
	)
	(via
		(at 89.382346 -398.9959)
		(size 0.7112)
		(drill 0.4064)
		(layers "F.Cu" "B.Cu")
		(net "GND")
	)
	(via
		(at 192.404746 -189.316868)
		(size 0.5588)
		(drill 0.3048)
		(layers "F.Cu" "B.Cu")
		(net "GND")
	)
	(via
		(at 65.404746 -130.1877)
		(size 0.7112)
		(drill 0.4064)
		(layers "F.Cu" "B.Cu")
		(net "GND")
	)
	(via
		(at 217.042746 -94.7547)
		(size 0.7112)
		(drill 0.4064)
		(layers "F.Cu" "B.Cu")
		(net "GND")
	)
	(via
		(at 19.484594 -240.814606)
		(size 0.7112)
		(drill 0.4064)
		(layers "F.Cu" "B.Cu")
		(net "GND")
	)
	(via
		(at 178.028346 -368.3635)
		(size 0.7112)
		(drill 0.4064)
		(layers "F.Cu" "B.Cu")
		(net "GND")
	)
	(via
		(at 118.998746 -434.9877)
		(size 0.7112)
		(drill 0.4064)
		(layers "F.Cu" "B.Cu")
		(net "GND")
	)
	(via
		(at 218.947746 -386.7277)
		(size 0.7112)
		(drill 0.4064)
		(layers "F.Cu" "B.Cu")
		(net "GND")
	)
	(via
		(at 194.195446 -289.179)
		(size 0.5588)
		(drill 0.3048)
		(layers "F.Cu" "B.Cu")
		(net "GND")
	)
	(via
		(at 80.518 -4.3942)
		(size 0.5588)
		(drill 0.3048)
		(layers "F.Cu" "B.Cu")
		(net "GND")
	)
	(via
		(at 213.232746 -386.9817)
		(size 0.7112)
		(drill 0.4064)
		(layers "F.Cu" "B.Cu")
		(net "GND")
	)
	(via
		(at 134.568946 -394.9827)
		(size 0.7112)
		(drill 0.4064)
		(layers "F.Cu" "B.Cu")
		(net "GND")
	)
	(via
		(at 30.606746 -321.1957)
		(size 0.7112)
		(drill 0.4064)
		(layers "F.Cu" "B.Cu")
		(net "GND")
	)
	(via
		(at 142.900146 -476.1103)
		(size 0.7112)
		(drill 0.4064)
		(layers "F.Cu" "B.Cu")
		(net "GND")
	)
	(via
		(at 150.240746 -471.4113)
		(size 0.7112)
		(drill 0.4064)
		(layers "F.Cu" "B.Cu")
		(net "GND")
	)
	(via
		(at 241.350546 -294.4495)
		(size 0.7112)
		(drill 0.4064)
		(layers "F.Cu" "B.Cu")
		(net "GND")
	)
	(via
		(at 145.668746 -170.9547)
		(size 0.7112)
		(drill 0.4064)
		(layers "F.Cu" "B.Cu")
		(net "GND")
	)
	(via
		(at 76.377546 -301.0281)
		(size 0.7112)
		(drill 0.4064)
		(layers "F.Cu" "B.Cu")
		(net "GND")
	)
	(via
		(at 160.019746 -262.7757)
		(size 0.7112)
		(drill 0.4064)
		(layers "F.Cu" "B.Cu")
		(net "GND")
	)
	(via
		(at 154.177746 -443.3697)
		(size 0.7112)
		(drill 0.4064)
		(layers "F.Cu" "B.Cu")
		(net "GND")
	)
	(via
		(at 136.270746 -71.8947)
		(size 0.7112)
		(drill 0.4064)
		(layers "F.Cu" "B.Cu")
		(net "GND")
	)
	(via
		(at 62.331346 -209.1817)
		(size 0.7112)
		(drill 0.4064)
		(layers "F.Cu" "B.Cu")
		(net "GND")
	)
	(via
		(at 259.206746 -99.4537)
		(size 0.7112)
		(drill 0.4064)
		(layers "F.Cu" "B.Cu")
		(net "GND")
	)
	(via
		(at 237.2868 -455.549)
		(size 0.7112)
		(drill 0.4064)
		(layers "F.Cu" "B.Cu")
		(net "GND")
	)
	(via
		(at 159.892746 -272.1737)
		(size 0.7112)
		(drill 0.4064)
		(layers "F.Cu" "B.Cu")
		(net "GND")
	)
	(via
		(at 64.642746 -250.0757)
		(size 0.7112)
		(drill 0.4064)
		(layers "F.Cu" "B.Cu")
		(net "GND")
	)
	(via
		(at 218.439746 -284.1117)
		(size 0.7112)
		(drill 0.4064)
		(layers "F.Cu" "B.Cu")
		(net "GND")
	)
	(via
		(at 245.5164 -396.1638)
		(size 0.7112)
		(drill 0.4064)
		(layers "F.Cu" "B.Cu")
		(net "GND")
	)
	(via
		(at 13.51534 -178.177444)
		(size 0.7112)
		(drill 0.4064)
		(layers "F.Cu" "B.Cu")
		(net "GND")
	)
	(via
		(at 105.917746 -6.3627)
		(size 0.7112)
		(drill 0.4064)
		(layers "F.Cu" "B.Cu")
		(net "GND")
	)
	(via
		(at 156.895546 -388.7089)
		(size 0.7112)
		(drill 0.4064)
		(layers "F.Cu" "B.Cu")
		(net "GND")
	)
	(via
		(at 44.246546 -213.6267)
		(size 0.5588)
		(drill 0.3048)
		(layers "F.Cu" "B.Cu")
		(net "GND")
	)
	(via
		(at 259.206746 -187.3377)
		(size 0.7112)
		(drill 0.4064)
		(layers "F.Cu" "B.Cu")
		(net "GND")
	)
	(via
		(at 171.170346 -499.5799)
		(size 0.7112)
		(drill 0.4064)
		(layers "F.Cu" "B.Cu")
		(net "GND")
	)
	(via
		(at 114.934746 -143.5227)
		(size 0.7112)
		(drill 0.4064)
		(layers "F.Cu" "B.Cu")
		(net "GND")
	)
	(via
		(at 146.049746 -496.2017)
		(size 0.7112)
		(drill 0.4064)
		(layers "F.Cu" "B.Cu")
		(net "GND")
	)
	(via
		(at 155.828746 -220.4847)
		(size 0.7112)
		(drill 0.4064)
		(layers "F.Cu" "B.Cu")
		(net "GND")
	)
	(via
		(at 2.158746 -273.8247)
		(size 0.7112)
		(drill 0.4064)
		(layers "F.Cu" "B.Cu")
		(net "GND")
	)
	(via
		(at 241.502946 -175.5521)
		(size 0.7112)
		(drill 0.4064)
		(layers "F.Cu" "B.Cu")
		(net "GND")
	)
	(via
		(at 84.670646 -327.3806)
		(size 0.7112)
		(drill 0.4064)
		(layers "F.Cu" "B.Cu")
		(net "GND")
	)
	(via
		(at 146.456146 -132.6769)
		(size 0.7112)
		(drill 0.4064)
		(layers "F.Cu" "B.Cu")
		(net "GND")
	)
	(via
		(at 255.472946 -97.1423)
		(size 0.7112)
		(drill 0.4064)
		(layers "F.Cu" "B.Cu")
		(net "GND")
	)
	(via
		(at 125.348746 -224.5487)
		(size 0.7112)
		(drill 0.4064)
		(layers "F.Cu" "B.Cu")
		(net "GND")
	)
	(via
		(at 83.006946 -502.1707)
		(size 0.7112)
		(drill 0.4064)
		(layers "F.Cu" "B.Cu")
		(net "GND")
	)
	(via
		(at 55.244746 -352.4123)
		(size 0.7112)
		(drill 0.4064)
		(layers "F.Cu" "B.Cu")
		(net "GND")
	)
	(via
		(at 156.336746 -497.7257)
		(size 0.7112)
		(drill 0.4064)
		(layers "F.Cu" "B.Cu")
		(net "GND")
	)
	(via
		(at 220.649546 -503.7455)
		(size 0.7112)
		(drill 0.4064)
		(layers "F.Cu" "B.Cu")
		(net "GND")
	)
	(via
		(at 164.464746 -170.5737)
		(size 0.7112)
		(drill 0.4064)
		(layers "F.Cu" "B.Cu")
		(net "GND")
	)
	(via
		(at 66.674746 -252.9459)
		(size 0.7112)
		(drill 0.4064)
		(layers "F.Cu" "B.Cu")
		(net "GND")
	)
	(via
		(at 161.391346 -95.5675)
		(size 0.7112)
		(drill 0.4064)
		(layers "F.Cu" "B.Cu")
		(net "GND")
	)
	(via
		(at 181.152546 -120.6373)
		(size 0.7112)
		(drill 0.4064)
		(layers "F.Cu" "B.Cu")
		(net "GND")
	)
	(via
		(at 132.816346 -11.5189)
		(size 0.7112)
		(drill 0.4064)
		(layers "F.Cu" "B.Cu")
		(net "GND")
	)
	(via
		(at 168.909746 -199.6567)
		(size 0.7112)
		(drill 0.4064)
		(layers "F.Cu" "B.Cu")
		(net "GND")
	)
	(via
		(at 163.524946 -501.9675)
		(size 0.7112)
		(drill 0.4064)
		(layers "F.Cu" "B.Cu")
		(net "GND")
	)
	(via
		(at 240.029746 -210.0707)
		(size 0.7112)
		(drill 0.4064)
		(layers "F.Cu" "B.Cu")
		(net "GND")
	)
	(via
		(at 163.855146 -162.3441)
		(size 0.7112)
		(drill 0.4064)
		(layers "F.Cu" "B.Cu")
		(net "GND")
	)
	(via
		(at 246.9642 -402.717)
		(size 0.7112)
		(drill 0.4064)
		(layers "F.Cu" "B.Cu")
		(net "GND")
	)
	(via
		(at 44.830746 -35.5727)
		(size 0.7112)
		(drill 0.4064)
		(layers "F.Cu" "B.Cu")
		(net "GND")
	)
	(via
		(at 43.9674 -122.7074)
		(size 0.5588)
		(drill 0.3048)
		(layers "F.Cu" "B.Cu")
		(net "GND")
	)
	(via
		(at 190.601346 -115.2017)
		(size 0.7112)
		(drill 0.4064)
		(layers "F.Cu" "B.Cu")
		(net "GND")
	)
	(via
		(at 52.450746 -154.6987)
		(size 0.7112)
		(drill 0.4064)
		(layers "F.Cu" "B.Cu")
		(net "GND")
	)
	(via
		(at 220.141546 -449.8213)
		(size 0.7112)
		(drill 0.4064)
		(layers "F.Cu" "B.Cu")
		(net "GND")
	)
	(via
		(at 110.057946 -488.3277)
		(size 0.7112)
		(drill 0.4064)
		(layers "F.Cu" "B.Cu")
		(net "GND")
	)
	(via
		(at 146.887946 -232.3211)
		(size 0.7112)
		(drill 0.4064)
		(layers "F.Cu" "B.Cu")
		(net "GND")
	)
	(via
		(at 253.771146 -304.7873)
		(size 0.7112)
		(drill 0.4064)
		(layers "F.Cu" "B.Cu")
		(net "GND")
	)
	(via
		(at 241.604546 -307.6575)
		(size 0.7112)
		(drill 0.4064)
		(layers "F.Cu" "B.Cu")
		(net "GND")
	)
	(via
		(at 208.470246 -41.6179)
		(size 0.5588)
		(drill 0.3048)
		(layers "F.Cu" "B.Cu")
		(net "GND")
	)
	(via
		(at 7.314946 -487.44124)
		(size 0.5588)
		(drill 0.3048)
		(layers "F.Cu" "B.Cu")
		(net "GND")
	)
	(via
		(at 23.5966 -16.796512)
		(size 0.5588)
		(drill 0.3048)
		(layers "F.Cu" "B.Cu")
		(net "GND")
	)
	(via
		(at 137.540746 -41.6687)
		(size 0.7112)
		(drill 0.4064)
		(layers "F.Cu" "B.Cu")
		(net "GND")
	)
	(via
		(at 118.871746 -428.5107)
		(size 0.7112)
		(drill 0.4064)
		(layers "F.Cu" "B.Cu")
		(net "GND")
	)
	(via
		(at 83.768946 -300.4185)
		(size 0.7112)
		(drill 0.4064)
		(layers "F.Cu" "B.Cu")
		(net "GND")
	)
	(via
		(at 184.276746 -312.8391)
		(size 0.7112)
		(drill 0.4064)
		(layers "F.Cu" "B.Cu")
		(net "GND")
	)
	(via
		(at 98.932746 -483.6287)
		(size 0.7112)
		(drill 0.4064)
		(layers "F.Cu" "B.Cu")
		(net "GND")
	)
	(via
		(at 218.265756 -480.40671)
		(size 0.5588)
		(drill 0.3048)
		(layers "F.Cu" "B.Cu")
		(net "GND")
	)
	(via
		(at 172.592746 -504.7107)
		(size 0.7112)
		(drill 0.4064)
		(layers "F.Cu" "B.Cu")
		(net "GND")
	)
	(via
		(at 234.822746 -391.5537)
		(size 0.7112)
		(drill 0.4064)
		(layers "F.Cu" "B.Cu")
		(net "GND")
	)
	(via
		(at 95.021146 -394.8557)
		(size 0.7112)
		(drill 0.4064)
		(layers "F.Cu" "B.Cu")
		(net "GND")
	)
	(via
		(at 79.121 -334.3402)
		(size 0.7112)
		(drill 0.4064)
		(layers "F.Cu" "B.Cu")
		(net "GND")
	)
	(via
		(at 185.419746 -223.9899)
		(size 0.7112)
		(drill 0.4064)
		(layers "F.Cu" "B.Cu")
		(net "GND")
	)
	(via
		(at 215.8746 -407.6954)
		(size 0.7112)
		(drill 0.4064)
		(layers "F.Cu" "B.Cu")
		(net "GND")
	)
	(via
		(at 52.196746 -500.0371)
		(size 0.7112)
		(drill 0.4064)
		(layers "F.Cu" "B.Cu")
		(net "GND")
	)
	(via
		(at 5.943346 -94.978474)
		(size 0.5588)
		(drill 0.3048)
		(layers "F.Cu" "B.Cu")
		(net "GND")
	)
	(via
		(at 127.228346 -364.3249)
		(size 0.7112)
		(drill 0.4064)
		(layers "F.Cu" "B.Cu")
		(net "GND")
	)
	(via
		(at 252.729746 -194.3227)
		(size 0.7112)
		(drill 0.4064)
		(layers "F.Cu" "B.Cu")
		(net "GND")
	)
	(via
		(at 259.587746 -141.8717)
		(size 0.7112)
		(drill 0.4064)
		(layers "F.Cu" "B.Cu")
		(net "GND")
	)
	(via
		(at 188.239146 -380.5301)
		(size 0.7112)
		(drill 0.4064)
		(layers "F.Cu" "B.Cu")
		(net "GND")
	)
	(via
		(at 51.688746 -63.6397)
		(size 0.7112)
		(drill 0.4064)
		(layers "F.Cu" "B.Cu")
		(net "GND")
	)
	(via
		(at 32.130746 -321.1957)
		(size 0.7112)
		(drill 0.4064)
		(layers "F.Cu" "B.Cu")
		(net "GND")
	)
	(via
		(at 226.7458 -441.071)
		(size 0.7112)
		(drill 0.4064)
		(layers "F.Cu" "B.Cu")
		(net "GND")
	)
	(via
		(at 79.6544 -353.3902)
		(size 0.7112)
		(drill 0.4064)
		(layers "F.Cu" "B.Cu")
		(net "GND")
	)
	(via
		(at 159.638746 -86.2457)
		(size 0.7112)
		(drill 0.4064)
		(layers "F.Cu" "B.Cu")
		(net "GND")
	)
	(via
		(at 81.279746 -271.0053)
		(size 0.7112)
		(drill 0.4064)
		(layers "F.Cu" "B.Cu")
		(net "GND")
	)
	(via
		(at 135.762746 -166.2557)
		(size 0.7112)
		(drill 0.4064)
		(layers "F.Cu" "B.Cu")
		(net "GND")
	)
	(via
		(at 39.877746 -355.0285)
		(size 0.7112)
		(drill 0.4064)
		(layers "F.Cu" "B.Cu")
		(net "GND")
	)
	(via
		(at 183.768746 -328.3331)
		(size 0.7112)
		(drill 0.4064)
		(layers "F.Cu" "B.Cu")
		(net "GND")
	)
	(via
		(at 197.967346 -471.3859)
		(size 0.7112)
		(drill 0.4064)
		(layers "F.Cu" "B.Cu")
		(net "GND")
	)
	(via
		(at 2.158746 -230.3907)
		(size 0.7112)
		(drill 0.4064)
		(layers "F.Cu" "B.Cu")
		(net "GND")
	)
	(via
		(at 188.099446 -459.837536)
		(size 0.7112)
		(drill 0.4064)
		(layers "F.Cu" "B.Cu")
		(net "GND")
	)
	(via
		(at 165.074346 -39.9669)
		(size 0.7112)
		(drill 0.4064)
		(layers "F.Cu" "B.Cu")
		(net "GND")
	)
	(via
		(at 195.833746 -381.0127)
		(size 0.7112)
		(drill 0.4064)
		(layers "F.Cu" "B.Cu")
		(net "GND")
	)
	(via
		(at 221.433644 -59.416696)
		(size 0.7112)
		(drill 0.4064)
		(layers "F.Cu" "B.Cu")
		(net "GND")
	)
	(via
		(at 18.922746 -168.1607)
		(size 0.5588)
		(drill 0.3048)
		(layers "F.Cu" "B.Cu")
		(net "GND")
	)
	(via
		(at 84.3788 -23.9268)
		(size 0.7112)
		(drill 0.4064)
		(layers "F.Cu" "B.Cu")
		(net "GND")
	)
	(via
		(at 216.153746 -239.6617)
		(size 0.7112)
		(drill 0.4064)
		(layers "F.Cu" "B.Cu")
		(net "GND")
	)
	(via
		(at 41.274746 -259.9817)
		(size 0.7112)
		(drill 0.4064)
		(layers "F.Cu" "B.Cu")
		(net "GND")
	)
	(via
		(at 126.999746 -6.4897)
		(size 0.7112)
		(drill 0.4064)
		(layers "F.Cu" "B.Cu")
		(net "GND")
	)
	(via
		(at 65.785746 -256.9337)
		(size 0.7112)
		(drill 0.4064)
		(layers "F.Cu" "B.Cu")
		(net "GND")
	)
	(via
		(at 247.395746 -504.5837)
		(size 0.7112)
		(drill 0.4064)
		(layers "F.Cu" "B.Cu")
		(net "GND")
	)
	(via
		(at 82.968846 -311.8739)
		(size 0.7112)
		(drill 0.4064)
		(layers "F.Cu" "B.Cu")
		(net "GND")
	)
	(via
		(at 7.574026 -161.277554)
		(size 0.5588)
		(drill 0.3048)
		(layers "F.Cu" "B.Cu")
		(net "GND")
	)
	(via
		(at 108.483146 -373.1641)
		(size 0.7112)
		(drill 0.4064)
		(layers "F.Cu" "B.Cu")
		(net "GND")
	)
	(via
		(at 212.343746 -202.9587)
		(size 0.7112)
		(drill 0.4064)
		(layers "F.Cu" "B.Cu")
		(net "GND")
	)
	(via
		(at 185.978546 -477.2025)
		(size 0.7112)
		(drill 0.4064)
		(layers "F.Cu" "B.Cu")
		(net "GND")
	)
	(via
		(at 121.487946 -372.0719)
		(size 0.7112)
		(drill 0.4064)
		(layers "F.Cu" "B.Cu")
		(net "GND")
	)
	(via
		(at 234.822746 -386.7277)
		(size 0.7112)
		(drill 0.4064)
		(layers "F.Cu" "B.Cu")
		(net "GND")
	)
	(via
		(at 203.453746 -255.4097)
		(size 0.7112)
		(drill 0.4064)
		(layers "F.Cu" "B.Cu")
		(net "GND")
	)
	(via
		(at 145.541746 -68.4657)
		(size 0.7112)
		(drill 0.4064)
		(layers "F.Cu" "B.Cu")
		(net "GND")
	)
	(via
		(at 213.740746 -416.2933)
		(size 0.7112)
		(drill 0.4064)
		(layers "F.Cu" "B.Cu")
		(net "GND")
	)
	(via
		(at 156.641546 -240.8555)
		(size 0.7112)
		(drill 0.4064)
		(layers "F.Cu" "B.Cu")
		(net "GND")
	)
	(via
		(at 118.871746 -423.6847)
		(size 0.7112)
		(drill 0.4064)
		(layers "F.Cu" "B.Cu")
		(net "GND")
	)
	(via
		(at 42.544746 -37.9857)
		(size 0.7112)
		(drill 0.4064)
		(layers "F.Cu" "B.Cu")
		(net "GND")
	)
	(via
		(at 93.547946 -98.1329)
		(size 0.7112)
		(drill 0.4064)
		(layers "F.Cu" "B.Cu")
		(net "GND")
	)
	(via
		(at 75.463146 -440.3979)
		(size 0.7112)
		(drill 0.4064)
		(layers "F.Cu" "B.Cu")
		(net "GND")
	)
	(via
		(at 194.208146 -166.5605)
		(size 0.7112)
		(drill 0.4064)
		(layers "F.Cu" "B.Cu")
		(net "GND")
	)
	(via
		(at 174.116746 -499.8847)
		(size 0.7112)
		(drill 0.4064)
		(layers "F.Cu" "B.Cu")
		(net "GND")
	)
	(via
		(at 246.9388 -405.9936)
		(size 0.7112)
		(drill 0.4064)
		(layers "F.Cu" "B.Cu")
		(net "GND")
	)
	(via
		(at 221.487746 -278.116792)
		(size 0.5588)
		(drill 0.3048)
		(layers "F.Cu" "B.Cu")
		(net "GND")
	)
	(via
		(at 6.8072 -366.7252)
		(size 0.5588)
		(drill 0.3048)
		(layers "F.Cu" "B.Cu")
		(net "GND")
	)
	(via
		(at 247.776746 -297.5737)
		(size 0.7112)
		(drill 0.4064)
		(layers "F.Cu" "B.Cu")
		(net "GND")
	)
	(via
		(at 91.541346 -156.3497)
		(size 0.7112)
		(drill 0.4064)
		(layers "F.Cu" "B.Cu")
		(net "GND")
	)
	(via
		(at 223.367346 -501.5357)
		(size 0.7112)
		(drill 0.4064)
		(layers "F.Cu" "B.Cu")
		(net "GND")
	)
	(via
		(at 142.646146 -495.0333)
		(size 0.7112)
		(drill 0.4064)
		(layers "F.Cu" "B.Cu")
		(net "GND")
	)
	(via
		(at 57.0992 -474.218)
		(size 0.7112)
		(drill 0.4064)
		(layers "F.Cu" "B.Cu")
		(net "GND")
	)
	(via
		(at 97.357946 -78.8035)
		(size 0.7112)
		(drill 0.4064)
		(layers "F.Cu" "B.Cu")
		(net "GND")
	)
	(via
		(at 145.6436 -400.7104)
		(size 0.7112)
		(drill 0.4064)
		(layers "F.Cu" "B.Cu")
		(net "GND")
	)
	(via
		(at 258.444746 -496.4557)
		(size 0.7112)
		(drill 0.4064)
		(layers "F.Cu" "B.Cu")
		(net "GND")
	)
	(via
		(at 113.537746 -484.6447)
		(size 0.7112)
		(drill 0.4064)
		(layers "F.Cu" "B.Cu")
		(net "GND")
	)
	(via
		(at 37.988748 -334.260698)
		(size 0.5588)
		(drill 0.3048)
		(layers "F.Cu" "B.Cu")
		(net "GND")
	)
	(via
		(at 52.755546 -339.8393)
		(size 0.7112)
		(drill 0.4064)
		(layers "F.Cu" "B.Cu")
		(net "GND")
	)
	(via
		(at 239.902746 -194.9577)
		(size 0.7112)
		(drill 0.4064)
		(layers "F.Cu" "B.Cu")
		(net "GND")
	)
	(via
		(at 253.111 -336.4992)
		(size 0.7112)
		(drill 0.4064)
		(layers "F.Cu" "B.Cu")
		(net "GND")
	)
	(via
		(at 110.311946 -476.5167)
		(size 0.7112)
		(drill 0.4064)
		(layers "F.Cu" "B.Cu")
		(net "GND")
	)
	(via
		(at 110.438946 -206.9211)
		(size 0.7112)
		(drill 0.4064)
		(layers "F.Cu" "B.Cu")
		(net "GND")
	)
	(via
		(at 54.736746 -230.0097)
		(size 0.5588)
		(drill 0.3048)
		(layers "F.Cu" "B.Cu")
		(net "GND")
	)
	(via
		(at 60.731146 -333.7941)
		(size 0.7112)
		(drill 0.4064)
		(layers "F.Cu" "B.Cu")
		(net "GND")
	)
	(via
		(at 234.035346 -202.2729)
		(size 0.7112)
		(drill 0.4064)
		(layers "F.Cu" "B.Cu")
		(net "GND")
	)
	(via
		(at 232.409746 -474.4847)
		(size 0.7112)
		(drill 0.4064)
		(layers "F.Cu" "B.Cu")
		(net "GND")
	)
	(via
		(at 169.417746 -121.0437)
		(size 0.7112)
		(drill 0.4064)
		(layers "F.Cu" "B.Cu")
		(net "GND")
	)
	(via
		(at 21.919946 -414.6677)
		(size 0.7112)
		(drill 0.4064)
		(layers "F.Cu" "B.Cu")
		(net "GND")
	)
	(via
		(at 41.528746 -262.9027)
		(size 0.7112)
		(drill 0.4064)
		(layers "F.Cu" "B.Cu")
		(net "GND")
	)
	(via
		(at 185.546746 -496.4811)
		(size 0.7112)
		(drill 0.4064)
		(layers "F.Cu" "B.Cu")
		(net "GND")
	)
	(via
		(at 215.340946 -210.3755)
		(size 0.7112)
		(drill 0.4064)
		(layers "F.Cu" "B.Cu")
		(net "GND")
	)
	(via
		(at 48.437546 -197.7009)
		(size 0.7112)
		(drill 0.4064)
		(layers "F.Cu" "B.Cu")
		(net "GND")
	)
	(via
		(at 234.949746 -298.2087)
		(size 0.7112)
		(drill 0.4064)
		(layers "F.Cu" "B.Cu")
		(net "GND")
	)
	(via
		(at 137.667746 -20.0787)
		(size 0.7112)
		(drill 0.4064)
		(layers "F.Cu" "B.Cu")
		(net "GND")
	)
	(via
		(at 155.295346 -260.7691)
		(size 0.7112)
		(drill 0.4064)
		(layers "F.Cu" "B.Cu")
		(net "GND")
	)
	(via
		(at 6.095746 -359.0417)
		(size 0.5588)
		(drill 0.3048)
		(layers "F.Cu" "B.Cu")
		(net "GND")
	)
	(via
		(at 88.518746 -496.9637)
		(size 0.7112)
		(drill 0.4064)
		(layers "F.Cu" "B.Cu")
		(net "GND")
	)
	(via
		(at 23.702264 -343.154)
		(size 0.7112)
		(drill 0.4064)
		(layers "F.Cu" "B.Cu")
		(net "GND")
	)
	(via
		(at 259.333746 -82.3087)
		(size 0.7112)
		(drill 0.4064)
		(layers "F.Cu" "B.Cu")
		(net "GND")
	)
	(via
		(at 174.523146 -227.6729)
		(size 0.7112)
		(drill 0.4064)
		(layers "F.Cu" "B.Cu")
		(net "GND")
	)
	(via
		(at 194.919346 -35.5981)
		(size 0.7112)
		(drill 0.4064)
		(layers "F.Cu" "B.Cu")
		(net "GND")
	)
	(via
		(at 114.3762 -102.6668)
		(size 0.7112)
		(drill 0.4064)
		(layers "F.Cu" "B.Cu")
		(net "GND")
	)
	(via
		(at 219.456 -443.992)
		(size 0.7112)
		(drill 0.4064)
		(layers "F.Cu" "B.Cu")
		(net "GND")
	)
	(via
		(at 36.34994 -51.780694)
		(size 0.7112)
		(drill 0.4064)
		(layers "F.Cu" "B.Cu")
		(net "GND")
	)
	(via
		(at 176.275746 -164.6301)
		(size 0.7112)
		(drill 0.4064)
		(layers "F.Cu" "B.Cu")
		(net "GND")
	)
	(via
		(at 75.717146 -344.7415)
		(size 0.7112)
		(drill 0.4064)
		(layers "F.Cu" "B.Cu")
		(net "GND")
	)
	(via
		(at 19.600164 -343.7636)
		(size 0.7112)
		(drill 0.4064)
		(layers "F.Cu" "B.Cu")
		(net "GND")
	)
	(via
		(at 22.683724 -443.701424)
		(size 0.5588)
		(drill 0.3048)
		(layers "F.Cu" "B.Cu")
		(net "GND")
	)
	(via
		(at 212.343746 -194.8307)
		(size 0.7112)
		(drill 0.4064)
		(layers "F.Cu" "B.Cu")
		(net "GND")
	)
	(via
		(at 221.433644 -172.576744)
		(size 0.7112)
		(drill 0.4064)
		(layers "F.Cu" "B.Cu")
		(net "GND")
	)
	(via
		(at 73.837546 -447.2305)
		(size 0.7112)
		(drill 0.4064)
		(layers "F.Cu" "B.Cu")
		(net "GND")
	)
	(via
		(at 115.315746 -129.4257)
		(size 0.7112)
		(drill 0.4064)
		(layers "F.Cu" "B.Cu")
		(net "GND")
	)
	(via
		(at 256.285746 -432.4223)
		(size 0.7112)
		(drill 0.4064)
		(layers "F.Cu" "B.Cu")
		(net "GND")
	)
	(via
		(at 5.8928 -307.1622)
		(size 0.7112)
		(drill 0.4064)
		(layers "F.Cu" "B.Cu")
		(net "GND")
	)
	(via
		(at 173.202346 -181.2671)
		(size 0.7112)
		(drill 0.4064)
		(layers "F.Cu" "B.Cu")
		(net "GND")
	)
	(via
		(at 131.698746 -417.5633)
		(size 0.7112)
		(drill 0.4064)
		(layers "F.Cu" "B.Cu")
		(net "GND")
	)
	(via
		(at 3.784346 -441.0075)
		(size 0.7112)
		(drill 0.4064)
		(layers "F.Cu" "B.Cu")
		(net "GND")
	)
	(via
		(at 79.248 -384.7084)
		(size 0.7112)
		(drill 0.4064)
		(layers "F.Cu" "B.Cu")
		(net "GND")
	)
	(via
		(at 196.849746 -121.0437)
		(size 0.7112)
		(drill 0.4064)
		(layers "F.Cu" "B.Cu")
		(net "GND")
	)
	(via
		(at 89.915746 -200.0885)
		(size 0.7112)
		(drill 0.4064)
		(layers "F.Cu" "B.Cu")
		(net "GND")
	)
	(via
		(at 8.883904 -157.2895)
		(size 0.5588)
		(drill 0.3048)
		(layers "F.Cu" "B.Cu")
		(net "GND")
	)
	(via
		(at 80.771746 -159.4739)
		(size 0.7112)
		(drill 0.4064)
		(layers "F.Cu" "B.Cu")
		(net "GND")
	)
	(via
		(at 110.870746 -466.4837)
		(size 0.7112)
		(drill 0.3556)
		(layers "F.Cu" "B.Cu")
		(net "GND")
	)
	(via
		(at 24.384 -347.726)
		(size 0.7112)
		(drill 0.4064)
		(layers "F.Cu" "B.Cu")
		(net "GND")
	)
	(via
		(at 204.8002 -170.3324)
		(size 0.7112)
		(drill 0.4064)
		(layers "F.Cu" "B.Cu")
		(net "GND")
	)
	(via
		(at 54.2036 -90.2462)
		(size 0.5588)
		(drill 0.3048)
		(layers "F.Cu" "B.Cu")
		(net "GND")
	)
	(via
		(at 105.663746 -131.7117)
		(size 0.7112)
		(drill 0.4064)
		(layers "F.Cu" "B.Cu")
		(net "GND")
	)
	(via
		(at 246.760746 -499.1227)
		(size 0.7112)
		(drill 0.4064)
		(layers "F.Cu" "B.Cu")
		(net "GND")
	)
	(via
		(at 138.378946 -74.6633)
		(size 0.7112)
		(drill 0.4064)
		(layers "F.Cu" "B.Cu")
		(net "GND")
	)
	(via
		(at 252.348746 -458.6097)
		(size 0.7112)
		(drill 0.4064)
		(layers "F.Cu" "B.Cu")
		(net "GND")
	)
	(via
		(at 247.1928 -385.1656)
		(size 0.7112)
		(drill 0.4064)
		(layers "F.Cu" "B.Cu")
		(net "GND")
	)
	(via
		(at 115.442746 -120.0277)
		(size 0.7112)
		(drill 0.4064)
		(layers "F.Cu" "B.Cu")
		(net "GND")
	)
	(via
		(at 6.095746 -418.9857)
		(size 0.5588)
		(drill 0.3048)
		(layers "F.Cu" "B.Cu")
		(net "GND")
	)
	(via
		(at 30.900878 -311.049416)
		(size 0.7112)
		(drill 0.4064)
		(layers "F.Cu" "B.Cu")
		(net "GND")
	)
	(via
		(at 250.7488 -425.6024)
		(size 0.5588)
		(drill 0.3048)
		(layers "F.Cu" "B.Cu")
		(net "GND")
	)
	(via
		(at 55.88 -106.934)
		(size 0.7112)
		(drill 0.4064)
		(layers "F.Cu" "B.Cu")
		(net "GND")
	)
	(via
		(at 171.373546 -269.6083)
		(size 0.7112)
		(drill 0.4064)
		(layers "F.Cu" "B.Cu")
		(net "GND")
	)
	(via
		(at 5.849112 -373.019066)
		(size 0.5588)
		(drill 0.3048)
		(layers "F.Cu" "B.Cu")
		(net "GND")
	)
	(via
		(at 259.460746 -35.8267)
		(size 0.7112)
		(drill 0.4064)
		(layers "F.Cu" "B.Cu")
		(net "GND")
	)
	(via
		(at 74.015346 -298.2341)
		(size 0.7112)
		(drill 0.4064)
		(layers "F.Cu" "B.Cu")
		(net "GND")
	)
	(via
		(at 71.373746 -154.5717)
		(size 0.7112)
		(drill 0.4064)
		(layers "F.Cu" "B.Cu")
		(net "GND")
	)
	(via
		(at 249.681746 -56.1467)
		(size 0.7112)
		(drill 0.4064)
		(layers "F.Cu" "B.Cu")
		(net "GND")
	)
	(via
		(at 80.136746 -460.3115)
		(size 0.7112)
		(drill 0.4064)
		(layers "F.Cu" "B.Cu")
		(net "GND")
	)
	(via
		(at 149.326346 -489.9279)
		(size 0.7112)
		(drill 0.4064)
		(layers "F.Cu" "B.Cu")
		(net "GND")
	)
	(via
		(at 62.102746 -34.6837)
		(size 0.7112)
		(drill 0.4064)
		(layers "F.Cu" "B.Cu")
		(net "GND")
	)
	(via
		(at 259.206746 -288.0487)
		(size 0.7112)
		(drill 0.4064)
		(layers "F.Cu" "B.Cu")
		(net "GND")
	)
	(via
		(at 184.276746 -5.9817)
		(size 0.7112)
		(drill 0.4064)
		(layers "F.Cu" "B.Cu")
		(net "GND")
	)
	(via
		(at 178.815746 -97.9297)
		(size 0.7112)
		(drill 0.3556)
		(layers "F.Cu" "B.Cu")
		(net "GND")
	)
	(via
		(at 72.846946 -336.9183)
		(size 0.7112)
		(drill 0.4064)
		(layers "F.Cu" "B.Cu")
		(net "GND")
	)
	(via
		(at 112.978946 -174.5869)
		(size 0.7112)
		(drill 0.4064)
		(layers "F.Cu" "B.Cu")
		(net "GND")
	)
	(via
		(at 259.460746 -45.2247)
		(size 0.7112)
		(drill 0.4064)
		(layers "F.Cu" "B.Cu")
		(net "GND")
	)
	(via
		(at 212.800946 -191.5541)
		(size 0.7112)
		(drill 0.4064)
		(layers "F.Cu" "B.Cu")
		(net "GND")
	)
	(via
		(at 33.90265 -338.1248)
		(size 0.5588)
		(drill 0.3048)
		(layers "F.Cu" "B.Cu")
		(net "GND")
	)
	(via
		(at 122.808746 -89.6747)
		(size 0.7112)
		(drill 0.4064)
		(layers "F.Cu" "B.Cu")
		(net "GND")
	)
	(via
		(at 190.906146 -225.3869)
		(size 0.7112)
		(drill 0.4064)
		(layers "F.Cu" "B.Cu")
		(net "GND")
	)
	(via
		(at 173.481746 -76.2127)
		(size 0.7112)
		(drill 0.4064)
		(layers "F.Cu" "B.Cu")
		(net "GND")
	)
	(via
		(at 227.202746 -366.0267)
		(size 0.7112)
		(drill 0.4064)
		(layers "F.Cu" "B.Cu")
		(net "GND")
	)
	(via
		(at 42.544746 -352.8187)
		(size 0.7112)
		(drill 0.4064)
		(layers "F.Cu" "B.Cu")
		(net "GND")
	)
	(via
		(at 75.564746 -224.5487)
		(size 0.7112)
		(drill 0.4064)
		(layers "F.Cu" "B.Cu")
		(net "GND")
	)
	(via
		(at 31.749746 -413.7787)
		(size 0.7112)
		(drill 0.4064)
		(layers "F.Cu" "B.Cu")
		(net "GND")
	)
	(via
		(at 258.952746 -259.9817)
		(size 0.7112)
		(drill 0.4064)
		(layers "F.Cu" "B.Cu")
		(net "GND")
	)
	(via
		(at 6.0198 -344.0684)
		(size 0.5588)
		(drill 0.3048)
		(layers "F.Cu" "B.Cu")
		(net "GND")
	)
	(via
		(at 38.734746 -100.5713)
		(size 0.7112)
		(drill 0.4064)
		(layers "F.Cu" "B.Cu")
		(net "GND")
	)
	(via
		(at 2.412746 -76.4667)
		(size 0.7112)
		(drill 0.4064)
		(layers "F.Cu" "B.Cu")
		(net "GND")
	)
	(via
		(at 147.192746 -142.6337)
		(size 0.7112)
		(drill 0.4064)
		(layers "F.Cu" "B.Cu")
		(net "GND")
	)
	(via
		(at 221.467934 -484.116888)
		(size 0.5588)
		(drill 0.3048)
		(layers "F.Cu" "B.Cu")
		(net "GND")
	)
	(via
		(at 53.034946 -194.7545)
		(size 0.7112)
		(drill 0.4064)
		(layers "F.Cu" "B.Cu")
		(net "GND")
	)
	(via
		(at 249.2248 -410.972508)
		(size 0.5588)
		(drill 0.3048)
		(layers "F.Cu" "B.Cu")
		(net "GND")
	)
	(via
		(at 131.825746 -280.1747)
		(size 0.7112)
		(drill 0.4064)
		(layers "F.Cu" "B.Cu")
		(net "GND")
	)
	(via
		(at 59.003946 -249.4153)
		(size 0.7112)
		(drill 0.4064)
		(layers "F.Cu" "B.Cu")
		(net "GND")
	)
	(via
		(at 161.797746 -232.1687)
		(size 0.7112)
		(drill 0.3556)
		(layers "F.Cu" "B.Cu")
		(net "GND")
	)
	(via
		(at 134.492746 -283.4767)
		(size 0.7112)
		(drill 0.4064)
		(layers "F.Cu" "B.Cu")
		(net "GND")
	)
	(via
		(at 7.3152 -110.9218)
		(size 0.5588)
		(drill 0.3048)
		(layers "F.Cu" "B.Cu")
		(net "GND")
	)
	(via
		(at 105.714546 -347.3577)
		(size 0.7112)
		(drill 0.4064)
		(layers "F.Cu" "B.Cu")
		(net "GND")
	)
	(via
		(at 192.734946 -304.5841)
		(size 0.7112)
		(drill 0.4064)
		(layers "F.Cu" "B.Cu")
		(net "GND")
	)
	(via
		(at 189.229746 -159.1437)
		(size 0.7112)
		(drill 0.4064)
		(layers "F.Cu" "B.Cu")
		(net "GND")
	)
	(via
		(at 67.309746 -214.0077)
		(size 0.7112)
		(drill 0.4064)
		(layers "F.Cu" "B.Cu")
		(net "GND")
	)
	(via
		(at 62.763146 -201.9427)
		(size 0.7112)
		(drill 0.4064)
		(layers "F.Cu" "B.Cu")
		(net "GND")
	)
	(via
		(at 119.735346 -31.6357)
		(size 0.7112)
		(drill 0.4064)
		(layers "F.Cu" "B.Cu")
		(net "GND")
	)
	(via
		(at 244.2464 -389.7376)
		(size 0.7112)
		(drill 0.4064)
		(layers "F.Cu" "B.Cu")
		(net "GND")
	)
	(via
		(at 62.229746 -138.4427)
		(size 0.7112)
		(drill 0.4064)
		(layers "F.Cu" "B.Cu")
		(net "GND")
	)
	(via
		(at 118.312946 -6.2865)
		(size 0.7112)
		(drill 0.4064)
		(layers "F.Cu" "B.Cu")
		(net "GND")
	)
	(via
		(at 259.079746 -233.0577)
		(size 0.7112)
		(drill 0.4064)
		(layers "F.Cu" "B.Cu")
		(net "GND")
	)
	(via
		(at 30.7594 -273.1262)
		(size 0.5588)
		(drill 0.3048)
		(layers "F.Cu" "B.Cu")
		(net "GND")
	)
	(via
		(at 217.297 -37.973)
		(size 0.5588)
		(drill 0.3048)
		(layers "F.Cu" "B.Cu")
		(net "GND")
	)
	(via
		(at 131.952746 -124.2187)
		(size 0.7112)
		(drill 0.4064)
		(layers "F.Cu" "B.Cu")
		(net "GND")
	)
	(via
		(at 229.869746 -102.2477)
		(size 0.7112)
		(drill 0.4064)
		(layers "F.Cu" "B.Cu")
		(net "GND")
	)
	(via
		(at 218.8972 -150.1648)
		(size 0.7112)
		(drill 0.4064)
		(layers "F.Cu" "B.Cu")
		(net "GND")
	)
	(via
		(at 5.841746 -381.0127)
		(size 0.5588)
		(drill 0.3048)
		(layers "F.Cu" "B.Cu")
		(net "GND")
	)
	(via
		(at 40.512746 -265.323066)
		(size 0.7112)
		(drill 0.4064)
		(layers "F.Cu" "B.Cu")
		(net "GND")
	)
	(via
		(at 236.473746 -495.3127)
		(size 0.7112)
		(drill 0.4064)
		(layers "F.Cu" "B.Cu")
		(net "GND")
	)
	(via
		(at 229.691946 -496.5573)
		(size 0.7112)
		(drill 0.4064)
		(layers "F.Cu" "B.Cu")
		(net "GND")
	)
	(via
		(at 23.184866 -340.523068)
		(size 0.5588)
		(drill 0.3048)
		(layers "F.Cu" "B.Cu")
		(net "GND")
	)
	(via
		(at 215.086946 -191.5541)
		(size 0.7112)
		(drill 0.4064)
		(layers "F.Cu" "B.Cu")
		(net "GND")
	)
	(via
		(at 51.993546 -360.2609)
		(size 0.7112)
		(drill 0.4064)
		(layers "F.Cu" "B.Cu")
		(net "GND")
	)
	(via
		(at 38.813232 -62.570614)
		(size 0.7112)
		(drill 0.4064)
		(layers "F.Cu" "B.Cu")
		(net "GND")
	)
	(via
		(at 114.401346 -170.8785)
		(size 0.7112)
		(drill 0.4064)
		(layers "F.Cu" "B.Cu")
		(net "GND")
	)
	(via
		(at 86.004146 -213.4743)
		(size 0.7112)
		(drill 0.4064)
		(layers "F.Cu" "B.Cu")
		(net "GND")
	)
	(via
		(at 77.723746 -485.9147)
		(size 0.7112)
		(drill 0.4064)
		(layers "F.Cu" "B.Cu")
		(net "GND")
	)
	(via
		(at 255.523746 -157.1879)
		(size 0.7112)
		(drill 0.4064)
		(layers "F.Cu" "B.Cu")
		(net "GND")
	)
	(via
		(at 215.772746 -504.7107)
		(size 0.7112)
		(drill 0.4064)
		(layers "F.Cu" "B.Cu")
		(net "GND")
	)
	(via
		(at 253.644146 -286.6263)
		(size 0.7112)
		(drill 0.4064)
		(layers "F.Cu" "B.Cu")
		(net "GND")
	)
	(via
		(at 195.833746 -76.7207)
		(size 0.5588)
		(drill 0.3048)
		(layers "F.Cu" "B.Cu")
		(net "GND")
	)
	(via
		(at 103.377746 -471.4113)
		(size 0.7112)
		(drill 0.4064)
		(layers "F.Cu" "B.Cu")
		(net "GND")
	)
	(via
		(at 60.705746 -500.5197)
		(size 0.7112)
		(drill 0.4064)
		(layers "F.Cu" "B.Cu")
		(net "GND")
	)
	(via
		(at 107.949746 -324.7517)
		(size 0.7112)
		(drill 0.4064)
		(layers "F.Cu" "B.Cu")
		(net "GND")
	)
	(via
		(at 62.3824 -11.1252)
		(size 0.7112)
		(drill 0.4064)
		(layers "F.Cu" "B.Cu")
		(net "GND")
	)
	(via
		(at 6.095746 -61.8617)
		(size 0.7112)
		(drill 0.4064)
		(layers "F.Cu" "B.Cu")
		(net "GND")
	)
	(via
		(at 71.373746 -30.4927)
		(size 0.7112)
		(drill 0.4064)
		(layers "F.Cu" "B.Cu")
		(net "GND")
	)
	(via
		(at 162.432746 -241.8461)
		(size 0.7112)
		(drill 0.4064)
		(layers "F.Cu" "B.Cu")
		(net "GND")
	)
	(via
		(at 142.493746 -232.8037)
		(size 0.7112)
		(drill 0.4064)
		(layers "F.Cu" "B.Cu")
		(net "GND")
	)
	(via
		(at 40.876728 -139.564872)
		(size 0.5588)
		(drill 0.3048)
		(layers "F.Cu" "B.Cu")
		(net "GND")
	)
	(via
		(at 185.800746 -153.4287)
		(size 0.7112)
		(drill 0.4064)
		(layers "F.Cu" "B.Cu")
		(net "GND")
	)
	(via
		(at 95.884746 -300.2407)
		(size 0.7112)
		(drill 0.4064)
		(layers "F.Cu" "B.Cu")
		(net "GND")
	)
	(via
		(at 64.24549 -81.054956)
		(size 0.5588)
		(drill 0.3048)
		(layers "F.Cu" "B.Cu")
		(net "GND")
	)
	(via
		(at 189.991746 -170.3705)
		(size 0.7112)
		(drill 0.4064)
		(layers "F.Cu" "B.Cu")
		(net "GND")
	)
	(via
		(at 195.605146 -439.5089)
		(size 0.7112)
		(drill 0.4064)
		(layers "F.Cu" "B.Cu")
		(net "GND")
	)
	(via
		(at 72.2122 -425.9326)
		(size 0.7112)
		(drill 0.4064)
		(layers "F.Cu" "B.Cu")
		(net "GND")
	)
	(via
		(at 205.994 -455.422)
		(size 0.5588)
		(drill 0.3048)
		(layers "F.Cu" "B.Cu")
		(net "GND")
	)
	(via
		(at 187.451746 -284.2387)
		(size 0.7112)
		(drill 0.4064)
		(layers "F.Cu" "B.Cu")
		(net "GND")
	)
	(via
		(at 249.808746 -122.6947)
		(size 0.7112)
		(drill 0.4064)
		(layers "F.Cu" "B.Cu")
		(net "GND")
	)
	(via
		(at 25.9334 -130.7846)
		(size 0.5588)
		(drill 0.3048)
		(layers "F.Cu" "B.Cu")
		(net "GND")
	)
	(via
		(at 210.692746 -311.9247)
		(size 0.7112)
		(drill 0.4064)
		(layers "F.Cu" "B.Cu")
		(net "GND")
	)
	(via
		(at 2.158746 -255.5367)
		(size 0.7112)
		(drill 0.4064)
		(layers "F.Cu" "B.Cu")
		(net "GND")
	)
	(via
		(at 245.4402 -405.9936)
		(size 0.7112)
		(drill 0.4064)
		(layers "F.Cu" "B.Cu")
		(net "GND")
	)
	(via
		(at 171.170346 -492.4679)
		(size 0.7112)
		(drill 0.4064)
		(layers "F.Cu" "B.Cu")
		(net "GND")
	)
	(via
		(at 78.917546 -239.6617)
		(size 0.7112)
		(drill 0.4064)
		(layers "F.Cu" "B.Cu")
		(net "GND")
	)
	(via
		(at 145.541746 -72.9107)
		(size 0.7112)
		(drill 0.4064)
		(layers "F.Cu" "B.Cu")
		(net "GND")
	)
	(via
		(at 88.772746 -485.1527)
		(size 0.7112)
		(drill 0.4064)
		(layers "F.Cu" "B.Cu")
		(net "GND")
	)
	(via
		(at 27.114246 -237.329218)
		(size 0.5588)
		(drill 0.3048)
		(layers "F.Cu" "B.Cu")
		(net "GND")
	)
	(via
		(at 28.702 -340.614)
		(size 0.5588)
		(drill 0.3048)
		(layers "F.Cu" "B.Cu")
		(net "GND")
	)
	(via
		(at 259.206746 -476.8977)
		(size 0.7112)
		(drill 0.4064)
		(layers "F.Cu" "B.Cu")
		(net "GND")
	)
	(via
		(at 196.468746 -383.2987)
		(size 0.7112)
		(drill 0.4064)
		(layers "F.Cu" "B.Cu")
		(net "GND")
	)
	(via
		(at 163.956746 -1.7907)
		(size 0.7112)
		(drill 0.4064)
		(layers "F.Cu" "B.Cu")
		(net "GND")
	)
	(via
		(at 5.968746 -130.985514)
		(size 0.5588)
		(drill 0.3048)
		(layers "F.Cu" "B.Cu")
		(net "GND")
	)
	(via
		(at 8.9662 -133.2992)
		(size 0.5588)
		(drill 0.3048)
		(layers "F.Cu" "B.Cu")
		(net "GND")
	)
	(via
		(at 117.195346 -391.5791)
		(size 0.7112)
		(drill 0.4064)
		(layers "F.Cu" "B.Cu")
		(net "GND")
	)
	(via
		(at 173.608746 -63.1317)
		(size 0.7112)
		(drill 0.4064)
		(layers "F.Cu" "B.Cu")
		(net "GND")
	)
	(via
		(at 189.890146 -468.4395)
		(size 0.7112)
		(drill 0.4064)
		(layers "F.Cu" "B.Cu")
		(net "GND")
	)
	(via
		(at 33.781746 -335.1657)
		(size 0.5588)
		(drill 0.3048)
		(layers "F.Cu" "B.Cu")
		(net "GND")
	)
	(via
		(at 218.947746 -37.2237)
		(size 0.5588)
		(drill 0.3048)
		(layers "F.Cu" "B.Cu")
		(net "GND")
	)
	(via
		(at 192.658746 -21.3487)
		(size 0.7112)
		(drill 0.4064)
		(layers "F.Cu" "B.Cu")
		(net "GND")
	)
	(via
		(at 165.861746 -356.5017)
		(size 0.7112)
		(drill 0.4064)
		(layers "F.Cu" "B.Cu")
		(net "GND")
	)
	(via
		(at 154.812746 -425.4627)
		(size 0.7112)
		(drill 0.4064)
		(layers "F.Cu" "B.Cu")
		(net "GND")
	)
	(via
		(at 1.651 -291.084)
		(size 0.7112)
		(drill 0.4064)
		(layers "F.Cu" "B.Cu")
		(net "GND")
	)
	(via
		(at 259.333746 -153.8097)
		(size 0.7112)
		(drill 0.4064)
		(layers "F.Cu" "B.Cu")
		(net "GND")
	)
	(via
		(at 107.949746 -194.7037)
		(size 0.7112)
		(drill 0.4064)
		(layers "F.Cu" "B.Cu")
		(net "GND")
	)
	(via
		(at 106.807 -504.698)
		(size 0.7112)
		(drill 0.4064)
		(layers "F.Cu" "B.Cu")
		(net "GND")
	)
	(via
		(at 200.659746 -144.7927)
		(size 0.7112)
		(drill 0.4064)
		(layers "F.Cu" "B.Cu")
		(net "GND")
	)
	(via
		(at 117.855746 -175.6537)
		(size 0.7112)
		(drill 0.4064)
		(layers "F.Cu" "B.Cu")
		(net "GND")
	)
	(via
		(at 212.381846 -284.1117)
		(size 0.7112)
		(drill 0.4064)
		(layers "F.Cu" "B.Cu")
		(net "GND")
	)
	(via
		(at 190.880746 -212.4837)
		(size 0.7112)
		(drill 0.4064)
		(layers "F.Cu" "B.Cu")
		(net "GND")
	)
	(via
		(at 137.286746 -64.7827)
		(size 0.7112)
		(drill 0.4064)
		(layers "F.Cu" "B.Cu")
		(net "GND")
	)
	(via
		(at 79.374746 -122.9487)
		(size 0.7112)
		(drill 0.4064)
		(layers "F.Cu" "B.Cu")
		(net "GND")
	)
	(via
		(at 23.926546 -82.6897)
		(size 0.7112)
		(drill 0.4064)
		(layers "F.Cu" "B.Cu")
		(net "GND")
	)
	(via
		(at 258.952746 -291.0967)
		(size 0.7112)
		(drill 0.4064)
		(layers "F.Cu" "B.Cu")
		(net "GND")
	)
	(via
		(at 92.455746 -34.5567)
		(size 0.7112)
		(drill 0.4064)
		(layers "F.Cu" "B.Cu")
		(net "GND")
	)
	(via
		(at 172.287946 -361.9627)
		(size 0.7112)
		(drill 0.4064)
		(layers "F.Cu" "B.Cu")
		(net "GND")
	)
	(via
		(at 48.132746 -1.1557)
		(size 0.7112)
		(drill 0.4064)
		(layers "F.Cu" "B.Cu")
		(net "GND")
	)
	(via
		(at 1.549146 -445.4525)
		(size 0.7112)
		(drill 0.4064)
		(layers "F.Cu" "B.Cu")
		(net "GND")
	)
	(via
		(at 149.351746 -16.1417)
		(size 0.7112)
		(drill 0.4064)
		(layers "F.Cu" "B.Cu")
		(net "GND")
	)
	(via
		(at 95.402146 -336.1309)
		(size 0.7112)
		(drill 0.4064)
		(layers "F.Cu" "B.Cu")
		(net "GND")
	)
	(via
		(at 131.673346 -493.3315)
		(size 0.7112)
		(drill 0.4064)
		(layers "F.Cu" "B.Cu")
		(net "GND")
	)
	(via
		(at 12.1412 -175.9712)
		(size 0.7112)
		(drill 0.4064)
		(layers "F.Cu" "B.Cu")
		(net "GND")
	)
	(via
		(at 82.295746 -292.9255)
		(size 0.7112)
		(drill 0.4064)
		(layers "F.Cu" "B.Cu")
		(net "GND")
	)
	(via
		(at 89.941146 -94.7547)
		(size 0.7112)
		(drill 0.4064)
		(layers "F.Cu" "B.Cu")
		(net "GND")
	)
	(via
		(at 82.168746 -243.0653)
		(size 0.7112)
		(drill 0.4064)
		(layers "F.Cu" "B.Cu")
		(net "GND")
	)
	(via
		(at 246.252746 -166.0017)
		(size 0.7112)
		(drill 0.4064)
		(layers "F.Cu" "B.Cu")
		(net "GND")
	)
	(via
		(at 177.367946 -494.8047)
		(size 0.7112)
		(drill 0.4064)
		(layers "F.Cu" "B.Cu")
		(net "GND")
	)
	(via
		(at 84.670646 -346.329)
		(size 0.7112)
		(drill 0.4064)
		(layers "F.Cu" "B.Cu")
		(net "GND")
	)
	(via
		(at 5.968746 -367.0427)
		(size 0.5588)
		(drill 0.3048)
		(layers "F.Cu" "B.Cu")
		(net "GND")
	)
	(via
		(at 118.617746 -388.7851)
		(size 0.7112)
		(drill 0.4064)
		(layers "F.Cu" "B.Cu")
		(net "GND")
	)
	(via
		(at 232.409746 -479.3107)
		(size 0.7112)
		(drill 0.4064)
		(layers "F.Cu" "B.Cu")
		(net "GND")
	)
	(via
		(at 204.215746 -123.7107)
		(size 0.7112)
		(drill 0.4064)
		(layers "F.Cu" "B.Cu")
		(net "GND")
	)
	(via
		(at 208.0768 -438.6834)
		(size 0.7112)
		(drill 0.4064)
		(layers "F.Cu" "B.Cu")
		(net "GND")
	)
	(via
		(at 183.362346 -360.4387)
		(size 0.7112)
		(drill 0.4064)
		(layers "F.Cu" "B.Cu")
		(net "GND")
	)
	(via
		(at 45.72 -439.674)
		(size 0.7112)
		(drill 0.4064)
		(layers "F.Cu" "B.Cu")
		(net "GND")
	)
	(via
		(at 240.664746 -491.7567)
		(size 0.7112)
		(drill 0.4064)
		(layers "F.Cu" "B.Cu")
		(net "GND")
	)
	(via
		(at 23.520146 -153.983944)
		(size 0.7112)
		(drill 0.4064)
		(layers "F.Cu" "B.Cu")
		(net "GND")
	)
	(via
		(at 182.016146 -487.2863)
		(size 0.7112)
		(drill 0.4064)
		(layers "F.Cu" "B.Cu")
		(net "GND")
	)
	(via
		(at 45.999146 -479.0059)
		(size 0.7112)
		(drill 0.4064)
		(layers "F.Cu" "B.Cu")
		(net "GND")
	)
	(via
		(at 113.156746 -455.3077)
		(size 0.7112)
		(drill 0.4064)
		(layers "F.Cu" "B.Cu")
		(net "GND")
	)
	(via
		(at 247.573546 -486.2703)
		(size 0.7112)
		(drill 0.4064)
		(layers "F.Cu" "B.Cu")
		(net "GND")
	)
	(via
		(at 219.7608 -499.872)
		(size 0.7112)
		(drill 0.4064)
		(layers "F.Cu" "B.Cu")
		(net "GND")
	)
	(via
		(at 105.028746 -1.5367)
		(size 0.7112)
		(drill 0.4064)
		(layers "F.Cu" "B.Cu")
		(net "GND")
	)
	(via
		(at 222.935546 -418.2491)
		(size 0.7112)
		(drill 0.4064)
		(layers "F.Cu" "B.Cu")
		(net "GND")
	)
	(via
		(at 236.981746 -118.5037)
		(size 0.7112)
		(drill 0.4064)
		(layers "F.Cu" "B.Cu")
		(net "GND")
	)
	(via
		(at 51.612546 -353.8855)
		(size 0.7112)
		(drill 0.4064)
		(layers "F.Cu" "B.Cu")
		(net "GND")
	)
	(via
		(at 50.7746 -424.3324)
		(size 0.7112)
		(drill 0.4064)
		(layers "F.Cu" "B.Cu")
		(net "GND")
	)
	(via
		(at 259.206746 -176.5427)
		(size 0.7112)
		(drill 0.4064)
		(layers "F.Cu" "B.Cu")
		(net "GND")
	)
	(via
		(at 225.424746 -471.3097)
		(size 0.7112)
		(drill 0.4064)
		(layers "F.Cu" "B.Cu")
		(net "GND")
	)
	(via
		(at 113.817146 -340.6775)
		(size 0.7112)
		(drill 0.4064)
		(layers "F.Cu" "B.Cu")
		(net "GND")
	)
	(via
		(at 66.623946 -41.6687)
		(size 0.7112)
		(drill 0.4064)
		(layers "F.Cu" "B.Cu")
		(net "GND")
	)
	(via
		(at 248.030746 -302.9077)
		(size 0.7112)
		(drill 0.4064)
		(layers "F.Cu" "B.Cu")
		(net "GND")
	)
	(via
		(at 7.594346 -102.713536)
		(size 0.5588)
		(drill 0.3048)
		(layers "F.Cu" "B.Cu")
		(net "GND")
	)
	(via
		(at 255.142746 -148.9329)
		(size 0.7112)
		(drill 0.4064)
		(layers "F.Cu" "B.Cu")
		(net "GND")
	)
	(via
		(at 245.6942 -385.1656)
		(size 0.7112)
		(drill 0.4064)
		(layers "F.Cu" "B.Cu")
		(net "GND")
	)
	(via
		(at 122.300746 -280.0477)
		(size 0.7112)
		(drill 0.4064)
		(layers "F.Cu" "B.Cu")
		(net "GND")
	)
	(via
		(at 22.834346 -93.5609)
		(size 0.7112)
		(drill 0.4064)
		(layers "F.Cu" "B.Cu")
		(net "GND")
	)
	(via
		(at 230.505 -407.416)
		(size 0.7112)
		(drill 0.4064)
		(layers "F.Cu" "B.Cu")
		(net "GND")
	)
	(via
		(at 142.366746 -245.8847)
		(size 0.7112)
		(drill 0.4064)
		(layers "F.Cu" "B.Cu")
		(net "GND")
	)
	(via
		(at 117.474746 -269.9639)
		(size 0.7112)
		(drill 0.4064)
		(layers "F.Cu" "B.Cu")
		(net "GND")
	)
	(via
		(at 62.2046 -37.8714)
		(size 0.7112)
		(drill 0.4064)
		(layers "F.Cu" "B.Cu")
		(net "GND")
	)
	(via
		(at 252.095 -354.9142)
		(size 0.7112)
		(drill 0.4064)
		(layers "F.Cu" "B.Cu")
		(net "GND")
	)
	(via
		(at 235.076746 -324.4977)
		(size 0.7112)
		(drill 0.4064)
		(layers "F.Cu" "B.Cu")
		(net "GND")
	)
	(via
		(at 200.1266 -446.7352)
		(size 0.7112)
		(drill 0.4064)
		(layers "F.Cu" "B.Cu")
		(net "GND")
	)
	(via
		(at 215.265 -268.6812)
		(size 0.5588)
		(drill 0.3048)
		(layers "F.Cu" "B.Cu")
		(net "GND")
	)
	(via
		(at 252.475746 -257.0607)
		(size 0.7112)
		(drill 0.4064)
		(layers "F.Cu" "B.Cu")
		(net "GND")
	)
	(via
		(at 55.895748 -490.502702)
		(size 0.5588)
		(drill 0.3048)
		(layers "F.Cu" "B.Cu")
		(net "GND")
	)
	(via
		(at 198.094346 -444.0301)
		(size 0.7112)
		(drill 0.4064)
		(layers "F.Cu" "B.Cu")
		(net "GND")
	)
	(via
		(at 222.2246 -369.316)
		(size 0.5588)
		(drill 0.3048)
		(layers "F.Cu" "B.Cu")
		(net "GND")
	)
	(via
		(at 130.555746 -260.8707)
		(size 0.7112)
		(drill 0.4064)
		(layers "F.Cu" "B.Cu")
		(net "GND")
	)
	(via
		(at 2.285746 -80.9117)
		(size 0.7112)
		(drill 0.4064)
		(layers "F.Cu" "B.Cu")
		(net "GND")
	)
	(via
		(at 176.783746 -313.7027)
		(size 0.7112)
		(drill 0.4064)
		(layers "F.Cu" "B.Cu")
		(net "GND")
	)
	(via
		(at 56.006746 -138.5697)
		(size 0.7112)
		(drill 0.4064)
		(layers "F.Cu" "B.Cu")
		(net "GND")
	)
	(via
		(at 183.768746 -324.6501)
		(size 0.7112)
		(drill 0.4064)
		(layers "F.Cu" "B.Cu")
		(net "GND")
	)
	(via
		(at 153.669746 -44.1325)
		(size 0.7112)
		(drill 0.4064)
		(layers "F.Cu" "B.Cu")
		(net "GND")
	)
	(via
		(at 196.722746 -484.6447)
		(size 0.7112)
		(drill 0.4064)
		(layers "F.Cu" "B.Cu")
		(net "GND")
	)
	(via
		(at 22.859746 -342.4047)
		(size 0.5588)
		(drill 0.3048)
		(layers "F.Cu" "B.Cu")
		(net "GND")
	)
	(via
		(at 117.474746 -235.9787)
		(size 0.7112)
		(drill 0.4064)
		(layers "F.Cu" "B.Cu")
		(net "GND")
	)
	(via
		(at 74.040746 -504.8377)
		(size 0.7112)
		(drill 0.4064)
		(layers "F.Cu" "B.Cu")
		(net "GND")
	)
	(via
		(at 5.943346 -116.978938)
		(size 0.5588)
		(drill 0.3048)
		(layers "F.Cu" "B.Cu")
		(net "GND")
	)
	(via
		(at 98.678746 -495.4397)
		(size 0.7112)
		(drill 0.4064)
		(layers "F.Cu" "B.Cu")
		(net "GND")
	)
	(via
		(at 110.134146 -275.7297)
		(size 0.7112)
		(drill 0.4064)
		(layers "F.Cu" "B.Cu")
		(net "GND")
	)
	(via
		(at 246.633746 -238.5695)
		(size 0.7112)
		(drill 0.4064)
		(layers "F.Cu" "B.Cu")
		(net "GND")
	)
	(via
		(at 75.844146 -127.3175)
		(size 0.7112)
		(drill 0.4064)
		(layers "F.Cu" "B.Cu")
		(net "GND")
	)
	(via
		(at 165.861746 -360.1847)
		(size 0.7112)
		(drill 0.4064)
		(layers "F.Cu" "B.Cu")
		(net "GND")
	)
	(via
		(at 232.384346 -421.0177)
		(size 0.7112)
		(drill 0.4064)
		(layers "F.Cu" "B.Cu")
		(net "GND")
	)
	(via
		(at 66.928746 -440.5757)
		(size 0.7112)
		(drill 0.4064)
		(layers "F.Cu" "B.Cu")
		(net "GND")
	)
	(via
		(at 194.030346 -471.3859)
		(size 0.7112)
		(drill 0.4064)
		(layers "F.Cu" "B.Cu")
		(net "GND")
	)
	(via
		(at 221.335346 -305.2699)
		(size 0.7112)
		(drill 0.4064)
		(layers "F.Cu" "B.Cu")
		(net "GND")
	)
	(via
		(at 216.026746 -330.2127)
		(size 0.7112)
		(drill 0.4064)
		(layers "F.Cu" "B.Cu")
		(net "GND")
	)
	(via
		(at 78.104746 -141.1097)
		(size 0.7112)
		(drill 0.4064)
		(layers "F.Cu" "B.Cu")
		(net "GND")
	)
	(via
		(at 62.610746 -347.9927)
		(size 0.7112)
		(drill 0.4064)
		(layers "F.Cu" "B.Cu")
		(net "GND")
	)
	(via
		(at 225.983546 -222.5167)
		(size 0.7112)
		(drill 0.4064)
		(layers "F.Cu" "B.Cu")
		(net "GND")
	)
	(via
		(at 180.822346 -493.7887)
		(size 0.7112)
		(drill 0.4064)
		(layers "F.Cu" "B.Cu")
		(net "GND")
	)
	(via
		(at 199.247506 -288.6837)
		(size 0.5588)
		(drill 0.3048)
		(layers "F.Cu" "B.Cu")
		(net "GND")
	)
	(via
		(at 242.696746 -483.1207)
		(size 0.7112)
		(drill 0.4064)
		(layers "F.Cu" "B.Cu")
		(net "GND")
	)
	(via
		(at 149.580346 -485.2289)
		(size 0.7112)
		(drill 0.4064)
		(layers "F.Cu" "B.Cu")
		(net "GND")
	)
	(via
		(at 253.644146 -317.8683)
		(size 0.7112)
		(drill 0.4064)
		(layers "F.Cu" "B.Cu")
		(net "GND")
	)
	(via
		(at 156.870146 -320.2305)
		(size 0.7112)
		(drill 0.4064)
		(layers "F.Cu" "B.Cu")
		(net "GND")
	)
	(via
		(at 234.635294 -21.7297)
		(size 0.5588)
		(drill 0.3048)
		(layers "F.Cu" "B.Cu")
		(net "GND")
	)
	(via
		(at 56.260746 -447.2813)
		(size 0.7112)
		(drill 0.4064)
		(layers "F.Cu" "B.Cu")
		(net "GND")
	)
	(via
		(at 246.252746 -170.4467)
		(size 0.7112)
		(drill 0.4064)
		(layers "F.Cu" "B.Cu")
		(net "GND")
	)
	(via
		(at 190.982346 -445.0461)
		(size 0.7112)
		(drill 0.4064)
		(layers "F.Cu" "B.Cu")
		(net "GND")
	)
	(via
		(at 142.493746 -236.4867)
		(size 0.7112)
		(drill 0.4064)
		(layers "F.Cu" "B.Cu")
		(net "GND")
	)
	(via
		(at 79.247746 -308.3179)
		(size 0.7112)
		(drill 0.4064)
		(layers "F.Cu" "B.Cu")
		(net "GND")
	)
	(via
		(at 11.277346 -493.3315)
		(size 0.5588)
		(drill 0.3048)
		(layers "F.Cu" "B.Cu")
		(net "GND")
	)
	(via
		(at 54.102 -424.815)
		(size 0.7112)
		(drill 0.4064)
		(layers "F.Cu" "B.Cu")
		(net "GND")
	)
	(via
		(at 229.869746 -97.8027)
		(size 0.7112)
		(drill 0.4064)
		(layers "F.Cu" "B.Cu")
		(net "GND")
	)
	(via
		(at 51.2064 -306.2986)
		(size 0.7112)
		(drill 0.4064)
		(layers "F.Cu" "B.Cu")
		(net "GND")
	)
	(via
		(at 61.518546 -307.3527)
		(size 0.7112)
		(drill 0.4064)
		(layers "F.Cu" "B.Cu")
		(net "GND")
	)
	(via
		(at 145.414746 -82.6897)
		(size 0.7112)
		(drill 0.4064)
		(layers "F.Cu" "B.Cu")
		(net "GND")
	)
	(via
		(at 165.556946 -15.1511)
		(size 0.7112)
		(drill 0.4064)
		(layers "F.Cu" "B.Cu")
		(net "GND")
	)
	(via
		(at 212.978746 -36.8427)
		(size 0.7112)
		(drill 0.4064)
		(layers "F.Cu" "B.Cu")
		(net "GND")
	)
	(via
		(at 218.799156 -489.8517)
		(size 0.7112)
		(drill 0.4064)
		(layers "F.Cu" "B.Cu")
		(net "GND")
	)
	(via
		(at 133.476746 -196.2023)
		(size 0.7112)
		(drill 0.4064)
		(layers "F.Cu" "B.Cu")
		(net "GND")
	)
	(via
		(at 218.566746 -302.9077)
		(size 0.7112)
		(drill 0.3556)
		(layers "F.Cu" "B.Cu")
		(net "GND")
	)
	(via
		(at 220.497146 -415.4551)
		(size 0.7112)
		(drill 0.4064)
		(layers "F.Cu" "B.Cu")
		(net "GND")
	)
	(via
		(at 131.800346 -388.6581)
		(size 0.7112)
		(drill 0.4064)
		(layers "F.Cu" "B.Cu")
		(net "GND")
	)
	(via
		(at 113.537746 -482.3587)
		(size 0.7112)
		(drill 0.4064)
		(layers "F.Cu" "B.Cu")
		(net "GND")
	)
	(via
		(at 152.272746 -343.2937)
		(size 0.7112)
		(drill 0.4064)
		(layers "F.Cu" "B.Cu")
		(net "GND")
	)
	(via
		(at 32.258 -282.829)
		(size 0.5588)
		(drill 0.3048)
		(layers "F.Cu" "B.Cu")
		(net "GND")
	)
	(via
		(at 126.593346 -119.3927)
		(size 0.7112)
		(drill 0.4064)
		(layers "F.Cu" "B.Cu")
		(net "GND")
	)
	(via
		(at 99.440746 -471.4113)
		(size 0.7112)
		(drill 0.4064)
		(layers "F.Cu" "B.Cu")
		(net "GND")
	)
	(via
		(at 120.522746 -283.2227)
		(size 0.7112)
		(drill 0.4064)
		(layers "F.Cu" "B.Cu")
		(net "GND")
	)
	(via
		(at 191.769746 -365.1377)
		(size 0.7112)
		(drill 0.4064)
		(layers "F.Cu" "B.Cu")
		(net "GND")
	)
	(via
		(at 186.054746 -185.2295)
		(size 0.7112)
		(drill 0.4064)
		(layers "F.Cu" "B.Cu")
		(net "GND")
	)
	(via
		(at 219.227146 -460.5401)
		(size 0.7112)
		(drill 0.4064)
		(layers "F.Cu" "B.Cu")
		(net "GND")
	)
	(via
		(at 71.068946 -302.7045)
		(size 0.7112)
		(drill 0.4064)
		(layers "F.Cu" "B.Cu")
		(net "GND")
	)
	(via
		(at 72.084946 -317.3095)
		(size 0.7112)
		(drill 0.4064)
		(layers "F.Cu" "B.Cu")
		(net "GND")
	)
	(via
		(at 21.361146 -441.2361)
		(size 0.7112)
		(drill 0.4064)
		(layers "F.Cu" "B.Cu")
		(net "GND")
	)
	(via
		(at 55.498746 -120.6119)
		(size 0.7112)
		(drill 0.4064)
		(layers "F.Cu" "B.Cu")
		(net "GND")
	)
	(via
		(at 259.206746 -158.2547)
		(size 0.7112)
		(drill 0.4064)
		(layers "F.Cu" "B.Cu")
		(net "GND")
	)
	(via
		(at 36.242752 -55.590694)
		(size 0.7112)
		(drill 0.4064)
		(layers "F.Cu" "B.Cu")
		(net "GND")
	)
	(via
		(at 141.097 -457.8858)
		(size 0.7112)
		(drill 0.4064)
		(layers "F.Cu" "B.Cu")
		(net "GND")
	)
	(via
		(at 113.486946 -52.2351)
		(size 0.7112)
		(drill 0.4064)
		(layers "F.Cu" "B.Cu")
		(net "GND")
	)
	(via
		(at 236.727746 -66.5607)
		(size 0.7112)
		(drill 0.4064)
		(layers "F.Cu" "B.Cu")
		(net "GND")
	)
	(via
		(at 102.996746 -492.6457)
		(size 0.7112)
		(drill 0.4064)
		(layers "F.Cu" "B.Cu")
		(net "GND")
	)
	(via
		(at 152.348946 -97.8281)
		(size 0.7112)
		(drill 0.4064)
		(layers "F.Cu" "B.Cu")
		(net "GND")
	)
	(via
		(at 174.116746 -492.7727)
		(size 0.7112)
		(drill 0.4064)
		(layers "F.Cu" "B.Cu")
		(net "GND")
	)
	(via
		(at 236.778546 -457.6699)
		(size 0.7112)
		(drill 0.4064)
		(layers "F.Cu" "B.Cu")
		(net "GND")
	)
	(via
		(at 120.700546 -488.6833)
		(size 0.7112)
		(drill 0.4064)
		(layers "F.Cu" "B.Cu")
		(net "GND")
	)
	(via
		(at 111.785146 -116.6495)
		(size 0.7112)
		(drill 0.4064)
		(layers "F.Cu" "B.Cu")
		(net "GND")
	)
	(via
		(at 48.361346 -498.1575)
		(size 0.7112)
		(drill 0.4064)
		(layers "F.Cu" "B.Cu")
		(net "GND")
	)
	(via
		(at 11.303 -504.698)
		(size 0.7112)
		(drill 0.4064)
		(layers "F.Cu" "B.Cu")
		(net "GND")
	)
	(via
		(at 247.903746 -319.0367)
		(size 0.7112)
		(drill 0.4064)
		(layers "F.Cu" "B.Cu")
		(net "GND")
	)
	(via
		(at 51.917346 -471.2843)
		(size 0.7112)
		(drill 0.4064)
		(layers "F.Cu" "B.Cu")
		(net "GND")
	)
	(via
		(at 46.735746 -499.9101)
		(size 0.7112)
		(drill 0.4064)
		(layers "F.Cu" "B.Cu")
		(net "GND")
	)
	(via
		(at 86.715346 -136.1059)
		(size 0.7112)
		(drill 0.4064)
		(layers "F.Cu" "B.Cu")
		(net "GND")
	)
	(via
		(at 234.416346 -470.8271)
		(size 0.7112)
		(drill 0.4064)
		(layers "F.Cu" "B.Cu")
		(net "GND")
	)
	(via
		(at 81.660746 -450.2277)
		(size 0.7112)
		(drill 0.4064)
		(layers "F.Cu" "B.Cu")
		(net "GND")
	)
	(via
		(at 191.033146 -28.4861)
		(size 0.7112)
		(drill 0.4064)
		(layers "F.Cu" "B.Cu")
		(net "GND")
	)
	(via
		(at 141.985746 -262.1407)
		(size 0.7112)
		(drill 0.4064)
		(layers "F.Cu" "B.Cu")
		(net "GND")
	)
	(via
		(at 42.671746 -277.5839)
		(size 0.7112)
		(drill 0.4064)
		(layers "F.Cu" "B.Cu")
		(net "GND")
	)
	(via
		(at 21.564346 -73.4695)
		(size 0.7112)
		(drill 0.4064)
		(layers "F.Cu" "B.Cu")
		(net "GND")
	)
	(via
		(at 152.856946 -498.3099)
		(size 0.7112)
		(drill 0.4064)
		(layers "F.Cu" "B.Cu")
		(net "GND")
	)
	(via
		(at 259.206746 -31.1277)
		(size 0.7112)
		(drill 0.4064)
		(layers "F.Cu" "B.Cu")
		(net "GND")
	)
	(via
		(at 208.355946 -110.2995)
		(size 0.7112)
		(drill 0.4064)
		(layers "F.Cu" "B.Cu")
		(net "GND")
	)
	(via
		(at 150.621746 -111.6457)
		(size 0.7112)
		(drill 0.4064)
		(layers "F.Cu" "B.Cu")
		(net "GND")
	)
	(via
		(at 206.577946 -17.3609)
		(size 0.7112)
		(drill 0.4064)
		(layers "F.Cu" "B.Cu")
		(net "GND")
	)
	(via
		(at 249.173746 -491.0709)
		(size 0.7112)
		(drill 0.4064)
		(layers "F.Cu" "B.Cu")
		(net "GND")
	)
	(via
		(at 240.080546 -494.3729)
		(size 0.7112)
		(drill 0.4064)
		(layers "F.Cu" "B.Cu")
		(net "GND")
	)
	(via
		(at 106.679746 -283.3497)
		(size 0.7112)
		(drill 0.4064)
		(layers "F.Cu" "B.Cu")
		(net "GND")
	)
	(via
		(at 246.252746 -206.9465)
		(size 0.7112)
		(drill 0.4064)
		(layers "F.Cu" "B.Cu")
		(net "GND")
	)
	(via
		(at 87.274146 -345.4527)
		(size 0.7112)
		(drill 0.4064)
		(layers "F.Cu" "B.Cu")
		(net "GND")
	)
	(via
		(at 128.066546 -49.0855)
		(size 0.7112)
		(drill 0.4064)
		(layers "F.Cu" "B.Cu")
		(net "GND")
	)
	(via
		(at 23.748746 -446.9257)
		(size 0.7112)
		(drill 0.4064)
		(layers "F.Cu" "B.Cu")
		(net "GND")
	)
	(via
		(at 112.420146 -234.8611)
		(size 0.7112)
		(drill 0.4064)
		(layers "F.Cu" "B.Cu")
		(net "GND")
	)
	(via
		(at 236.600746 -498.3607)
		(size 0.7112)
		(drill 0.4064)
		(layers "F.Cu" "B.Cu")
		(net "GND")
	)
	(via
		(at 159.791146 -181.3687)
		(size 0.7112)
		(drill 0.4064)
		(layers "F.Cu" "B.Cu")
		(net "GND")
	)
	(via
		(at 27.431746 -367.8047)
		(size 0.5588)
		(drill 0.3048)
		(layers "F.Cu" "B.Cu")
		(net "GND")
	)
	(via
		(at 77.088746 -358.4575)
		(size 0.7112)
		(drill 0.4064)
		(layers "F.Cu" "B.Cu")
		(net "GND")
	)
	(via
		(at 228.218746 -214.5157)
		(size 0.7112)
		(drill 0.4064)
		(layers "F.Cu" "B.Cu")
		(net "GND")
	)
	(via
		(at 171.449746 -40.5257)
		(size 0.7112)
		(drill 0.4064)
		(layers "F.Cu" "B.Cu")
		(net "GND")
	)
	(via
		(at 155.701746 -217.0557)
		(size 0.7112)
		(drill 0.4064)
		(layers "F.Cu" "B.Cu")
		(net "GND")
	)
	(via
		(at 55.651146 -336.7913)
		(size 0.7112)
		(drill 0.4064)
		(layers "F.Cu" "B.Cu")
		(net "GND")
	)
	(via
		(at 46.126146 -100.6475)
		(size 0.7112)
		(drill 0.4064)
		(layers "F.Cu" "B.Cu")
		(net "GND")
	)
	(via
		(at 6.908546 -194.2973)
		(size 0.7112)
		(drill 0.4064)
		(layers "F.Cu" "B.Cu")
		(net "GND")
	)
	(via
		(at 182.143146 -161.5567)
		(size 0.7112)
		(drill 0.4064)
		(layers "F.Cu" "B.Cu")
		(net "GND")
	)
	(via
		(at 62.001146 -217.7923)
		(size 0.7112)
		(drill 0.4064)
		(layers "F.Cu" "B.Cu")
		(net "GND")
	)
	(via
		(at 29.755846 -321.9577)
		(size 0.7112)
		(drill 0.4064)
		(layers "F.Cu" "B.Cu")
		(net "GND")
	)
	(via
		(at 210.057746 -244.6401)
		(size 0.7112)
		(drill 0.4064)
		(layers "F.Cu" "B.Cu")
		(net "GND")
	)
	(via
		(at 163.220146 -224.3455)
		(size 0.7112)
		(drill 0.4064)
		(layers "F.Cu" "B.Cu")
		(net "GND")
	)
	(via
		(at 5.461 -277.495)
		(size 0.7112)
		(drill 0.4064)
		(layers "F.Cu" "B.Cu")
		(net "GND")
	)
	(via
		(at 149.478746 -504.5837)
		(size 0.7112)
		(drill 0.4064)
		(layers "F.Cu" "B.Cu")
		(net "GND")
	)
	(via
		(at 252.602746 -239.1537)
		(size 0.7112)
		(drill 0.4064)
		(layers "F.Cu" "B.Cu")
		(net "GND")
	)
	(via
		(at 45.8216 -305.5112)
		(size 0.7112)
		(drill 0.4064)
		(layers "F.Cu" "B.Cu")
		(net "GND")
	)
	(via
		(at 78.104746 -172.4787)
		(size 0.7112)
		(drill 0.4064)
		(layers "F.Cu" "B.Cu")
		(net "GND")
	)
	(via
		(at 25.247346 -111.1123)
		(size 0.7112)
		(drill 0.4064)
		(layers "F.Cu" "B.Cu")
		(net "GND")
	)
	(via
		(at 135.508746 -485.6607)
		(size 0.7112)
		(drill 0.4064)
		(layers "F.Cu" "B.Cu")
		(net "GND")
	)
	(via
		(at 19.684746 -234.0737)
		(size 0.7112)
		(drill 0.4064)
		(layers "F.Cu" "B.Cu")
		(net "GND")
	)
	(via
		(at 83.133946 -455.1299)
		(size 0.7112)
		(drill 0.4064)
		(layers "F.Cu" "B.Cu")
		(net "GND")
	)
	(via
		(at 11.269472 -495.6683)
		(size 0.5588)
		(drill 0.3048)
		(layers "F.Cu" "B.Cu")
		(net "GND")
	)
	(via
		(at 123.316746 -1.5367)
		(size 0.7112)
		(drill 0.4064)
		(layers "F.Cu" "B.Cu")
		(net "GND")
	)
	(via
		(at 50.596546 -167.4241)
		(size 0.7112)
		(drill 0.4064)
		(layers "F.Cu" "B.Cu")
		(net "GND")
	)
	(via
		(at 191.9224 -292.0492)
		(size 0.5588)
		(drill 0.3048)
		(layers "F.Cu" "B.Cu")
		(net "GND")
	)
	(via
		(at 227.913946 -483.6541)
		(size 0.7112)
		(drill 0.4064)
		(layers "F.Cu" "B.Cu")
		(net "GND")
	)
	(via
		(at 88.315546 -196.4563)
		(size 0.7112)
		(drill 0.4064)
		(layers "F.Cu" "B.Cu")
		(net "GND")
	)
	(via
		(at 59.511946 -196.5325)
		(size 0.7112)
		(drill 0.4064)
		(layers "F.Cu" "B.Cu")
		(net "GND")
	)
	(via
		(at 54.152546 -342.9127)
		(size 0.7112)
		(drill 0.4064)
		(layers "F.Cu" "B.Cu")
		(net "GND")
	)
	(via
		(at 35.3568 -123.0122)
		(size 0.7112)
		(drill 0.4064)
		(layers "F.Cu" "B.Cu")
		(net "GND")
	)
	(via
		(at 69.849746 -253.1237)
		(size 0.7112)
		(drill 0.4064)
		(layers "F.Cu" "B.Cu")
		(net "GND")
	)
	(via
		(at 44.779946 -381.0381)
		(size 0.7112)
		(drill 0.4064)
		(layers "F.Cu" "B.Cu")
		(net "GND")
	)
	(via
		(at 218.744546 -138.6967)
		(size 0.7112)
		(drill 0.4064)
		(layers "F.Cu" "B.Cu")
		(net "GND")
	)
	(via
		(at 249.808746 -71.2597)
		(size 0.7112)
		(drill 0.4064)
		(layers "F.Cu" "B.Cu")
		(net "GND")
	)
	(via
		(at 2.285746 -239.2807)
		(size 0.7112)
		(drill 0.4064)
		(layers "F.Cu" "B.Cu")
		(net "GND")
	)
	(via
		(at 150.012146 -430.3903)
		(size 0.7112)
		(drill 0.4064)
		(layers "F.Cu" "B.Cu")
		(net "GND")
	)
	(via
		(at 127.126746 -11.9507)
		(size 0.7112)
		(drill 0.4064)
		(layers "F.Cu" "B.Cu")
		(net "GND")
	)
	(via
		(at 112.724946 -321.3735)
		(size 0.7112)
		(drill 0.4064)
		(layers "F.Cu" "B.Cu")
		(net "GND")
	)
	(via
		(at 105.282746 -433.6415)
		(size 0.7112)
		(drill 0.4064)
		(layers "F.Cu" "B.Cu")
		(net "GND")
	)
	(via
		(at 147.395946 -437.5277)
		(size 0.7112)
		(drill 0.4064)
		(layers "F.Cu" "B.Cu")
		(net "GND")
	)
	(via
		(at 84.581746 -285.2547)
		(size 0.7112)
		(drill 0.4064)
		(layers "F.Cu" "B.Cu")
		(net "GND")
	)
	(via
		(at 51.180746 -26.5557)
		(size 0.5588)
		(drill 0.3048)
		(layers "F.Cu" "B.Cu")
		(net "GND")
	)
	(via
		(at 23.672546 -71.0311)
		(size 0.7112)
		(drill 0.4064)
		(layers "F.Cu" "B.Cu")
		(net "GND")
	)
	(via
		(at 259.460746 -49.1617)
		(size 0.7112)
		(drill 0.4064)
		(layers "F.Cu" "B.Cu")
		(net "GND")
	)
	(via
		(at 36.372546 -358.6607)
		(size 0.7112)
		(drill 0.4064)
		(layers "F.Cu" "B.Cu")
		(net "GND")
	)
	(via
		(at 196.900546 -217.9955)
		(size 0.7112)
		(drill 0.4064)
		(layers "F.Cu" "B.Cu")
		(net "GND")
	)
	(via
		(at 187.451746 -299.3517)
		(size 0.7112)
		(drill 0.4064)
		(layers "F.Cu" "B.Cu")
		(net "GND")
	)
	(via
		(at 64.388746 -263.7917)
		(size 0.7112)
		(drill 0.4064)
		(layers "F.Cu" "B.Cu")
		(net "GND")
	)
	(via
		(at 148.005546 -316.9285)
		(size 0.7112)
		(drill 0.4064)
		(layers "F.Cu" "B.Cu")
		(net "GND")
	)
	(via
		(at 119.074946 -105.2195)
		(size 0.7112)
		(drill 0.4064)
		(layers "F.Cu" "B.Cu")
		(net "GND")
	)
	(via
		(at 148.157946 -323.6595)
		(size 0.7112)
		(drill 0.4064)
		(layers "F.Cu" "B.Cu")
		(net "GND")
	)
	(via
		(at 37.084 -504.825)
		(size 0.7112)
		(drill 0.4064)
		(layers "F.Cu" "B.Cu")
		(net "GND")
	)
	(via
		(at 241.629946 -137.4521)
		(size 0.7112)
		(drill 0.4064)
		(layers "F.Cu" "B.Cu")
		(net "GND")
	)
	(via
		(at 52.844446 -351.9297)
		(size 0.7112)
		(drill 0.4064)
		(layers "F.Cu" "B.Cu")
		(net "GND")
	)
	(via
		(at 229.869746 -94.1197)
		(size 0.7112)
		(drill 0.4064)
		(layers "F.Cu" "B.Cu")
		(net "GND")
	)
	(via
		(at 123.723146 -407.9875)
		(size 0.7112)
		(drill 0.4064)
		(layers "F.Cu" "B.Cu")
		(net "GND")
	)
	(via
		(at 182.676546 -335.8769)
		(size 0.7112)
		(drill 0.4064)
		(layers "F.Cu" "B.Cu")
		(net "GND")
	)
	(via
		(at 127.380746 -280.0477)
		(size 0.7112)
		(drill 0.4064)
		(layers "F.Cu" "B.Cu")
		(net "GND")
	)
	(via
		(at 40.399716 -169.0116)
		(size 0.7112)
		(drill 0.4064)
		(layers "F.Cu" "B.Cu")
		(net "GND")
	)
	(via
		(at 49.53 -438.277)
		(size 0.7112)
		(drill 0.4064)
		(layers "F.Cu" "B.Cu")
		(net "GND")
	)
	(via
		(at 206.831946 -22.6949)
		(size 0.7112)
		(drill 0.4064)
		(layers "F.Cu" "B.Cu")
		(net "GND")
	)
	(via
		(at 46.227746 -158.5087)
		(size 0.7112)
		(drill 0.4064)
		(layers "F.Cu" "B.Cu")
		(net "GND")
	)
	(via
		(at 195.071746 -494.073942)
		(size 0.5588)
		(drill 0.3048)
		(layers "F.Cu" "B.Cu")
		(net "GND")
	)
	(via
		(at 145.668746 -175.3997)
		(size 0.7112)
		(drill 0.4064)
		(layers "F.Cu" "B.Cu")
		(net "GND")
	)
	(via
		(at 53.9496 -364.1598)
		(size 0.7112)
		(drill 0.4064)
		(layers "F.Cu" "B.Cu")
		(net "GND")
	)
	(via
		(at 176.656746 -132.3467)
		(size 0.7112)
		(drill 0.4064)
		(layers "F.Cu" "B.Cu")
		(net "GND")
	)
	(via
		(at 120.827546 -223.6343)
		(size 0.7112)
		(drill 0.4064)
		(layers "F.Cu" "B.Cu")
		(net "GND")
	)
	(via
		(at 252.475746 -237.3757)
		(size 0.7112)
		(drill 0.4064)
		(layers "F.Cu" "B.Cu")
		(net "GND")
	)
	(via
		(at 200.532746 -314.8457)
		(size 0.7112)
		(drill 0.4064)
		(layers "F.Cu" "B.Cu")
		(net "GND")
	)
	(via
		(at 141.350746 -118.7577)
		(size 0.7112)
		(drill 0.4064)
		(layers "F.Cu" "B.Cu")
		(net "GND")
	)
	(via
		(at 5.968746 -114.985546)
		(size 0.5588)
		(drill 0.3048)
		(layers "F.Cu" "B.Cu")
		(net "GND")
	)
	(via
		(at 58.648346 -365.0869)
		(size 0.7112)
		(drill 0.4064)
		(layers "F.Cu" "B.Cu")
		(net "GND")
	)
	(via
		(at 74.421746 -122.8217)
		(size 0.7112)
		(drill 0.4064)
		(layers "F.Cu" "B.Cu")
		(net "GND")
	)
	(via
		(at 22.631146 -108.2421)
		(size 0.7112)
		(drill 0.4064)
		(layers "F.Cu" "B.Cu")
		(net "GND")
	)
	(via
		(at 90.931746 -142.1003)
		(size 0.7112)
		(drill 0.4064)
		(layers "F.Cu" "B.Cu")
		(net "GND")
	)
	(via
		(at 61.620146 -304.3809)
		(size 0.7112)
		(drill 0.4064)
		(layers "F.Cu" "B.Cu")
		(net "GND")
	)
	(via
		(at 98.678746 -497.7257)
		(size 0.7112)
		(drill 0.4064)
		(layers "F.Cu" "B.Cu")
		(net "GND")
	)
	(via
		(at 34.543746 -477.9137)
		(size 0.5588)
		(drill 0.3048)
		(layers "F.Cu" "B.Cu")
		(net "GND")
	)
	(via
		(at 120.954546 -476.8723)
		(size 0.7112)
		(drill 0.4064)
		(layers "F.Cu" "B.Cu")
		(net "GND")
	)
	(via
		(at 249.808746 -117.8687)
		(size 0.7112)
		(drill 0.4064)
		(layers "F.Cu" "B.Cu")
		(net "GND")
	)
	(via
		(at 202.513946 -418.2491)
		(size 0.7112)
		(drill 0.4064)
		(layers "F.Cu" "B.Cu")
		(net "GND")
	)
	(via
		(at 134.365746 -407.5557)
		(size 0.7112)
		(drill 0.4064)
		(layers "F.Cu" "B.Cu")
		(net "GND")
	)
	(via
		(at 151.536146 -308.6227)
		(size 0.7112)
		(drill 0.4064)
		(layers "F.Cu" "B.Cu")
		(net "GND")
	)
	(via
		(at 246.887746 -256.8067)
		(size 0.7112)
		(drill 0.4064)
		(layers "F.Cu" "B.Cu")
		(net "GND")
	)
	(via
		(at 184.937146 -468.5665)
		(size 0.7112)
		(drill 0.4064)
		(layers "F.Cu" "B.Cu")
		(net "GND")
	)
	(via
		(at 62.357 -9.9314)
		(size 0.7112)
		(drill 0.4064)
		(layers "F.Cu" "B.Cu")
		(net "GND")
	)
	(via
		(at 37.363146 -62.3189)
		(size 0.5588)
		(drill 0.3048)
		(layers "F.Cu" "B.Cu")
		(net "GND")
	)
	(via
		(at 113.817146 -459.6003)
		(size 0.7112)
		(drill 0.4064)
		(layers "F.Cu" "B.Cu")
		(net "GND")
	)
	(via
		(at 221.509844 -489.196888)
		(size 0.5588)
		(drill 0.3048)
		(layers "F.Cu" "B.Cu")
		(net "GND")
	)
	(via
		(at 177.926746 -284.1117)
		(size 0.7112)
		(drill 0.4064)
		(layers "F.Cu" "B.Cu")
		(net "GND")
	)
	(via
		(at 208.101946 -104.9655)
		(size 0.7112)
		(drill 0.4064)
		(layers "F.Cu" "B.Cu")
		(net "GND")
	)
	(via
		(at 185.419746 -446.1383)
		(size 0.7112)
		(drill 0.4064)
		(layers "F.Cu" "B.Cu")
		(net "GND")
	)
	(via
		(at 239.394746 -232.6767)
		(size 0.7112)
		(drill 0.4064)
		(layers "F.Cu" "B.Cu")
		(net "GND")
	)
	(via
		(at 124.358146 -191.1223)
		(size 0.7112)
		(drill 0.4064)
		(layers "F.Cu" "B.Cu")
		(net "GND")
	)
	(via
		(at 211.632546 -474.5863)
		(size 0.7112)
		(drill 0.4064)
		(layers "F.Cu" "B.Cu")
		(net "GND")
	)
	(via
		(at 196.595746 -353.9363)
		(size 0.7112)
		(drill 0.4064)
		(layers "F.Cu" "B.Cu")
		(net "GND")
	)
	(via
		(at 75.209146 -4.3434)
		(size 0.5588)
		(drill 0.3048)
		(layers "F.Cu" "B.Cu")
		(net "GND")
	)
	(via
		(at 246.761 -475.361)
		(size 0.7112)
		(drill 0.4064)
		(layers "F.Cu" "B.Cu")
		(net "GND")
	)
	(via
		(at 187.756546 -436.0545)
		(size 0.7112)
		(drill 0.4064)
		(layers "F.Cu" "B.Cu")
		(net "GND")
	)
	(via
		(at 87.248746 -64.4017)
		(size 0.7112)
		(drill 0.4064)
		(layers "F.Cu" "B.Cu")
		(net "GND")
	)
	(via
		(at 259.663946 -435.8005)
		(size 0.7112)
		(drill 0.4064)
		(layers "F.Cu" "B.Cu")
		(net "GND")
	)
	(via
		(at 7.800848 -158.742634)
		(size 0.5588)
		(drill 0.3048)
		(layers "F.Cu" "B.Cu")
		(net "GND")
	)
	(via
		(at 206.247746 -328.5617)
		(size 0.7112)
		(drill 0.3556)
		(layers "F.Cu" "B.Cu")
		(net "GND")
	)
	(via
		(at 19.684746 -127.6477)
		(size 0.5588)
		(drill 0.3048)
		(layers "F.Cu" "B.Cu")
		(net "GND")
	)
	(via
		(at 167.080946 -327.2663)
		(size 0.7112)
		(drill 0.4064)
		(layers "F.Cu" "B.Cu")
		(net "GND")
	)
	(via
		(at 143.001746 -228.1047)
		(size 0.7112)
		(drill 0.4064)
		(layers "F.Cu" "B.Cu")
		(net "GND")
	)
	(via
		(at 189.788546 -383.3241)
		(size 0.7112)
		(drill 0.4064)
		(layers "F.Cu" "B.Cu")
		(net "GND")
	)
	(via
		(at 5.943346 -108.978954)
		(size 0.5588)
		(drill 0.3048)
		(layers "F.Cu" "B.Cu")
		(net "GND")
	)
	(via
		(at 191.515746 -279.4127)
		(size 0.7112)
		(drill 0.4064)
		(layers "F.Cu" "B.Cu")
		(net "GND")
	)
	(via
		(at 67.258946 -333.7179)
		(size 0.7112)
		(drill 0.4064)
		(layers "F.Cu" "B.Cu")
		(net "GND")
	)
	(via
		(at 145.008346 -240.4999)
		(size 0.7112)
		(drill 0.4064)
		(layers "F.Cu" "B.Cu")
		(net "GND")
	)
	(via
		(at 221.509844 -283.196792)
		(size 0.5588)
		(drill 0.3048)
		(layers "F.Cu" "B.Cu")
		(net "GND")
	)
	(via
		(at 5.9944 -103.0478)
		(size 0.5588)
		(drill 0.3048)
		(layers "F.Cu" "B.Cu")
		(net "GND")
	)
	(via
		(at 150.062946 -413.4739)
		(size 0.7112)
		(drill 0.4064)
		(layers "F.Cu" "B.Cu")
		(net "GND")
	)
	(via
		(at 235.203746 -314.7187)
		(size 0.7112)
		(drill 0.4064)
		(layers "F.Cu" "B.Cu")
		(net "GND")
	)
	(via
		(at 61.721746 -421.1447)
		(size 0.7112)
		(drill 0.4064)
		(layers "F.Cu" "B.Cu")
		(net "GND")
	)
	(via
		(at 32.156146 -454.5711)
		(size 0.7112)
		(drill 0.4064)
		(layers "F.Cu" "B.Cu")
		(net "GND")
	)
	(via
		(at 134.238746 -370.9035)
		(size 0.7112)
		(drill 0.4064)
		(layers "F.Cu" "B.Cu")
		(net "GND")
	)
	(via
		(at 235.076746 -359.8037)
		(size 0.7112)
		(drill 0.4064)
		(layers "F.Cu" "B.Cu")
		(net "GND")
	)
	(via
		(at 120.167146 -35.8267)
		(size 0.7112)
		(drill 0.4064)
		(layers "F.Cu" "B.Cu")
		(net "GND")
	)
	(via
		(at 72.8218 -385.0894)
		(size 0.7112)
		(drill 0.4064)
		(layers "F.Cu" "B.Cu")
		(net "GND")
	)
	(via
		(at 224.281746 -426.2755)
		(size 0.7112)
		(drill 0.4064)
		(layers "F.Cu" "B.Cu")
		(net "GND")
	)
	(via
		(at 193.827146 -202.2729)
		(size 0.7112)
		(drill 0.4064)
		(layers "F.Cu" "B.Cu")
		(net "GND")
	)
	(via
		(at 10.159746 -146.4437)
		(size 0.7112)
		(drill 0.4064)
		(layers "F.Cu" "B.Cu")
		(net "GND")
	)
	(via
		(at 228.345746 -158.0007)
		(size 0.7112)
		(drill 0.4064)
		(layers "F.Cu" "B.Cu")
		(net "GND")
	)
	(via
		(at 106.730546 -99.4029)
		(size 0.7112)
		(drill 0.4064)
		(layers "F.Cu" "B.Cu")
		(net "GND")
	)
	(via
		(at 152.145746 -262.9027)
		(size 0.7112)
		(drill 0.4064)
		(layers "F.Cu" "B.Cu")
		(net "GND")
	)
	(via
		(at 167.461946 -501.9675)
		(size 0.7112)
		(drill 0.4064)
		(layers "F.Cu" "B.Cu")
		(net "GND")
	)
	(via
		(at 184.276746 -41.2877)
		(size 0.7112)
		(drill 0.4064)
		(layers "F.Cu" "B.Cu")
		(net "GND")
	)
	(via
		(at 52.577746 -1.2827)
		(size 0.7112)
		(drill 0.4064)
		(layers "F.Cu" "B.Cu")
		(net "GND")
	)
	(via
		(at 146.583146 -127.7239)
		(size 0.7112)
		(drill 0.4064)
		(layers "F.Cu" "B.Cu")
		(net "GND")
	)
	(via
		(at 139.191746 -485.4829)
		(size 0.7112)
		(drill 0.4064)
		(layers "F.Cu" "B.Cu")
		(net "GND")
	)
	(via
		(at 255.853946 -101.7143)
		(size 0.7112)
		(drill 0.4064)
		(layers "F.Cu" "B.Cu")
		(net "GND")
	)
	(via
		(at 23.0378 -201.3966)
		(size 0.5588)
		(drill 0.3048)
		(layers "F.Cu" "B.Cu")
		(net "GND")
	)
	(via
		(at 59.511946 -313.0931)
		(size 0.7112)
		(drill 0.4064)
		(layers "F.Cu" "B.Cu")
		(net "GND")
	)
	(via
		(at 247.6754 -341.0204)
		(size 0.7112)
		(drill 0.4064)
		(layers "F.Cu" "B.Cu")
		(net "GND")
	)
	(via
		(at 121.919746 -152.0317)
		(size 0.7112)
		(drill 0.4064)
		(layers "F.Cu" "B.Cu")
		(net "GND")
	)
	(via
		(at 23.144734 -414.667446)
		(size 0.7112)
		(drill 0.4064)
		(layers "F.Cu" "B.Cu")
		(net "GND")
	)
	(via
		(at 37.972746 -253.4031)
		(size 0.7112)
		(drill 0.4064)
		(layers "F.Cu" "B.Cu")
		(net "GND")
	)
	(via
		(at 59.029346 -225.1837)
		(size 0.7112)
		(drill 0.4064)
		(layers "F.Cu" "B.Cu")
		(net "GND")
	)
	(via
		(at 259.460746 -54.1147)
		(size 0.7112)
		(drill 0.4064)
		(layers "F.Cu" "B.Cu")
		(net "GND")
	)
	(via
		(at 105.358946 -389.2169)
		(size 0.7112)
		(drill 0.4064)
		(layers "F.Cu" "B.Cu")
		(net "GND")
	)
	(via
		(at 110.616746 -131.8387)
		(size 0.7112)
		(drill 0.4064)
		(layers "F.Cu" "B.Cu")
		(net "GND")
	)
	(via
		(at 110.438946 -211.7471)
		(size 0.7112)
		(drill 0.4064)
		(layers "F.Cu" "B.Cu")
		(net "GND")
	)
	(via
		(at 58.308748 -229.644702)
		(size 0.5588)
		(drill 0.3048)
		(layers "F.Cu" "B.Cu")
		(net "GND")
	)
	(via
		(at 181.254146 -308.5211)
		(size 0.7112)
		(drill 0.4064)
		(layers "F.Cu" "B.Cu")
		(net "GND")
	)
	(via
		(at 62.483746 -340.1187)
		(size 0.7112)
		(drill 0.4064)
		(layers "F.Cu" "B.Cu")
		(net "GND")
	)
	(via
		(at 84.937346 -429.6791)
		(size 0.7112)
		(drill 0.4064)
		(layers "F.Cu" "B.Cu")
		(net "GND")
	)
	(via
		(at 136.854946 -113.0427)
		(size 0.7112)
		(drill 0.4064)
		(layers "F.Cu" "B.Cu")
		(net "GND")
	)
	(via
		(at 259.841746 -453.2757)
		(size 0.7112)
		(drill 0.4064)
		(layers "F.Cu" "B.Cu")
		(net "GND")
	)
	(via
		(at 162.305746 -326.7837)
		(size 0.7112)
		(drill 0.4064)
		(layers "F.Cu" "B.Cu")
		(net "GND")
	)
	(via
		(at 130.682746 -247.7897)
		(size 0.7112)
		(drill 0.4064)
		(layers "F.Cu" "B.Cu")
		(net "GND")
	)
	(via
		(at 194.690746 -177.5587)
		(size 0.7112)
		(drill 0.4064)
		(layers "F.Cu" "B.Cu")
		(net "GND")
	)
	(via
		(at 98.526346 -457.9239)
		(size 0.7112)
		(drill 0.4064)
		(layers "F.Cu" "B.Cu")
		(net "GND")
	)
	(via
		(at 187.146946 -487.5403)
		(size 0.7112)
		(drill 0.4064)
		(layers "F.Cu" "B.Cu")
		(net "GND")
	)
	(via
		(at 234.949746 -293.3827)
		(size 0.7112)
		(drill 0.4064)
		(layers "F.Cu" "B.Cu")
		(net "GND")
	)
	(via
		(at 41.909746 -273.1897)
		(size 0.7112)
		(drill 0.4064)
		(layers "F.Cu" "B.Cu")
		(net "GND")
	)
	(via
		(at 47.548546 -91.1987)
		(size 0.7112)
		(drill 0.4064)
		(layers "F.Cu" "B.Cu")
		(net "GND")
	)
	(via
		(at 6.1722 -62.8142)
		(size 0.5588)
		(drill 0.3048)
		(layers "F.Cu" "B.Cu")
		(net "GND")
	)
	(via
		(at 63.550546 -374.2817)
		(size 0.7112)
		(drill 0.4064)
		(layers "F.Cu" "B.Cu")
		(net "GND")
	)
	(via
		(at 77.139546 -263.6647)
		(size 0.7112)
		(drill 0.4064)
		(layers "F.Cu" "B.Cu")
		(net "GND")
	)
	(via
		(at 210.235546 -221.8563)
		(size 0.7112)
		(drill 0.4064)
		(layers "F.Cu" "B.Cu")
		(net "GND")
	)
	(via
		(at 137.235946 -243.0399)
		(size 0.7112)
		(drill 0.4064)
		(layers "F.Cu" "B.Cu")
		(net "GND")
	)
	(via
		(at 132.155946 -31.1023)
		(size 0.7112)
		(drill 0.4064)
		(layers "F.Cu" "B.Cu")
		(net "GND")
	)
	(via
		(at 209.3214 -436.8546)
		(size 0.7112)
		(drill 0.4064)
		(layers "F.Cu" "B.Cu")
		(net "GND")
	)
	(via
		(at 90.855546 -179.7685)
		(size 0.7112)
		(drill 0.4064)
		(layers "F.Cu" "B.Cu")
		(net "GND")
	)
	(via
		(at 86.385146 -242.0239)
		(size 0.7112)
		(drill 0.4064)
		(layers "F.Cu" "B.Cu")
		(net "GND")
	)
	(via
		(at 32.766 -161.6964)
		(size 0.5588)
		(drill 0.3048)
		(layers "F.Cu" "B.Cu")
		(net "GND")
	)
	(via
		(at 255.345946 -18.1229)
		(size 0.7112)
		(drill 0.4064)
		(layers "F.Cu" "B.Cu")
		(net "GND")
	)
	(via
		(at 107.517946 -257.3147)
		(size 0.7112)
		(drill 0.4064)
		(layers "F.Cu" "B.Cu")
		(net "GND")
	)
	(via
		(at 101.726746 -30.3657)
		(size 0.7112)
		(drill 0.4064)
		(layers "F.Cu" "B.Cu")
		(net "GND")
	)
	(via
		(at 166.877746 -256.4257)
		(size 0.7112)
		(drill 0.4064)
		(layers "F.Cu" "B.Cu")
		(net "GND")
	)
	(via
		(at 5.968746 -126.985522)
		(size 0.5588)
		(drill 0.3048)
		(layers "F.Cu" "B.Cu")
		(net "GND")
	)
	(via
		(at 125.348746 -484.8987)
		(size 0.7112)
		(drill 0.4064)
		(layers "F.Cu" "B.Cu")
		(net "GND")
	)
	(via
		(at 141.858746 -271.5387)
		(size 0.7112)
		(drill 0.4064)
		(layers "F.Cu" "B.Cu")
		(net "GND")
	)
	(via
		(at 125.475746 -214.7697)
		(size 0.7112)
		(drill 0.4064)
		(layers "F.Cu" "B.Cu")
		(net "GND")
	)
	(via
		(at 226.186746 -326.5297)
		(size 0.7112)
		(drill 0.4064)
		(layers "F.Cu" "B.Cu")
		(net "GND")
	)
	(via
		(at 8.843264 -414.262062)
		(size 0.5588)
		(drill 0.3048)
		(layers "F.Cu" "B.Cu")
		(net "GND")
	)
	(via
		(at 80.517746 -79.394304)
		(size 0.7112)
		(drill 0.4064)
		(layers "F.Cu" "B.Cu")
		(net "GND")
	)
	(via
		(at 239.521746 -222.8977)
		(size 0.7112)
		(drill 0.4064)
		(layers "F.Cu" "B.Cu")
		(net "GND")
	)
	(via
		(at 88.391746 -489.0897)
		(size 0.7112)
		(drill 0.4064)
		(layers "F.Cu" "B.Cu")
		(net "GND")
	)
	(via
		(at 146.303746 -198.7677)
		(size 0.7112)
		(drill 0.4064)
		(layers "F.Cu" "B.Cu")
		(net "GND")
	)
	(via
		(at 113.893346 -431.6603)
		(size 0.7112)
		(drill 0.4064)
		(layers "F.Cu" "B.Cu")
		(net "GND")
	)
	(via
		(at 159.384746 -357.1367)
		(size 0.7112)
		(drill 0.4064)
		(layers "F.Cu" "B.Cu")
		(net "GND")
	)
	(via
		(at 93.852746 -71.7677)
		(size 0.7112)
		(drill 0.4064)
		(layers "F.Cu" "B.Cu")
		(net "GND")
	)
	(via
		(at 56.2102 -500.6848)
		(size 0.7112)
		(drill 0.4064)
		(layers "F.Cu" "B.Cu")
		(net "GND")
	)
	(via
		(at 62.23 -164.338)
		(size 0.7112)
		(drill 0.4064)
		(layers "F.Cu" "B.Cu")
		(net "GND")
	)
	(via
		(at 250.570746 -155.8417)
		(size 0.7112)
		(drill 0.4064)
		(layers "F.Cu" "B.Cu")
		(net "GND")
	)
	(via
		(at 128.676146 -309.0799)
		(size 0.7112)
		(drill 0.4064)
		(layers "F.Cu" "B.Cu")
		(net "GND")
	)
	(via
		(at 10.2616 -440.8424)
		(size 0.5588)
		(drill 0.3048)
		(layers "F.Cu" "B.Cu")
		(net "GND")
	)
	(via
		(at 35.940746 -301.1297)
		(size 0.7112)
		(drill 0.4064)
		(layers "F.Cu" "B.Cu")
		(net "GND")
	)
	(via
		(at 169.290746 -134.1247)
		(size 0.7112)
		(drill 0.4064)
		(layers "F.Cu" "B.Cu")
		(net "GND")
	)
	(via
		(at 78.460346 -179.1081)
		(size 0.7112)
		(drill 0.4064)
		(layers "F.Cu" "B.Cu")
		(net "GND")
	)
	(via
		(at 141.198346 -433.5145)
		(size 0.7112)
		(drill 0.4064)
		(layers "F.Cu" "B.Cu")
		(net "GND")
	)
	(via
		(at 258.317746 -309.6387)
		(size 0.7112)
		(drill 0.4064)
		(layers "F.Cu" "B.Cu")
		(net "GND")
	)
	(via
		(at 235.203746 -306.5907)
		(size 0.7112)
		(drill 0.4064)
		(layers "F.Cu" "B.Cu")
		(net "GND")
	)
	(via
		(at 246.379746 -185.5597)
		(size 0.7112)
		(drill 0.4064)
		(layers "F.Cu" "B.Cu")
		(net "GND")
	)
	(via
		(at 108.584746 -158.6357)
		(size 0.7112)
		(drill 0.4064)
		(layers "F.Cu" "B.Cu")
		(net "GND")
	)
	(via
		(at 259.206746 -205.6257)
		(size 0.7112)
		(drill 0.4064)
		(layers "F.Cu" "B.Cu")
		(net "GND")
	)
	(via
		(at 174.364142 -461.86725)
		(size 0.7112)
		(drill 0.4064)
		(layers "F.Cu" "B.Cu")
		(net "GND")
	)
	(via
		(at 252.297946 -440.5249)
		(size 0.7112)
		(drill 0.4064)
		(layers "F.Cu" "B.Cu")
		(net "GND")
	)
	(via
		(at 85.284818 -422.33469)
		(size 0.7112)
		(drill 0.4064)
		(layers "F.Cu" "B.Cu")
		(net "GND")
	)
	(via
		(at 24.4094 -351.7011)
		(size 0.7112)
		(drill 0.4064)
		(layers "F.Cu" "B.Cu")
		(net "GND")
	)
	(via
		(at 186.943746 -310.0197)
		(size 0.7112)
		(drill 0.4064)
		(layers "F.Cu" "B.Cu")
		(net "GND")
	)
	(via
		(at 156.336746 -492.8997)
		(size 0.7112)
		(drill 0.4064)
		(layers "F.Cu" "B.Cu")
		(net "GND")
	)
	(via
		(at 84.327746 -172.3517)
		(size 0.7112)
		(drill 0.4064)
		(layers "F.Cu" "B.Cu")
		(net "GND")
	)
	(via
		(at 128.218946 -499.7577)
		(size 0.7112)
		(drill 0.4064)
		(layers "F.Cu" "B.Cu")
		(net "GND")
	)
	(via
		(at 201.167746 -462.0387)
		(size 0.5588)
		(drill 0.3048)
		(layers "F.Cu" "B.Cu")
		(net "GND")
	)
	(via
		(at 213.359746 -294.0177)
		(size 0.7112)
		(drill 0.4064)
		(layers "F.Cu" "B.Cu")
		(net "GND")
	)
	(via
		(at 107.517946 -363.3089)
		(size 0.7112)
		(drill 0.4064)
		(layers "F.Cu" "B.Cu")
		(net "GND")
	)
	(via
		(at 52.577746 -474.3577)
		(size 0.7112)
		(drill 0.4064)
		(layers "F.Cu" "B.Cu")
		(net "GND")
	)
	(via
		(at 81.863946 -457.7461)
		(size 0.7112)
		(drill 0.4064)
		(layers "F.Cu" "B.Cu")
		(net "GND")
	)
	(via
		(at 169.544746 -144.2847)
		(size 0.7112)
		(drill 0.4064)
		(layers "F.Cu" "B.Cu")
		(net "GND")
	)
	(via
		(at 143.204946 -42.6085)
		(size 0.7112)
		(drill 0.4064)
		(layers "F.Cu" "B.Cu")
		(net "GND")
	)
	(via
		(at 112.775746 -471.4113)
		(size 0.7112)
		(drill 0.4064)
		(layers "F.Cu" "B.Cu")
		(net "GND")
	)
	(via
		(at 62.331346 -230.4923)
		(size 0.7112)
		(drill 0.4064)
		(layers "F.Cu" "B.Cu")
		(net "GND")
	)
	(via
		(at 181.127146 -142.6337)
		(size 0.7112)
		(drill 0.4064)
		(layers "F.Cu" "B.Cu")
		(net "GND")
	)
	(via
		(at 43.840146 -196.6595)
		(size 0.7112)
		(drill 0.4064)
		(layers "F.Cu" "B.Cu")
		(net "GND")
	)
	(via
		(at 34.213546 -90.4367)
		(size 0.7112)
		(drill 0.4064)
		(layers "F.Cu" "B.Cu")
		(net "GND")
	)
	(via
		(at 81.736946 -44.1833)
		(size 0.7112)
		(drill 0.4064)
		(layers "F.Cu" "B.Cu")
		(net "GND")
	)
	(via
		(at 74.421746 -188.8871)
		(size 0.5588)
		(drill 0.3048)
		(layers "F.Cu" "B.Cu")
		(net "GND")
	)
	(via
		(at 72.516746 -355.4857)
		(size 0.7112)
		(drill 0.4064)
		(layers "F.Cu" "B.Cu")
		(net "GND")
	)
	(via
		(at 57.225946 -243.2431)
		(size 0.7112)
		(drill 0.4064)
		(layers "F.Cu" "B.Cu")
		(net "GND")
	)
	(via
		(at 58.572146 -355.6635)
		(size 0.7112)
		(drill 0.4064)
		(layers "F.Cu" "B.Cu")
		(net "GND")
	)
	(via
		(at 149.326346 -494.7539)
		(size 0.7112)
		(drill 0.4064)
		(layers "F.Cu" "B.Cu")
		(net "GND")
	)
	(via
		(at 7.619746 -162.6997)
		(size 0.5588)
		(drill 0.3048)
		(layers "F.Cu" "B.Cu")
		(net "GND")
	)
	(via
		(at 148.792946 -501.9675)
		(size 0.7112)
		(drill 0.4064)
		(layers "F.Cu" "B.Cu")
		(net "GND")
	)
	(via
		(at 225.3996 -271.9324)
		(size 0.7112)
		(drill 0.4064)
		(layers "F.Cu" "B.Cu")
		(net "GND")
	)
	(via
		(at 259.079746 -279.1587)
		(size 0.7112)
		(drill 0.4064)
		(layers "F.Cu" "B.Cu")
		(net "GND")
	)
	(via
		(at 142.900146 -483.2223)
		(size 0.7112)
		(drill 0.4064)
		(layers "F.Cu" "B.Cu")
		(net "GND")
	)
	(via
		(at 78.587346 -130.4163)
		(size 0.7112)
		(drill 0.4064)
		(layers "F.Cu" "B.Cu")
		(net "GND")
	)
	(via
		(at 20.009866 -333.416656)
		(size 0.5588)
		(drill 0.3048)
		(layers "F.Cu" "B.Cu")
		(net "GND")
	)
	(via
		(at 36.237418 -335.081372)
		(size 0.5588)
		(drill 0.3048)
		(layers "F.Cu" "B.Cu")
		(net "GND")
	)
	(via
		(at 75.285346 -182.1053)
		(size 0.7112)
		(drill 0.4064)
		(layers "F.Cu" "B.Cu")
		(net "GND")
	)
	(via
		(at 67.385946 -340.2711)
		(size 0.7112)
		(drill 0.4064)
		(layers "F.Cu" "B.Cu")
		(net "GND")
	)
	(via
		(at 20.009866 -330.876656)
		(size 0.5588)
		(drill 0.3048)
		(layers "F.Cu" "B.Cu")
		(net "GND")
	)
	(via
		(at 56.006746 -142.2527)
		(size 0.7112)
		(drill 0.4064)
		(layers "F.Cu" "B.Cu")
		(net "GND")
	)
	(via
		(at 39.750746 -250.4313)
		(size 0.7112)
		(drill 0.4064)
		(layers "F.Cu" "B.Cu")
		(net "GND")
	)
	(via
		(at 170.357546 -407.2001)
		(size 0.7112)
		(drill 0.4064)
		(layers "F.Cu" "B.Cu")
		(net "GND")
	)
	(via
		(at 240.512346 -31.1277)
		(size 0.5588)
		(drill 0.3048)
		(layers "F.Cu" "B.Cu")
		(net "GND")
	)
	(via
		(at 152.018746 -272.3007)
		(size 0.7112)
		(drill 0.4064)
		(layers "F.Cu" "B.Cu")
		(net "GND")
	)
	(via
		(at 238.124746 -481.0379)
		(size 0.7112)
		(drill 0.4064)
		(layers "F.Cu" "B.Cu")
		(net "GND")
	)
	(via
		(at 117.347746 -245.3767)
		(size 0.7112)
		(drill 0.4064)
		(layers "F.Cu" "B.Cu")
		(net "GND")
	)
	(via
		(at 125.247146 -253.0729)
		(size 0.7112)
		(drill 0.4064)
		(layers "F.Cu" "B.Cu")
		(net "GND")
	)
	(via
		(at 112.724946 -323.6595)
		(size 0.7112)
		(drill 0.4064)
		(layers "F.Cu" "B.Cu")
		(net "GND")
	)
	(via
		(at 233.933746 -271.6657)
		(size 0.7112)
		(drill 0.4064)
		(layers "F.Cu" "B.Cu")
		(net "GND")
	)
	(via
		(at 259.079746 -250.5837)
		(size 0.7112)
		(drill 0.4064)
		(layers "F.Cu" "B.Cu")
		(net "GND")
	)
	(via
		(at 241.248946 -274.5613)
		(size 0.7112)
		(drill 0.4064)
		(layers "F.Cu" "B.Cu")
		(net "GND")
	)
	(via
		(at 145.262346 -250.6599)
		(size 0.7112)
		(drill 0.4064)
		(layers "F.Cu" "B.Cu")
		(net "GND")
	)
	(via
		(at 106.705146 -315.3537)
		(size 0.7112)
		(drill 0.4064)
		(layers "F.Cu" "B.Cu")
		(net "GND")
	)
	(via
		(at 120.167146 -40.6527)
		(size 0.7112)
		(drill 0.4064)
		(layers "F.Cu" "B.Cu")
		(net "GND")
	)
	(via
		(at 219.7862 -472.1098)
		(size 0.5588)
		(drill 0.3048)
		(layers "F.Cu" "B.Cu")
		(net "GND")
	)
	(via
		(at 216.407746 -314.3377)
		(size 0.7112)
		(drill 0.4064)
		(layers "F.Cu" "B.Cu")
		(net "GND")
	)
	(via
		(at 209.524346 -6.3881)
		(size 0.7112)
		(drill 0.4064)
		(layers "F.Cu" "B.Cu")
		(net "GND")
	)
	(via
		(at 12.775946 -494.4491)
		(size 0.5588)
		(drill 0.3048)
		(layers "F.Cu" "B.Cu")
		(net "GND")
	)
	(via
		(at 172.338746 -170.4467)
		(size 0.7112)
		(drill 0.4064)
		(layers "F.Cu" "B.Cu")
		(net "GND")
	)
	(via
		(at 82.295746 -400.6215)
		(size 0.5588)
		(drill 0.3048)
		(layers "F.Cu" "B.Cu")
		(net "GND")
	)
	(via
		(at 83.819746 -436.1053)
		(size 0.7112)
		(drill 0.4064)
		(layers "F.Cu" "B.Cu")
		(net "GND")
	)
	(via
		(at 86.842346 -168.8973)
		(size 0.7112)
		(drill 0.4064)
		(layers "F.Cu" "B.Cu")
		(net "GND")
	)
	(via
		(at 188.823346 -471.3859)
		(size 0.7112)
		(drill 0.4064)
		(layers "F.Cu" "B.Cu")
		(net "GND")
	)
	(via
		(at 235.712 -461.899)
		(size 0.7112)
		(drill 0.4064)
		(layers "F.Cu" "B.Cu")
		(net "GND")
	)
	(via
		(at 173.735746 -86.3727)
		(size 0.7112)
		(drill 0.4064)
		(layers "F.Cu" "B.Cu")
		(net "GND")
	)
	(via
		(at 179.425346 -471.3859)
		(size 0.7112)
		(drill 0.4064)
		(layers "F.Cu" "B.Cu")
		(net "GND")
	)
	(via
		(at 169.849546 -311.8231)
		(size 0.7112)
		(drill 0.4064)
		(layers "F.Cu" "B.Cu")
		(net "GND")
	)
	(via
		(at 195.117212 -84.826856)
		(size 0.5588)
		(drill 0.3048)
		(layers "F.Cu" "B.Cu")
		(net "GND")
	)
	(via
		(at 239.776 -383.8702)
		(size 0.7112)
		(drill 0.4064)
		(layers "F.Cu" "B.Cu")
		(net "GND")
	)
	(via
		(at 206.565246 -41.6052)
		(size 0.5588)
		(drill 0.3048)
		(layers "F.Cu" "B.Cu")
		(net "GND")
	)
	(via
		(at 124.967746 -283.3497)
		(size 0.7112)
		(drill 0.4064)
		(layers "F.Cu" "B.Cu")
		(net "GND")
	)
	(via
		(at 6.070346 -243.3193)
		(size 0.7112)
		(drill 0.4064)
		(layers "F.Cu" "B.Cu")
		(net "GND")
	)
	(via
		(at 213.614 -170.4594)
		(size 0.7112)
		(drill 0.4064)
		(layers "F.Cu" "B.Cu")
		(net "GND")
	)
	(via
		(at 246.634 -457.962)
		(size 0.7112)
		(drill 0.4064)
		(layers "F.Cu" "B.Cu")
		(net "GND")
	)
	(via
		(at 53.974746 -307.9877)
		(size 0.7112)
		(drill 0.4064)
		(layers "F.Cu" "B.Cu")
		(net "GND")
	)
	(via
		(at 149.351746 -55.1307)
		(size 0.7112)
		(drill 0.4064)
		(layers "F.Cu" "B.Cu")
		(net "GND")
	)
	(via
		(at 40.894 -162.3314)
		(size 0.5588)
		(drill 0.3048)
		(layers "F.Cu" "B.Cu")
		(net "GND")
	)
	(via
		(at 71.246746 -436.5117)
		(size 0.7112)
		(drill 0.4064)
		(layers "F.Cu" "B.Cu")
		(net "GND")
	)
	(via
		(at 82.606134 -489.527088)
		(size 0.5588)
		(drill 0.3048)
		(layers "F.Cu" "B.Cu")
		(net "GND")
	)
	(via
		(at 171.424346 -487.7689)
		(size 0.7112)
		(drill 0.4064)
		(layers "F.Cu" "B.Cu")
		(net "GND")
	)
	(via
		(at 221.446344 -360.79684)
		(size 0.7112)
		(drill 0.4064)
		(layers "F.Cu" "B.Cu")
		(net "GND")
	)
	(via
		(at 191.007746 -207.5307)
		(size 0.7112)
		(drill 0.4064)
		(layers "F.Cu" "B.Cu")
		(net "GND")
	)
	(via
		(at 6.375146 -239.3061)
		(size 0.7112)
		(drill 0.4064)
		(layers "F.Cu" "B.Cu")
		(net "GND")
	)
	(via
		(at 19.430746 -384.0607)
		(size 0.7112)
		(drill 0.4064)
		(layers "F.Cu" "B.Cu")
		(net "GND")
	)
	(via
		(at 221.177358 -257.796792)
		(size 0.7112)
		(drill 0.4064)
		(layers "F.Cu" "B.Cu")
		(net "GND")
	)
	(via
		(at 172.211746 -55.3847)
		(size 0.7112)
		(drill 0.4064)
		(layers "F.Cu" "B.Cu")
		(net "GND")
	)
	(via
		(at 224.662746 -202.9587)
		(size 0.7112)
		(drill 0.4064)
		(layers "F.Cu" "B.Cu")
		(net "GND")
	)
	(via
		(at 152.780746 -238.0107)
		(size 0.7112)
		(drill 0.4064)
		(layers "F.Cu" "B.Cu")
		(net "GND")
	)
	(via
		(at 216.915746 -107.8357)
		(size 0.7112)
		(drill 0.4064)
		(layers "F.Cu" "B.Cu")
		(net "GND")
	)
	(via
		(at 154.584146 -459.9305)
		(size 0.7112)
		(drill 0.4064)
		(layers "F.Cu" "B.Cu")
		(net "GND")
	)
	(via
		(at 110.565946 -193.8401)
		(size 0.7112)
		(drill 0.4064)
		(layers "F.Cu" "B.Cu")
		(net "GND")
	)
	(via
		(at 79.4766 -347.1926)
		(size 0.7112)
		(drill 0.4064)
		(layers "F.Cu" "B.Cu")
		(net "GND")
	)
	(via
		(at 29.082746 -363.7407)
		(size 0.5588)
		(drill 0.3048)
		(layers "F.Cu" "B.Cu")
		(net "GND")
	)
	(via
		(at 188.162946 -329.8825)
		(size 0.7112)
		(drill 0.4064)
		(layers "F.Cu" "B.Cu")
		(net "GND")
	)
	(via
		(at 135.001 -504.825)
		(size 0.7112)
		(drill 0.4064)
		(layers "F.Cu" "B.Cu")
		(net "GND")
	)
	(via
		(at 108.711746 -143.6497)
		(size 0.7112)
		(drill 0.4064)
		(layers "F.Cu" "B.Cu")
		(net "GND")
	)
	(via
		(at 120.217946 -502.2215)
		(size 0.7112)
		(drill 0.4064)
		(layers "F.Cu" "B.Cu")
		(net "GND")
	)
	(via
		(at 61.204856 -491.264702)
		(size 0.5588)
		(drill 0.3048)
		(layers "F.Cu" "B.Cu")
		(net "GND")
	)
	(via
		(at 6.412738 -392.915648)
		(size 0.5588)
		(drill 0.3048)
		(layers "F.Cu" "B.Cu")
		(net "GND")
	)
	(via
		(at 241.883946 -91.8591)
		(size 0.7112)
		(drill 0.4064)
		(layers "F.Cu" "B.Cu")
		(net "GND")
	)
	(via
		(at 90.931746 -91.1987)
		(size 0.7112)
		(drill 0.4064)
		(layers "F.Cu" "B.Cu")
		(net "GND")
	)
	(via
		(at 197.484746 -504.8377)
		(size 0.7112)
		(drill 0.4064)
		(layers "F.Cu" "B.Cu")
		(net "GND")
	)
	(via
		(at 216.026746 -502.3993)
		(size 0.7112)
		(drill 0.4064)
		(layers "F.Cu" "B.Cu")
		(net "GND")
	)
	(via
		(at 79.628746 -297.2181)
		(size 0.7112)
		(drill 0.4064)
		(layers "F.Cu" "B.Cu")
		(net "GND")
	)
	(via
		(at 62.610746 -21.8567)
		(size 0.5588)
		(drill 0.3048)
		(layers "F.Cu" "B.Cu")
		(net "GND")
	)
	(via
		(at 105.663746 -407.2255)
		(size 0.7112)
		(drill 0.4064)
		(layers "F.Cu" "B.Cu")
		(net "GND")
	)
	(via
		(at 256.692146 -29.3497)
		(size 0.7112)
		(drill 0.4064)
		(layers "F.Cu" "B.Cu")
		(net "GND")
	)
	(via
		(at 244.220746 -25.4127)
		(size 0.5588)
		(drill 0.3048)
		(layers "F.Cu" "B.Cu")
		(net "GND")
	)
	(via
		(at 26.695146 -370.6241)
		(size 0.5588)
		(drill 0.3048)
		(layers "F.Cu" "B.Cu")
		(net "GND")
	)
	(via
		(at 77.215746 -457.4159)
		(size 0.7112)
		(drill 0.4064)
		(layers "F.Cu" "B.Cu")
		(net "GND")
	)
	(via
		(at 216.026746 -325.7677)
		(size 0.7112)
		(drill 0.4064)
		(layers "F.Cu" "B.Cu")
		(net "GND")
	)
	(via
		(at 180.136546 -498.5893)
		(size 0.7112)
		(drill 0.4064)
		(layers "F.Cu" "B.Cu")
		(net "GND")
	)
	(via
		(at 194.690746 -179.2097)
		(size 0.7112)
		(drill 0.4064)
		(layers "F.Cu" "B.Cu")
		(net "GND")
	)
	(via
		(at 74.675746 -160.1597)
		(size 0.7112)
		(drill 0.4064)
		(layers "F.Cu" "B.Cu")
		(net "GND")
	)
	(via
		(at 202.488546 -474.5863)
		(size 0.7112)
		(drill 0.4064)
		(layers "F.Cu" "B.Cu")
		(net "GND")
	)
	(via
		(at 188.747146 -199.4789)
		(size 0.7112)
		(drill 0.4064)
		(layers "F.Cu" "B.Cu")
		(net "GND")
	)
	(via
		(at 10.159746 -86.8807)
		(size 0.7112)
		(drill 0.4064)
		(layers "F.Cu" "B.Cu")
		(net "GND")
	)
	(via
		(at 67.741546 -107.9627)
		(size 0.7112)
		(drill 0.4064)
		(layers "F.Cu" "B.Cu")
		(net "GND")
	)
	(via
		(at 120.904 -504.698)
		(size 0.7112)
		(drill 0.4064)
		(layers "F.Cu" "B.Cu")
		(net "GND")
	)
	(via
		(at 5.968746 -172.98543)
		(size 0.5588)
		(drill 0.3048)
		(layers "F.Cu" "B.Cu")
		(net "GND")
	)
	(via
		(at 117.728746 -275.2979)
		(size 0.7112)
		(drill 0.4064)
		(layers "F.Cu" "B.Cu")
		(net "GND")
	)
	(via
		(at 128.472946 -480.8347)
		(size 0.7112)
		(drill 0.4064)
		(layers "F.Cu" "B.Cu")
		(net "GND")
	)
	(via
		(at 93.979746 -483.0953)
		(size 0.7112)
		(drill 0.4064)
		(layers "F.Cu" "B.Cu")
		(net "GND")
	)
	(via
		(at 50.546 -207.01)
		(size 0.5588)
		(drill 0.3048)
		(layers "F.Cu" "B.Cu")
		(net "GND")
	)
	(via
		(at 246.252746 -162.3187)
		(size 0.7112)
		(drill 0.4064)
		(layers "F.Cu" "B.Cu")
		(net "GND")
	)
	(via
		(at 211.988146 -137.9347)
		(size 0.7112)
		(drill 0.4064)
		(layers "F.Cu" "B.Cu")
		(net "GND")
	)
	(via
		(at 97.281746 -70.2691)
		(size 0.7112)
		(drill 0.4064)
		(layers "F.Cu" "B.Cu")
		(net "GND")
	)
	(via
		(at 95.123 -247.269)
		(size 0.7112)
		(drill 0.4064)
		(layers "F.Cu" "B.Cu")
		(net "GND")
	)
	(via
		(at 166.750746 -77.9907)
		(size 0.7112)
		(drill 0.4064)
		(layers "F.Cu" "B.Cu")
		(net "GND")
	)
	(via
		(at 79.628746 -215.3539)
		(size 0.7112)
		(drill 0.4064)
		(layers "F.Cu" "B.Cu")
		(net "GND")
	)
	(via
		(at 68.732146 -357.7717)
		(size 0.7112)
		(drill 0.4064)
		(layers "F.Cu" "B.Cu")
		(net "GND")
	)
	(via
		(at 9.1694 -480.6188)
		(size 0.7112)
		(drill 0.4064)
		(layers "F.Cu" "B.Cu")
		(net "GND")
	)
	(via
		(at 259.333746 -472.4527)
		(size 0.7112)
		(drill 0.4064)
		(layers "F.Cu" "B.Cu")
		(net "GND")
	)
	(via
		(at 12.1412 -442.087)
		(size 0.5588)
		(drill 0.3048)
		(layers "F.Cu" "B.Cu")
		(net "GND")
	)
	(via
		(at 36.702746 -37.8587)
		(size 0.7112)
		(drill 0.4064)
		(layers "F.Cu" "B.Cu")
		(net "GND")
	)
	(via
		(at 152.729946 -367.7031)
		(size 0.7112)
		(drill 0.4064)
		(layers "F.Cu" "B.Cu")
		(net "GND")
	)
	(via
		(at 185.419746 -219.1639)
		(size 0.7112)
		(drill 0.4064)
		(layers "F.Cu" "B.Cu")
		(net "GND")
	)
	(via
		(at 152.018746 -320.4337)
		(size 0.7112)
		(drill 0.4064)
		(layers "F.Cu" "B.Cu")
		(net "GND")
	)
	(via
		(at 156.590746 -283.2227)
		(size 0.7112)
		(drill 0.4064)
		(layers "F.Cu" "B.Cu")
		(net "GND")
	)
	(via
		(at 159.435546 -290.4617)
		(size 0.7112)
		(drill 0.4064)
		(layers "F.Cu" "B.Cu")
		(net "GND")
	)
	(via
		(at 201.167746 -328.7903)
		(size 0.7112)
		(drill 0.4064)
		(layers "F.Cu" "B.Cu")
		(net "GND")
	)
	(via
		(at 52.552346 -43.5991)
		(size 0.7112)
		(drill 0.4064)
		(layers "F.Cu" "B.Cu")
		(net "GND")
	)
	(via
		(at 172.846746 -1.6637)
		(size 0.7112)
		(drill 0.4064)
		(layers "F.Cu" "B.Cu")
		(net "GND")
	)
	(via
		(at 90.525346 -114.7445)
		(size 0.7112)
		(drill 0.4064)
		(layers "F.Cu" "B.Cu")
		(net "GND")
	)
	(via
		(at 44.856146 -367.6523)
		(size 0.7112)
		(drill 0.4064)
		(layers "F.Cu" "B.Cu")
		(net "GND")
	)
	(via
		(at 13.292582 -162.88893)
		(size 0.7112)
		(drill 0.4064)
		(layers "F.Cu" "B.Cu")
		(net "GND")
	)
	(via
		(at 126.720346 -352.1583)
		(size 0.7112)
		(drill 0.4064)
		(layers "F.Cu" "B.Cu")
		(net "GND")
	)
	(via
		(at 53.593746 -56.2737)
		(size 0.7112)
		(drill 0.4064)
		(layers "F.Cu" "B.Cu")
		(net "GND")
	)
	(via
		(at 4.953 -41.021)
		(size 0.7112)
		(drill 0.4064)
		(layers "F.Cu" "B.Cu")
		(net "GND")
	)
	(via
		(at 49.885346 -314.1091)
		(size 0.7112)
		(drill 0.4064)
		(layers "F.Cu" "B.Cu")
		(net "GND")
	)
	(via
		(at 58.165746 -194.4497)
		(size 0.5588)
		(drill 0.3048)
		(layers "F.Cu" "B.Cu")
		(net "GND")
	)
	(via
		(at 190.906146 -230.2129)
		(size 0.7112)
		(drill 0.4064)
		(layers "F.Cu" "B.Cu")
		(net "GND")
	)
	(via
		(at 197.484746 -168.7957)
		(size 0.7112)
		(drill 0.4064)
		(layers "F.Cu" "B.Cu")
		(net "GND")
	)
	(via
		(at 141.604746 -368.8207)
		(size 0.7112)
		(drill 0.4064)
		(layers "F.Cu" "B.Cu")
		(net "GND")
	)
	(via
		(at 181.457346 -304.7365)
		(size 0.7112)
		(drill 0.4064)
		(layers "F.Cu" "B.Cu")
		(net "GND")
	)
	(via
		(at 66.979546 -345.3257)
		(size 0.7112)
		(drill 0.4064)
		(layers "F.Cu" "B.Cu")
		(net "GND")
	)
	(via
		(at 39.98976 -381.11684)
		(size 0.5588)
		(drill 0.3048)
		(layers "F.Cu" "B.Cu")
		(net "GND")
	)
	(via
		(at 23.961344 -450.370702)
		(size 0.7112)
		(drill 0.4064)
		(layers "F.Cu" "B.Cu")
		(net "GND")
	)
	(via
		(at 70.179946 -288.1757)
		(size 0.7112)
		(drill 0.4064)
		(layers "F.Cu" "B.Cu")
		(net "GND")
	)
	(via
		(at 247.014746 -276.3647)
		(size 0.7112)
		(drill 0.4064)
		(layers "F.Cu" "B.Cu")
		(net "GND")
	)
	(via
		(at 134.314946 -502.0945)
		(size 0.7112)
		(drill 0.4064)
		(layers "F.Cu" "B.Cu")
		(net "GND")
	)
	(via
		(at 5.7912 -137.0584)
		(size 0.5588)
		(drill 0.3048)
		(layers "F.Cu" "B.Cu")
		(net "GND")
	)
	(via
		(at 254.431546 -127.8509)
		(size 0.7112)
		(drill 0.4064)
		(layers "F.Cu" "B.Cu")
		(net "GND")
	)
	(via
		(at 197.103746 -486.6767)
		(size 0.7112)
		(drill 0.4064)
		(layers "F.Cu" "B.Cu")
		(net "GND")
	)
	(via
		(at 103.123746 -495.6937)
		(size 0.7112)
		(drill 0.4064)
		(layers "F.Cu" "B.Cu")
		(net "GND")
	)
	(via
		(at 133.984746 -324.6501)
		(size 0.7112)
		(drill 0.4064)
		(layers "F.Cu" "B.Cu")
		(net "GND")
	)
	(via
		(at 225.3996 -59.32297)
		(size 0.7112)
		(drill 0.4064)
		(layers "F.Cu" "B.Cu")
		(net "GND")
	)
	(via
		(at 90.423746 -191.2239)
		(size 0.7112)
		(drill 0.4064)
		(layers "F.Cu" "B.Cu")
		(net "GND")
	)
	(via
		(at 61.3664 -194.4878)
		(size 0.5588)
		(drill 0.3048)
		(layers "F.Cu" "B.Cu")
		(net "GND")
	)
	(via
		(at 252.221746 -232.0417)
		(size 0.7112)
		(drill 0.4064)
		(layers "F.Cu" "B.Cu")
		(net "GND")
	)
	(via
		(at 7.2898 -113.2078)
		(size 0.5588)
		(drill 0.3048)
		(layers "F.Cu" "B.Cu")
		(net "GND")
	)
	(via
		(at 116.839746 -361.7087)
		(size 0.7112)
		(drill 0.4064)
		(layers "F.Cu" "B.Cu")
		(net "GND")
	)
	(via
		(at 50.698146 -477.4819)
		(size 0.7112)
		(drill 0.4064)
		(layers "F.Cu" "B.Cu")
		(net "GND")
	)
	(via
		(at 226.694746 -311.0357)
		(size 0.7112)
		(drill 0.4064)
		(layers "F.Cu" "B.Cu")
		(net "GND")
	)
	(via
		(at 247.015 -388.3914)
		(size 0.7112)
		(drill 0.4064)
		(layers "F.Cu" "B.Cu")
		(net "GND")
	)
	(via
		(at 221.433644 -180.208428)
		(size 0.7112)
		(drill 0.4064)
		(layers "F.Cu" "B.Cu")
		(net "GND")
	)
	(via
		(at 208.838546 -339.1535)
		(size 0.7112)
		(drill 0.4064)
		(layers "F.Cu" "B.Cu")
		(net "GND")
	)
	(via
		(at 218.0336 -396.7226)
		(size 0.7112)
		(drill 0.4064)
		(layers "F.Cu" "B.Cu")
		(net "GND")
	)
	(via
		(at 14.1478 -1.4986)
		(size 0.7112)
		(drill 0.4064)
		(layers "F.Cu" "B.Cu")
		(net "GND")
	)
	(via
		(at 5.968746 -410.9847)
		(size 0.5588)
		(drill 0.3048)
		(layers "F.Cu" "B.Cu")
		(net "GND")
	)
	(via
		(at 57.200546 -502.6025)
		(size 0.7112)
		(drill 0.4064)
		(layers "F.Cu" "B.Cu")
		(net "GND")
	)
	(via
		(at 228.853746 -165.7477)
		(size 0.7112)
		(drill 0.4064)
		(layers "F.Cu" "B.Cu")
		(net "GND")
	)
	(via
		(at 202.564746 -24.2697)
		(size 0.7112)
		(drill 0.4064)
		(layers "F.Cu" "B.Cu")
		(net "GND")
	)
	(via
		(at 59.181746 -105.2957)
		(size 0.7112)
		(drill 0.4064)
		(layers "F.Cu" "B.Cu")
		(net "GND")
	)
	(via
		(at 30.479746 -413.7787)
		(size 0.7112)
		(drill 0.4064)
		(layers "F.Cu" "B.Cu")
		(net "GND")
	)
	(via
		(at 112.572546 -314.6425)
		(size 0.7112)
		(drill 0.4064)
		(layers "F.Cu" "B.Cu")
		(net "GND")
	)
	(via
		(at 224.891346 -122.7963)
		(size 0.7112)
		(drill 0.4064)
		(layers "F.Cu" "B.Cu")
		(net "GND")
	)
	(via
		(at 120.014746 -409.3337)
		(size 0.7112)
		(drill 0.4064)
		(layers "F.Cu" "B.Cu")
		(net "GND")
	)
	(via
		(at 196.849746 -125.4887)
		(size 0.7112)
		(drill 0.4064)
		(layers "F.Cu" "B.Cu")
		(net "GND")
	)
	(via
		(at 203.453746 -55.0037)
		(size 0.7112)
		(drill 0.4064)
		(layers "F.Cu" "B.Cu")
		(net "GND")
	)
	(via
		(at 142.519146 -330.4667)
		(size 0.7112)
		(drill 0.4064)
		(layers "F.Cu" "B.Cu")
		(net "GND")
	)
	(via
		(at 60.5282 -400.0754)
		(size 0.7112)
		(drill 0.4064)
		(layers "F.Cu" "B.Cu")
		(net "GND")
	)
	(via
		(at 171.119546 -389.9789)
		(size 0.7112)
		(drill 0.4064)
		(layers "F.Cu" "B.Cu")
		(net "GND")
	)
	(via
		(at 244.1194 -405.892)
		(size 0.7112)
		(drill 0.4064)
		(layers "F.Cu" "B.Cu")
		(net "GND")
	)
	(via
		(at 113.055146 -371.9195)
		(size 0.7112)
		(drill 0.4064)
		(layers "F.Cu" "B.Cu")
		(net "GND")
	)
	(via
		(at 14.096746 -151.2951)
		(size 0.5588)
		(drill 0.3048)
		(layers "F.Cu" "B.Cu")
		(net "GND")
	)
	(via
		(at 147.573746 -358.8385)
		(size 0.7112)
		(drill 0.4064)
		(layers "F.Cu" "B.Cu")
		(net "GND")
	)
	(via
		(at 191.135 -496.443)
		(size 0.5588)
		(drill 0.3048)
		(layers "F.Cu" "B.Cu")
		(net "GND")
	)
	(via
		(at 98.043746 -52.6415)
		(size 0.7112)
		(drill 0.4064)
		(layers "F.Cu" "B.Cu")
		(net "GND")
	)
	(via
		(at 145.008346 -245.3259)
		(size 0.7112)
		(drill 0.4064)
		(layers "F.Cu" "B.Cu")
		(net "GND")
	)
	(via
		(at 21.843746 -412.6357)
		(size 0.7112)
		(drill 0.4064)
		(layers "F.Cu" "B.Cu")
		(net "GND")
	)
	(via
		(at 69.088 -504.825)
		(size 0.7112)
		(drill 0.4064)
		(layers "F.Cu" "B.Cu")
		(net "GND")
	)
	(via
		(at 56.463946 -317.9699)
		(size 0.7112)
		(drill 0.4064)
		(layers "F.Cu" "B.Cu")
		(net "GND")
	)
	(via
		(at 237.616746 -136.9187)
		(size 0.7112)
		(drill 0.4064)
		(layers "F.Cu" "B.Cu")
		(net "GND")
	)
	(via
		(at 27.051 -239.522)
		(size 0.7112)
		(drill 0.4064)
		(layers "F.Cu" "B.Cu")
		(net "GND")
	)
	(via
		(at 93.776546 -487.6165)
		(size 0.7112)
		(drill 0.4064)
		(layers "F.Cu" "B.Cu")
		(net "GND")
	)
	(via
		(at 108.965746 -280.0477)
		(size 0.7112)
		(drill 0.4064)
		(layers "F.Cu" "B.Cu")
		(net "GND")
	)
	(via
		(at 54.101746 -172.0469)
		(size 0.7112)
		(drill 0.4064)
		(layers "F.Cu" "B.Cu")
		(net "GND")
	)
	(via
		(at 245.6434 -386.7912)
		(size 0.7112)
		(drill 0.4064)
		(layers "F.Cu" "B.Cu")
		(net "GND")
	)
	(via
		(at 233.298746 -176.0347)
		(size 0.7112)
		(drill 0.4064)
		(layers "F.Cu" "B.Cu")
		(net "GND")
	)
	(via
		(at 104.012746 -280.0477)
		(size 0.7112)
		(drill 0.4064)
		(layers "F.Cu" "B.Cu")
		(net "GND")
	)
	(via
		(at 87.401146 -368.1857)
		(size 0.7112)
		(drill 0.4064)
		(layers "F.Cu" "B.Cu")
		(net "GND")
	)
	(via
		(at 140.842746 -471.4113)
		(size 0.7112)
		(drill 0.4064)
		(layers "F.Cu" "B.Cu")
		(net "GND")
	)
	(via
		(at 199.516746 -73.9267)
		(size 0.5588)
		(drill 0.3048)
		(layers "F.Cu" "B.Cu")
		(net "GND")
	)
	(via
		(at 39.98976 -388.73684)
		(size 0.5588)
		(drill 0.3048)
		(layers "F.Cu" "B.Cu")
		(net "GND")
	)
	(via
		(at 152.145746 -259.2197)
		(size 0.7112)
		(drill 0.4064)
		(layers "F.Cu" "B.Cu")
		(net "GND")
	)
	(via
		(at 115.442746 -124.4727)
		(size 0.7112)
		(drill 0.4064)
		(layers "F.Cu" "B.Cu")
		(net "GND")
	)
	(via
		(at 165.709346 -400.2659)
		(size 0.7112)
		(drill 0.4064)
		(layers "F.Cu" "B.Cu")
		(net "GND")
	)
	(via
		(at 192.729612 -87.63)
		(size 0.5588)
		(drill 0.3048)
		(layers "F.Cu" "B.Cu")
		(net "GND")
	)
	(via
		(at 159.511746 -71.1327)
		(size 0.7112)
		(drill 0.4064)
		(layers "F.Cu" "B.Cu")
		(net "GND")
	)
	(via
		(at 141.020546 -425.3865)
		(size 0.7112)
		(drill 0.4064)
		(layers "F.Cu" "B.Cu")
		(net "GND")
	)
	(via
		(at 8.3312 -146.8628)
		(size 0.5588)
		(drill 0.3048)
		(layers "F.Cu" "B.Cu")
		(net "GND")
	)
	(via
		(at 163.321746 -55.3847)
		(size 0.7112)
		(drill 0.4064)
		(layers "F.Cu" "B.Cu")
		(net "GND")
	)
	(via
		(at 259.333746 -196.2277)
		(size 0.7112)
		(drill 0.4064)
		(layers "F.Cu" "B.Cu")
		(net "GND")
	)
	(via
		(at 29.844746 -443.2427)
		(size 0.7112)
		(drill 0.4064)
		(layers "F.Cu" "B.Cu")
		(net "GND")
	)
	(via
		(at 7.365746 -375.4247)
		(size 0.5588)
		(drill 0.3048)
		(layers "F.Cu" "B.Cu")
		(net "GND")
	)
	(via
		(at 19.967702 -325.796656)
		(size 0.5588)
		(drill 0.3048)
		(layers "F.Cu" "B.Cu")
		(net "GND")
	)
	(via
		(at 23.621746 -21.876512)
		(size 0.5588)
		(drill 0.3048)
		(layers "F.Cu" "B.Cu")
		(net "GND")
	)
	(via
		(at 27.2542 -365.2774)
		(size 0.5588)
		(drill 0.3048)
		(layers "F.Cu" "B.Cu")
		(net "GND")
	)
	(via
		(at 166.877746 -248.2977)
		(size 0.7112)
		(drill 0.4064)
		(layers "F.Cu" "B.Cu")
		(net "GND")
	)
	(via
		(at 191.439546 -477.3295)
		(size 0.7112)
		(drill 0.4064)
		(layers "F.Cu" "B.Cu")
		(net "GND")
	)
	(via
		(at 91.033346 -126.6571)
		(size 0.7112)
		(drill 0.4064)
		(layers "F.Cu" "B.Cu")
		(net "GND")
	)
	(via
		(at 252.729746 -265.4427)
		(size 0.7112)
		(drill 0.4064)
		(layers "F.Cu" "B.Cu")
		(net "GND")
	)
	(via
		(at 116.661946 -497.2939)
		(size 0.7112)
		(drill 0.4064)
		(layers "F.Cu" "B.Cu")
		(net "GND")
	)
	(via
		(at 77.901546 -249.2375)
		(size 0.7112)
		(drill 0.4064)
		(layers "F.Cu" "B.Cu")
		(net "GND")
	)
	(via
		(at 140.563346 -412.6357)
		(size 0.7112)
		(drill 0.4064)
		(layers "F.Cu" "B.Cu")
		(net "GND")
	)
	(via
		(at 222.351346 -335.9531)
		(size 0.7112)
		(drill 0.4064)
		(layers "F.Cu" "B.Cu")
		(net "GND")
	)
	(via
		(at 235.829094 -19.299174)
		(size 0.5588)
		(drill 0.3048)
		(layers "F.Cu" "B.Cu")
		(net "GND")
	)
	(via
		(at 209.600546 -216.1159)
		(size 0.7112)
		(drill 0.4064)
		(layers "F.Cu" "B.Cu")
		(net "GND")
	)
	(via
		(at 229.107746 -504.7107)
		(size 0.7112)
		(drill 0.4064)
		(layers "F.Cu" "B.Cu")
		(net "GND")
	)
	(via
		(at 26.669746 -434.076602)
		(size 0.5588)
		(drill 0.3048)
		(layers "F.Cu" "B.Cu")
		(net "GND")
	)
	(via
		(at 192.379346 -321.9831)
		(size 0.7112)
		(drill 0.4064)
		(layers "F.Cu" "B.Cu")
		(net "GND")
	)
	(via
		(at 241.934746 -345.9099)
		(size 0.7112)
		(drill 0.4064)
		(layers "F.Cu" "B.Cu")
		(net "GND")
	)
	(via
		(at 73.685146 -240.9571)
		(size 0.7112)
		(drill 0.4064)
		(layers "F.Cu" "B.Cu")
		(net "GND")
	)
	(via
		(at 137.540746 -36.8427)
		(size 0.7112)
		(drill 0.4064)
		(layers "F.Cu" "B.Cu")
		(net "GND")
	)
	(via
		(at 35.6616 -165.0492)
		(size 0.5588)
		(drill 0.3048)
		(layers "F.Cu" "B.Cu")
		(net "GND")
	)
	(via
		(at 224.637346 -117.4623)
		(size 0.7112)
		(drill 0.4064)
		(layers "F.Cu" "B.Cu")
		(net "GND")
	)
	(via
		(at 241.756946 -128.0541)
		(size 0.7112)
		(drill 0.4064)
		(layers "F.Cu" "B.Cu")
		(net "GND")
	)
	(via
		(at 131.673346 -495.6175)
		(size 0.7112)
		(drill 0.4064)
		(layers "F.Cu" "B.Cu")
		(net "GND")
	)
	(via
		(at 137.388346 -249.2883)
		(size 0.7112)
		(drill 0.4064)
		(layers "F.Cu" "B.Cu")
		(net "GND")
	)
	(via
		(at 78.485746 -181.9783)
		(size 0.5588)
		(drill 0.3048)
		(layers "F.Cu" "B.Cu")
		(net "GND")
	)
	(via
		(at 33.197546 -307.505862)
		(size 0.5588)
		(drill 0.3048)
		(layers "F.Cu" "B.Cu")
		(net "GND")
	)
	(via
		(at 43.713146 -222.8723)
		(size 0.7112)
		(drill 0.4064)
		(layers "F.Cu" "B.Cu")
		(net "GND")
	)
	(via
		(at 79.552546 -68.6689)
		(size 0.7112)
		(drill 0.4064)
		(layers "F.Cu" "B.Cu")
		(net "GND")
	)
	(via
		(at 48.666146 -480.4537)
		(size 0.7112)
		(drill 0.4064)
		(layers "F.Cu" "B.Cu")
		(net "GND")
	)
	(via
		(at 60.8076 -90.7796)
		(size 0.5588)
		(drill 0.3048)
		(layers "F.Cu" "B.Cu")
		(net "GND")
	)
	(via
		(at 171.195746 -258.4577)
		(size 0.7112)
		(drill 0.4064)
		(layers "F.Cu" "B.Cu")
		(net "GND")
	)
	(via
		(at 149.326346 -497.0399)
		(size 0.7112)
		(drill 0.4064)
		(layers "F.Cu" "B.Cu")
		(net "GND")
	)
	(via
		(at 219.074746 -463.1817)
		(size 0.7112)
		(drill 0.4064)
		(layers "F.Cu" "B.Cu")
		(net "GND")
	)
	(via
		(at 194.839082 -288.1757)
		(size 0.5588)
		(drill 0.3048)
		(layers "F.Cu" "B.Cu")
		(net "GND")
	)
	(via
		(at 50.9524 -422.5544)
		(size 0.7112)
		(drill 0.4064)
		(layers "F.Cu" "B.Cu")
		(net "GND")
	)
	(via
		(at 64.134746 -105.4227)
		(size 0.7112)
		(drill 0.4064)
		(layers "F.Cu" "B.Cu")
		(net "GND")
	)
	(via
		(at 133.730746 -216.1921)
		(size 0.7112)
		(drill 0.4064)
		(layers "F.Cu" "B.Cu")
		(net "GND")
	)
	(via
		(at 241.248946 -165.3921)
		(size 0.7112)
		(drill 0.4064)
		(layers "F.Cu" "B.Cu")
		(net "GND")
	)
	(via
		(at 42.787062 -134.099046)
		(size 0.5588)
		(drill 0.3048)
		(layers "F.Cu" "B.Cu")
		(net "GND")
	)
	(via
		(at 225.1964 -77.196696)
		(size 0.5588)
		(drill 0.3048)
		(layers "F.Cu" "B.Cu")
		(net "GND")
	)
	(via
		(at 259.206746 -12.8397)
		(size 0.7112)
		(drill 0.4064)
		(layers "F.Cu" "B.Cu")
		(net "GND")
	)
	(via
		(at 13.334746 -41.2877)
		(size 0.7112)
		(drill 0.4064)
		(layers "F.Cu" "B.Cu")
		(net "GND")
	)
	(via
		(at 80.263746 -182.6133)
		(size 0.5588)
		(drill 0.3048)
		(layers "F.Cu" "B.Cu")
		(net "GND")
	)
	(via
		(at 95.122746 -19.6977)
		(size 0.5588)
		(drill 0.3048)
		(layers "F.Cu" "B.Cu")
		(net "GND")
	)
	(via
		(at 258.190746 -330.4667)
		(size 0.7112)
		(drill 0.4064)
		(layers "F.Cu" "B.Cu")
		(net "GND")
	)
	(via
		(at 241.248946 -271.5133)
		(size 0.7112)
		(drill 0.4064)
		(layers "F.Cu" "B.Cu")
		(net "GND")
	)
	(via
		(at 32.511746 -39.8907)
		(size 0.5588)
		(drill 0.3048)
		(layers "F.Cu" "B.Cu")
		(net "GND")
	)
	(via
		(at 133.984746 -189.7761)
		(size 0.7112)
		(drill 0.4064)
		(layers "F.Cu" "B.Cu")
		(net "GND")
	)
	(via
		(at 140.258546 -400.4691)
		(size 0.7112)
		(drill 0.4064)
		(layers "F.Cu" "B.Cu")
		(net "GND")
	)
	(via
		(at 180.339746 -280.8097)
		(size 0.7112)
		(drill 0.4064)
		(layers "F.Cu" "B.Cu")
		(net "GND")
	)
	(via
		(at 9.194292 -367.474246)
		(size 0.5588)
		(drill 0.3048)
		(layers "F.Cu" "B.Cu")
		(net "GND")
	)
	(via
		(at 202.691746 -47.5107)
		(size 0.7112)
		(drill 0.4064)
		(layers "F.Cu" "B.Cu")
		(net "GND")
	)
	(via
		(at 67.512946 -229.0699)
		(size 0.7112)
		(drill 0.4064)
		(layers "F.Cu" "B.Cu")
		(net "GND")
	)
	(via
		(at 160.654746 -342.3793)
		(size 0.7112)
		(drill 0.4064)
		(layers "F.Cu" "B.Cu")
		(net "GND")
	)
	(via
		(at 181.330346 -352.1583)
		(size 0.7112)
		(drill 0.4064)
		(layers "F.Cu" "B.Cu")
		(net "GND")
	)
	(via
		(at 218.617546 -143.6497)
		(size 0.7112)
		(drill 0.4064)
		(layers "F.Cu" "B.Cu")
		(net "GND")
	)
	(via
		(at 62.229746 -142.1257)
		(size 0.7112)
		(drill 0.4064)
		(layers "F.Cu" "B.Cu")
		(net "GND")
	)
	(via
		(at 1.750314 -41.049194)
		(size 0.7112)
		(drill 0.4064)
		(layers "F.Cu" "B.Cu")
		(net "GND")
	)
	(via
		(at 5.669534 -312.704734)
		(size 0.7112)
		(drill 0.4064)
		(layers "F.Cu" "B.Cu")
		(net "GND")
	)
	(via
		(at 81.787746 -139.8397)
		(size 0.7112)
		(drill 0.4064)
		(layers "F.Cu" "B.Cu")
		(net "GND")
	)
	(via
		(at 143.763746 -317.1317)
		(size 0.7112)
		(drill 0.4064)
		(layers "F.Cu" "B.Cu")
		(net "GND")
	)
	(via
		(at 225.399854 -477.901)
		(size 0.7112)
		(drill 0.4064)
		(layers "F.Cu" "B.Cu")
		(net "GND")
	)
	(via
		(at 152.552146 -417.9443)
		(size 0.7112)
		(drill 0.4064)
		(layers "F.Cu" "B.Cu")
		(net "GND")
	)
	(via
		(at 4.572 -290.957)
		(size 0.7112)
		(drill 0.4064)
		(layers "F.Cu" "B.Cu")
		(net "GND")
	)
	(via
		(at 248.335546 -27.7241)
		(size 0.7112)
		(drill 0.4064)
		(layers "F.Cu" "B.Cu")
		(net "GND")
	)
	(via
		(at 234.162346 -189.1919)
		(size 0.7112)
		(drill 0.4064)
		(layers "F.Cu" "B.Cu")
		(net "GND")
	)
	(via
		(at 17.4498 -123.2408)
		(size 0.5588)
		(drill 0.3048)
		(layers "F.Cu" "B.Cu")
		(net "GND")
	)
	(via
		(at 239.2172 -454.0758)
		(size 0.7112)
		(drill 0.4064)
		(layers "F.Cu" "B.Cu")
		(net "GND")
	)
	(via
		(at 79.2226 -341.6046)
		(size 0.7112)
		(drill 0.4064)
		(layers "F.Cu" "B.Cu")
		(net "GND")
	)
	(via
		(at 241.248946 -170.2181)
		(size 0.7112)
		(drill 0.4064)
		(layers "F.Cu" "B.Cu")
		(net "GND")
	)
	(via
		(at 185.292746 -451.8025)
		(size 0.7112)
		(drill 0.4064)
		(layers "F.Cu" "B.Cu")
		(net "GND")
	)
	(via
		(at 64.236346 -225.1329)
		(size 0.7112)
		(drill 0.4064)
		(layers "F.Cu" "B.Cu")
		(net "GND")
	)
	(via
		(at 191.897 -486.283)
		(size 0.7112)
		(drill 0.4064)
		(layers "F.Cu" "B.Cu")
		(net "GND")
	)
	(via
		(at 112.648746 -89.9287)
		(size 0.7112)
		(drill 0.4064)
		(layers "F.Cu" "B.Cu")
		(net "GND")
	)
	(via
		(at 132.968746 -350.2787)
		(size 0.7112)
		(drill 0.4064)
		(layers "F.Cu" "B.Cu")
		(net "GND")
	)
	(via
		(at 117.093746 -208.1657)
		(size 0.7112)
		(drill 0.3556)
		(layers "F.Cu" "B.Cu")
		(net "GND")
	)
	(via
		(at 97.154746 -504.8377)
		(size 0.7112)
		(drill 0.4064)
		(layers "F.Cu" "B.Cu")
		(net "GND")
	)
	(via
		(at 213.169246 -41.6687)
		(size 0.5588)
		(drill 0.3048)
		(layers "F.Cu" "B.Cu")
		(net "GND")
	)
	(via
		(at 213.918546 -477.3295)
		(size 0.7112)
		(drill 0.4064)
		(layers "F.Cu" "B.Cu")
		(net "GND")
	)
	(via
		(at 246.760746 -492.0107)
		(size 0.7112)
		(drill 0.4064)
		(layers "F.Cu" "B.Cu")
		(net "GND")
	)
	(via
		(at 193.242946 -46.2153)
		(size 0.7112)
		(drill 0.4064)
		(layers "F.Cu" "B.Cu")
		(net "GND")
	)
	(via
		(at 27.2034 -440.944)
		(size 0.5588)
		(drill 0.3048)
		(layers "F.Cu" "B.Cu")
		(net "GND")
	)
	(via
		(at 256.539746 -456.5523)
		(size 0.7112)
		(drill 0.4064)
		(layers "F.Cu" "B.Cu")
		(net "GND")
	)
	(via
		(at 88.671146 -415.1757)
		(size 0.7112)
		(drill 0.4064)
		(layers "F.Cu" "B.Cu")
		(net "GND")
	)
	(via
		(at 80.263746 -497.4717)
		(size 0.5588)
		(drill 0.3048)
		(layers "F.Cu" "B.Cu")
		(net "GND")
	)
	(via
		(at 19.938746 -323.4817)
		(size 0.5588)
		(drill 0.3048)
		(layers "F.Cu" "B.Cu")
		(net "GND")
	)
	(via
		(at 171.576746 -441.4647)
		(size 0.7112)
		(drill 0.4064)
		(layers "F.Cu" "B.Cu")
		(net "GND")
	)
	(via
		(at 197.332346 -250.9647)
		(size 0.7112)
		(drill 0.4064)
		(layers "F.Cu" "B.Cu")
		(net "GND")
	)
	(via
		(at 191.896746 -382.9177)
		(size 0.7112)
		(drill 0.4064)
		(layers "F.Cu" "B.Cu")
		(net "GND")
	)
	(via
		(at 110.311946 -481.3427)
		(size 0.7112)
		(drill 0.4064)
		(layers "F.Cu" "B.Cu")
		(net "GND")
	)
	(via
		(at 194.335146 -468.5665)
		(size 0.7112)
		(drill 0.4064)
		(layers "F.Cu" "B.Cu")
		(net "GND")
	)
	(via
		(at 113.283746 -494.1697)
		(size 0.7112)
		(drill 0.4064)
		(layers "F.Cu" "B.Cu")
		(net "GND")
	)
	(via
		(at 91.312746 -441.1599)
		(size 0.7112)
		(drill 0.4064)
		(layers "F.Cu" "B.Cu")
		(net "GND")
	)
	(via
		(at 107.238546 -92.2909)
		(size 0.7112)
		(drill 0.4064)
		(layers "F.Cu" "B.Cu")
		(net "GND")
	)
	(via
		(at 6.3246 -398.653)
		(size 0.5588)
		(drill 0.3048)
		(layers "F.Cu" "B.Cu")
		(net "GND")
	)
	(via
		(at 78.104746 -168.0337)
		(size 0.7112)
		(drill 0.4064)
		(layers "F.Cu" "B.Cu")
		(net "GND")
	)
	(via
		(at 21.88591 -340.1187)
		(size 0.5588)
		(drill 0.3048)
		(layers "F.Cu" "B.Cu")
		(net "GND")
	)
	(via
		(at 11.419586 -146.242024)
		(size 0.5588)
		(drill 0.3048)
		(layers "F.Cu" "B.Cu")
		(net "GND")
	)
	(via
		(at 6.857746 -409.0797)
		(size 0.5588)
		(drill 0.3048)
		(layers "F.Cu" "B.Cu")
		(net "GND")
	)
	(via
		(at 161.746946 -371.1575)
		(size 0.7112)
		(drill 0.4064)
		(layers "F.Cu" "B.Cu")
		(net "GND")
	)
	(via
		(at 215.925146 -399.3515)
		(size 0.7112)
		(drill 0.4064)
		(layers "F.Cu" "B.Cu")
		(net "GND")
	)
	(via
		(at 234.949746 -377.3297)
		(size 0.7112)
		(drill 0.4064)
		(layers "F.Cu" "B.Cu")
		(net "GND")
	)
	(via
		(at 49.148746 -425.2087)
		(size 0.7112)
		(drill 0.4064)
		(layers "F.Cu" "B.Cu")
		(net "GND")
	)
	(via
		(at 142.646146 -487.9213)
		(size 0.7112)
		(drill 0.4064)
		(layers "F.Cu" "B.Cu")
		(net "GND")
	)
	(via
		(at 35.762946 -364.60684)
		(size 0.7112)
		(drill 0.4064)
		(layers "F.Cu" "B.Cu")
		(net "GND")
	)
	(via
		(at 248.030746 -349.7707)
		(size 0.7112)
		(drill 0.4064)
		(layers "F.Cu" "B.Cu")
		(net "GND")
	)
	(via
		(at 221.360746 -285.736792)
		(size 0.5588)
		(drill 0.3048)
		(layers "F.Cu" "B.Cu")
		(net "GND")
	)
	(via
		(at 241.883946 -147.6121)
		(size 0.7112)
		(drill 0.4064)
		(layers "F.Cu" "B.Cu")
		(net "GND")
	)
	(via
		(at 199.282558 -390.049512)
		(size 0.5588)
		(drill 0.3048)
		(layers "F.Cu" "B.Cu")
		(net "GND")
	)
	(via
		(at 146.176746 -499.2497)
		(size 0.7112)
		(drill 0.4064)
		(layers "F.Cu" "B.Cu")
		(net "GND")
	)
	(via
		(at 196.138546 -233.8451)
		(size 0.7112)
		(drill 0.4064)
		(layers "F.Cu" "B.Cu")
		(net "GND")
	)
	(via
		(at 71.373746 -214.1347)
		(size 0.7112)
		(drill 0.4064)
		(layers "F.Cu" "B.Cu")
		(net "GND")
	)
	(via
		(at 247.903746 -283.3497)
		(size 0.7112)
		(drill 0.4064)
		(layers "F.Cu" "B.Cu")
		(net "GND")
	)
	(via
		(at 35.7886 -163.576)
		(size 0.5588)
		(drill 0.3048)
		(layers "F.Cu" "B.Cu")
		(net "GND")
	)
	(via
		(at 8.8646 -381.254)
		(size 0.5588)
		(drill 0.3048)
		(layers "F.Cu" "B.Cu")
		(net "GND")
	)
	(via
		(at 30.225746 -309.6387)
		(size 0.5588)
		(drill 0.3048)
		(layers "F.Cu" "B.Cu")
		(net "GND")
	)
	(via
		(at 166.877746 -251.9807)
		(size 0.7112)
		(drill 0.4064)
		(layers "F.Cu" "B.Cu")
		(net "GND")
	)
	(via
		(at 220.014546 -228.9429)
		(size 0.7112)
		(drill 0.4064)
		(layers "F.Cu" "B.Cu")
		(net "GND")
	)
	(via
		(at 72.516746 -362.5977)
		(size 0.7112)
		(drill 0.4064)
		(layers "F.Cu" "B.Cu")
		(net "GND")
	)
	(via
		(at 241.883946 -68.4911)
		(size 0.7112)
		(drill 0.4064)
		(layers "F.Cu" "B.Cu")
		(net "GND")
	)
	(via
		(at 123.723146 -309.3847)
		(size 0.7112)
		(drill 0.4064)
		(layers "F.Cu" "B.Cu")
		(net "GND")
	)
	(via
		(at 10.803128 -494.482882)
		(size 0.5588)
		(drill 0.3048)
		(layers "F.Cu" "B.Cu")
		(net "GND")
	)
	(via
		(at 19.59991 -446.9257)
		(size 0.7112)
		(drill 0.4064)
		(layers "F.Cu" "B.Cu")
		(net "GND")
	)
	(via
		(at 186.689746 -261.7597)
		(size 0.7112)
		(drill 0.4064)
		(layers "F.Cu" "B.Cu")
		(net "GND")
	)
	(via
		(at 60.2996 -422.6052)
		(size 0.7112)
		(drill 0.4064)
		(layers "F.Cu" "B.Cu")
		(net "GND")
	)
	(via
		(at 120.141746 -54.4957)
		(size 0.7112)
		(drill 0.4064)
		(layers "F.Cu" "B.Cu")
		(net "GND")
	)
	(via
		(at 2.921 -42.164)
		(size 0.7112)
		(drill 0.4064)
		(layers "F.Cu" "B.Cu")
		(net "GND")
	)
	(via
		(at 124.967746 -488.8357)
		(size 0.7112)
		(drill 0.4064)
		(layers "F.Cu" "B.Cu")
		(net "GND")
	)
	(via
		(at 105.917746 -36.8427)
		(size 0.7112)
		(drill 0.4064)
		(layers "F.Cu" "B.Cu")
		(net "GND")
	)
	(via
		(at 127.126746 -32.0167)
		(size 0.7112)
		(drill 0.4064)
		(layers "F.Cu" "B.Cu")
		(net "GND")
	)
	(via
		(at 142.341346 -455.3077)
		(size 0.7112)
		(drill 0.4064)
		(layers "F.Cu" "B.Cu")
		(net "GND")
	)
	(via
		(at 72.008746 -282.7147)
		(size 0.7112)
		(drill 0.4064)
		(layers "F.Cu" "B.Cu")
		(net "GND")
	)
	(via
		(at 53.213 -192.786)
		(size 0.7112)
		(drill 0.4064)
		(layers "F.Cu" "B.Cu")
		(net "GND")
	)
	(via
		(at 190.8302 -407.6446)
		(size 0.7112)
		(drill 0.4064)
		(layers "F.Cu" "B.Cu")
		(net "GND")
	)
	(via
		(at 111.505746 -504.8377)
		(size 0.7112)
		(drill 0.4064)
		(layers "F.Cu" "B.Cu")
		(net "GND")
	)
	(via
		(at 56.184546 -395.2367)
		(size 0.7112)
		(drill 0.3556)
		(layers "F.Cu" "B.Cu")
		(net "GND")
	)
	(via
		(at 12.979146 -76.2127)
		(size 0.7112)
		(drill 0.4064)
		(layers "F.Cu" "B.Cu")
		(net "GND")
	)
	(via
		(at 149.580346 -482.9429)
		(size 0.7112)
		(drill 0.4064)
		(layers "F.Cu" "B.Cu")
		(net "GND")
	)
	(via
		(at 75.564746 -220.6117)
		(size 0.7112)
		(drill 0.4064)
		(layers "F.Cu" "B.Cu")
		(net "GND")
	)
	(via
		(at 176.161446 -455.456036)
		(size 0.7112)
		(drill 0.4064)
		(layers "F.Cu" "B.Cu")
		(net "GND")
	)
	(via
		(at 90.779346 -138.1379)
		(size 0.7112)
		(drill 0.4064)
		(layers "F.Cu" "B.Cu")
		(net "GND")
	)
	(via
		(at 22.859746 -100.6983)
		(size 0.7112)
		(drill 0.4064)
		(layers "F.Cu" "B.Cu")
		(net "GND")
	)
	(via
		(at 160.197546 -482.7905)
		(size 0.7112)
		(drill 0.4064)
		(layers "F.Cu" "B.Cu")
		(net "GND")
	)
	(via
		(at 154.812746 -179.8447)
		(size 0.7112)
		(drill 0.4064)
		(layers "F.Cu" "B.Cu")
		(net "GND")
	)
	(via
		(at 187.451746 -294.5257)
		(size 0.7112)
		(drill 0.4064)
		(layers "F.Cu" "B.Cu")
		(net "GND")
	)
	(via
		(at 174.777146 -214.5411)
		(size 0.7112)
		(drill 0.4064)
		(layers "F.Cu" "B.Cu")
		(net "GND")
	)
	(via
		(at 259.079746 -268.8717)
		(size 0.7112)
		(drill 0.4064)
		(layers "F.Cu" "B.Cu")
		(net "GND")
	)
	(via
		(at 57.505346 -172.0977)
		(size 0.7112)
		(drill 0.4064)
		(layers "F.Cu" "B.Cu")
		(net "GND")
	)
	(via
		(at 190.372746 -55.5117)
		(size 0.7112)
		(drill 0.4064)
		(layers "F.Cu" "B.Cu")
		(net "GND")
	)
	(via
		(at 251.4346 -426.4152)
		(size 0.5588)
		(drill 0.3048)
		(layers "F.Cu" "B.Cu")
		(net "GND")
	)
	(via
		(at 57.530746 -1.2827)
		(size 0.7112)
		(drill 0.4064)
		(layers "F.Cu" "B.Cu")
		(net "GND")
	)
	(via
		(at 125.221746 -477.0247)
		(size 0.7112)
		(drill 0.4064)
		(layers "F.Cu" "B.Cu")
		(net "GND")
	)
	(via
		(at 12.318746 -58.0517)
		(size 0.7112)
		(drill 0.4064)
		(layers "F.Cu" "B.Cu")
		(net "GND")
	)
	(via
		(at 227.202746 -391.0457)
		(size 0.7112)
		(drill 0.4064)
		(layers "F.Cu" "B.Cu")
		(net "GND")
	)
	(via
		(at 188.239146 -368.3635)
		(size 0.7112)
		(drill 0.4064)
		(layers "F.Cu" "B.Cu")
		(net "GND")
	)
	(via
		(at 138.963146 -310.3245)
		(size 0.7112)
		(drill 0.4064)
		(layers "F.Cu" "B.Cu")
		(net "GND")
	)
	(via
		(at 67.563746 -62.2427)
		(size 0.7112)
		(drill 0.4064)
		(layers "F.Cu" "B.Cu")
		(net "GND")
	)
	(via
		(at 104.901746 -73.6727)
		(size 0.7112)
		(drill 0.4064)
		(layers "F.Cu" "B.Cu")
		(net "GND")
	)
	(via
		(at 150.621746 -107.2007)
		(size 0.7112)
		(drill 0.4064)
		(layers "F.Cu" "B.Cu")
		(net "GND")
	)
	(via
		(at 246.506746 -215.3285)
		(size 0.7112)
		(drill 0.4064)
		(layers "F.Cu" "B.Cu")
		(net "GND")
	)
	(via
		(at 36.702746 -443.3697)
		(size 0.7112)
		(drill 0.4064)
		(layers "F.Cu" "B.Cu")
		(net "GND")
	)
	(via
		(at 145.922746 -273.4437)
		(size 0.7112)
		(drill 0.4064)
		(layers "F.Cu" "B.Cu")
		(net "GND")
	)
	(via
		(at 153.288746 -229.6287)
		(size 0.7112)
		(drill 0.4064)
		(layers "F.Cu" "B.Cu")
		(net "GND")
	)
	(via
		(at 171.576746 -26.3017)
		(size 0.7112)
		(drill 0.4064)
		(layers "F.Cu" "B.Cu")
		(net "GND")
	)
	(via
		(at 184.530746 -46.6217)
		(size 0.7112)
		(drill 0.4064)
		(layers "F.Cu" "B.Cu")
		(net "GND")
	)
	(via
		(at 251.459746 -498.5131)
		(size 0.7112)
		(drill 0.4064)
		(layers "F.Cu" "B.Cu")
		(net "GND")
	)
	(via
		(at 180.263546 -321.1957)
		(size 0.7112)
		(drill 0.4064)
		(layers "F.Cu" "B.Cu")
		(net "GND")
	)
	(via
		(at 38.639496 -165.574472)
		(size 0.7112)
		(drill 0.4064)
		(layers "F.Cu" "B.Cu")
		(net "GND")
	)
	(via
		(at 248.005346 -454.9521)
		(size 0.7112)
		(drill 0.4064)
		(layers "F.Cu" "B.Cu")
		(net "GND")
	)
	(via
		(at 6.629146 -226.4791)
		(size 0.7112)
		(drill 0.4064)
		(layers "F.Cu" "B.Cu")
		(net "GND")
	)
	(via
		(at 5.807456 -425.0817)
		(size 0.5588)
		(drill 0.3048)
		(layers "F.Cu" "B.Cu")
		(net "GND")
	)
	(via
		(at 84.327746 -137.2997)
		(size 0.7112)
		(drill 0.4064)
		(layers "F.Cu" "B.Cu")
		(net "GND")
	)
	(via
		(at 78.993746 -100.6475)
		(size 0.7112)
		(drill 0.4064)
		(layers "F.Cu" "B.Cu")
		(net "GND")
	)
	(via
		(at 163.855146 -476.8977)
		(size 0.7112)
		(drill 0.4064)
		(layers "F.Cu" "B.Cu")
		(net "GND")
	)
	(via
		(at 83.718146 -268.4907)
		(size 0.7112)
		(drill 0.4064)
		(layers "F.Cu" "B.Cu")
		(net "GND")
	)
	(via
		(at 257.428746 -1.6637)
		(size 0.7112)
		(drill 0.4064)
		(layers "F.Cu" "B.Cu")
		(net "GND")
	)
	(via
		(at 176.529746 -122.0597)
		(size 0.7112)
		(drill 0.4064)
		(layers "F.Cu" "B.Cu")
		(net "GND")
	)
	(via
		(at 19.85391 -34.827464)
		(size 0.7112)
		(drill 0.4064)
		(layers "F.Cu" "B.Cu")
		(net "GND")
	)
	(via
		(at 106.552746 -313.4487)
		(size 0.7112)
		(drill 0.4064)
		(layers "F.Cu" "B.Cu")
		(net "GND")
	)
	(via
		(at 253.644146 -278.4983)
		(size 0.7112)
		(drill 0.4064)
		(layers "F.Cu" "B.Cu")
		(net "GND")
	)
	(via
		(at 106.374946 -222.7707)
		(size 0.7112)
		(drill 0.4064)
		(layers "F.Cu" "B.Cu")
		(net "GND")
	)
	(via
		(at 5.943346 -112.978946)
		(size 0.5588)
		(drill 0.3048)
		(layers "F.Cu" "B.Cu")
		(net "GND")
	)
	(via
		(at 197.967346 -345.9099)
		(size 0.7112)
		(drill 0.4064)
		(layers "F.Cu" "B.Cu")
		(net "GND")
	)
	(via
		(at 185.114946 -484.6701)
		(size 0.7112)
		(drill 0.4064)
		(layers "F.Cu" "B.Cu")
		(net "GND")
	)
	(via
		(at 226.313746 -1.5367)
		(size 0.7112)
		(drill 0.4064)
		(layers "F.Cu" "B.Cu")
		(net "GND")
	)
	(via
		(at 129.768346 -220.5101)
		(size 0.7112)
		(drill 0.4064)
		(layers "F.Cu" "B.Cu")
		(net "GND")
	)
	(via
		(at 19.430746 -381.7747)
		(size 0.7112)
		(drill 0.4064)
		(layers "F.Cu" "B.Cu")
		(net "GND")
	)
	(via
		(at 260.832346 -449.2117)
		(size 0.7112)
		(drill 0.4064)
		(layers "F.Cu" "B.Cu")
		(net "GND")
	)
	(via
		(at 202.437746 -16.6497)
		(size 0.7112)
		(drill 0.4064)
		(layers "F.Cu" "B.Cu")
		(net "GND")
	)
	(via
		(at 218.439746 -203.0857)
		(size 0.7112)
		(drill 0.4064)
		(layers "F.Cu" "B.Cu")
		(net "GND")
	)
	(via
		(at 40.259 -299.974)
		(size 0.7112)
		(drill 0.3556)
		(layers "F.Cu" "B.Cu")
		(net "GND")
	)
	(via
		(at 158.470346 -51.4477)
		(size 0.7112)
		(drill 0.4064)
		(layers "F.Cu" "B.Cu")
		(net "GND")
	)
	(via
		(at 87.401146 -354.0125)
		(size 0.7112)
		(drill 0.4064)
		(layers "F.Cu" "B.Cu")
		(net "GND")
	)
	(via
		(at 154.050746 -148.4757)
		(size 0.7112)
		(drill 0.4064)
		(layers "F.Cu" "B.Cu")
		(net "GND")
	)
	(via
		(at 176.529746 -20.7391)
		(size 0.7112)
		(drill 0.4064)
		(layers "F.Cu" "B.Cu")
		(net "GND")
	)
	(via
		(at 118.236746 -328.5617)
		(size 0.7112)
		(drill 0.4064)
		(layers "F.Cu" "B.Cu")
		(net "GND")
	)
	(via
		(at 187.451746 -118.6307)
		(size 0.7112)
		(drill 0.4064)
		(layers "F.Cu" "B.Cu")
		(net "GND")
	)
	(via
		(at 255.345946 -45.7073)
		(size 0.7112)
		(drill 0.4064)
		(layers "F.Cu" "B.Cu")
		(net "GND")
	)
	(via
		(at 80.898746 -425.5897)
		(size 0.7112)
		(drill 0.4064)
		(layers "F.Cu" "B.Cu")
		(net "GND")
	)
	(via
		(at 40.22979 -182.736744)
		(size 0.5588)
		(drill 0.3048)
		(layers "F.Cu" "B.Cu")
		(net "GND")
	)
	(via
		(at 235.203746 -303.5427)
		(size 0.7112)
		(drill 0.4064)
		(layers "F.Cu" "B.Cu")
		(net "GND")
	)
	(via
		(at 55.117746 -174.3837)
		(size 0.5588)
		(drill 0.3048)
		(layers "F.Cu" "B.Cu")
		(net "GND")
	)
	(via
		(at 15.519146 -153.221944)
		(size 0.7112)
		(drill 0.4064)
		(layers "F.Cu" "B.Cu")
		(net "GND")
	)
	(via
		(at 150.494746 -121.4247)
		(size 0.7112)
		(drill 0.4064)
		(layers "F.Cu" "B.Cu")
		(net "GND")
	)
	(via
		(at 97.154746 -48.3997)
		(size 0.7112)
		(drill 0.4064)
		(layers "F.Cu" "B.Cu")
		(net "GND")
	)
	(via
		(at 83.311746 -318.7827)
		(size 0.7112)
		(drill 0.4064)
		(layers "F.Cu" "B.Cu")
		(net "GND")
	)
	(via
		(at 163.474146 -100.5713)
		(size 0.7112)
		(drill 0.4064)
		(layers "F.Cu" "B.Cu")
		(net "GND")
	)
	(via
		(at 141.604746 -361.7087)
		(size 0.7112)
		(drill 0.4064)
		(layers "F.Cu" "B.Cu")
		(net "GND")
	)
	(via
		(at 245.719346 -45.8089)
		(size 0.7112)
		(drill 0.4064)
		(layers "F.Cu" "B.Cu")
		(net "GND")
	)
	(via
		(at 137.667746 -23.7617)
		(size 0.7112)
		(drill 0.4064)
		(layers "F.Cu" "B.Cu")
		(net "GND")
	)
	(via
		(at 259.333746 -104.4067)
		(size 0.7112)
		(drill 0.4064)
		(layers "F.Cu" "B.Cu")
		(net "GND")
	)
	(via
		(at 167.614346 -92.2655)
		(size 0.7112)
		(drill 0.4064)
		(layers "F.Cu" "B.Cu")
		(net "GND")
	)
	(via
		(at 190.855346 -255.1557)
		(size 0.7112)
		(drill 0.4064)
		(layers "F.Cu" "B.Cu")
		(net "GND")
	)
	(via
		(at 204.088746 -136.7917)
		(size 0.7112)
		(drill 0.4064)
		(layers "F.Cu" "B.Cu")
		(net "GND")
	)
	(via
		(at 241.883946 -63.6651)
		(size 0.7112)
		(drill 0.4064)
		(layers "F.Cu" "B.Cu")
		(net "GND")
	)
	(via
		(at 107.035346 -486.6767)
		(size 0.7112)
		(drill 0.4064)
		(layers "F.Cu" "B.Cu")
		(net "GND")
	)
	(via
		(at 55.428896 -194.39255)
		(size 0.5588)
		(drill 0.3048)
		(layers "F.Cu" "B.Cu")
		(net "GND")
	)
	(via
		(at 206.654146 -502.9073)
		(size 0.7112)
		(drill 0.4064)
		(layers "F.Cu" "B.Cu")
		(net "GND")
	)
	(via
		(at 38.7096 -163.3982)
		(size 0.7112)
		(drill 0.4064)
		(layers "F.Cu" "B.Cu")
		(net "GND")
	)
	(via
		(at 78.104746 -145.5547)
		(size 0.7112)
		(drill 0.4064)
		(layers "F.Cu" "B.Cu")
		(net "GND")
	)
	(via
		(at 135.280146 -420.5351)
		(size 0.7112)
		(drill 0.4064)
		(layers "F.Cu" "B.Cu")
		(net "GND")
	)
	(via
		(at 6.095746 -362.9787)
		(size 0.5588)
		(drill 0.3048)
		(layers "F.Cu" "B.Cu")
		(net "GND")
	)
	(via
		(at 115.163346 -205.2193)
		(size 0.7112)
		(drill 0.4064)
		(layers "F.Cu" "B.Cu")
		(net "GND")
	)
	(via
		(at 112.724946 -316.5475)
		(size 0.7112)
		(drill 0.4064)
		(layers "F.Cu" "B.Cu")
		(net "GND")
	)
	(via
		(at 41.528746 -297.5991)
		(size 0.7112)
		(drill 0.4064)
		(layers "F.Cu" "B.Cu")
		(net "GND")
	)
	(via
		(at 210.692746 -502.9835)
		(size 0.7112)
		(drill 0.4064)
		(layers "F.Cu" "B.Cu")
		(net "GND")
	)
	(via
		(at 133.070346 -21.6789)
		(size 0.7112)
		(drill 0.4064)
		(layers "F.Cu" "B.Cu")
		(net "GND")
	)
	(via
		(at 77.978 -411.3784)
		(size 0.7112)
		(drill 0.4064)
		(layers "F.Cu" "B.Cu")
		(net "GND")
	)
	(via
		(at 26.288746 -331.4827)
		(size 0.7112)
		(drill 0.4064)
		(layers "F.Cu" "B.Cu")
		(net "GND")
	)
	(via
		(at 2.285746 -235.3437)
		(size 0.7112)
		(drill 0.4064)
		(layers "F.Cu" "B.Cu")
		(net "GND")
	)
	(via
		(at 51.358546 -324.3199)
		(size 0.7112)
		(drill 0.4064)
		(layers "F.Cu" "B.Cu")
		(net "GND")
	)
	(via
		(at 259.333746 -77.3557)
		(size 0.7112)
		(drill 0.4064)
		(layers "F.Cu" "B.Cu")
		(net "GND")
	)
	(via
		(at 8.178546 -414.813496)
		(size 0.5588)
		(drill 0.3048)
		(layers "F.Cu" "B.Cu")
		(net "GND")
	)
	(via
		(at 143.687546 -180.5051)
		(size 0.7112)
		(drill 0.4064)
		(layers "F.Cu" "B.Cu")
		(net "GND")
	)
	(via
		(at 132.155946 -35.9283)
		(size 0.7112)
		(drill 0.4064)
		(layers "F.Cu" "B.Cu")
		(net "GND")
	)
	(via
		(at 234.7468 -17.7292)
		(size 0.5588)
		(drill 0.3048)
		(layers "F.Cu" "B.Cu")
		(net "GND")
	)
	(via
		(at 137.540746 -16.1417)
		(size 0.7112)
		(drill 0.4064)
		(layers "F.Cu" "B.Cu")
		(net "GND")
	)
	(via
		(at 217.5256 -294.0558)
		(size 0.7112)
		(drill 0.4064)
		(layers "F.Cu" "B.Cu")
		(net "GND")
	)
	(via
		(at 44.170346 -215.0237)
		(size 0.7112)
		(drill 0.4064)
		(layers "F.Cu" "B.Cu")
		(net "GND")
	)
	(via
		(at 251.967746 -486.6005)
		(size 0.7112)
		(drill 0.4064)
		(layers "F.Cu" "B.Cu")
		(net "GND")
	)
	(via
		(at 248.157746 -329.1967)
		(size 0.7112)
		(drill 0.4064)
		(layers "F.Cu" "B.Cu")
		(net "GND")
	)
	(via
		(at 236.473746 -490.4867)
		(size 0.7112)
		(drill 0.4064)
		(layers "F.Cu" "B.Cu")
		(net "GND")
	)
	(via
		(at 183.819546 -237.8075)
		(size 0.7112)
		(drill 0.4064)
		(layers "F.Cu" "B.Cu")
		(net "GND")
	)
	(via
		(at 166.903146 -423.8879)
		(size 0.7112)
		(drill 0.4064)
		(layers "F.Cu" "B.Cu")
		(net "GND")
	)
	(via
		(at 254.914146 -469.0491)
		(size 0.7112)
		(drill 0.4064)
		(layers "F.Cu" "B.Cu")
		(net "GND")
	)
	(via
		(at 216.407746 -249.8217)
		(size 0.7112)
		(drill 0.4064)
		(layers "F.Cu" "B.Cu")
		(net "GND")
	)
	(via
		(at 109.880146 -270.3957)
		(size 0.7112)
		(drill 0.4064)
		(layers "F.Cu" "B.Cu")
		(net "GND")
	)
	(via
		(at 193.674746 -339.2297)
		(size 0.7112)
		(drill 0.4064)
		(layers "F.Cu" "B.Cu")
		(net "GND")
	)
	(via
		(at 244.1956 -396.0622)
		(size 0.7112)
		(drill 0.4064)
		(layers "F.Cu" "B.Cu")
		(net "GND")
	)
	(via
		(at 235.828078 -20.29079)
		(size 0.5588)
		(drill 0.3048)
		(layers "F.Cu" "B.Cu")
		(net "GND")
	)
	(via
		(at 138.810746 -303.5935)
		(size 0.7112)
		(drill 0.4064)
		(layers "F.Cu" "B.Cu")
		(net "GND")
	)
	(via
		(at 3.047746 -13.6017)
		(size 0.7112)
		(drill 0.4064)
		(layers "F.Cu" "B.Cu")
		(net "GND")
	)
	(via
		(at 112.216946 -30.8483)
		(size 0.7112)
		(drill 0.4064)
		(layers "F.Cu" "B.Cu")
		(net "GND")
	)
	(via
		(at 20.447 -280.543)
		(size 0.5588)
		(drill 0.3048)
		(layers "F.Cu" "B.Cu")
		(net "GND")
	)
	(via
		(at 171.449746 -14.9987)
		(size 0.7112)
		(drill 0.4064)
		(layers "F.Cu" "B.Cu")
		(net "GND")
	)
	(via
		(at 133.984746 -304.9397)
		(size 0.7112)
		(drill 0.4064)
		(layers "F.Cu" "B.Cu")
		(net "GND")
	)
	(via
		(at 82.296 -396.875)
		(size 0.5588)
		(drill 0.3048)
		(layers "F.Cu" "B.Cu")
		(net "GND")
	)
	(via
		(at 96.849946 -34.7345)
		(size 0.7112)
		(drill 0.4064)
		(layers "F.Cu" "B.Cu")
		(net "GND")
	)
	(via
		(at 38.734746 -37.9857)
		(size 0.5588)
		(drill 0.3048)
		(layers "F.Cu" "B.Cu")
		(net "GND")
	)
	(via
		(at 145.541746 -64.7827)
		(size 0.7112)
		(drill 0.4064)
		(layers "F.Cu" "B.Cu")
		(net "GND")
	)
	(via
		(at 57.276746 -407.9367)
		(size 0.7112)
		(drill 0.3556)
		(layers "F.Cu" "B.Cu")
		(net "GND")
	)
	(via
		(at 84.200746 -49.0855)
		(size 0.7112)
		(drill 0.4064)
		(layers "F.Cu" "B.Cu")
		(net "GND")
	)
	(via
		(at 21.234146 -443.1665)
		(size 0.7112)
		(drill 0.4064)
		(layers "F.Cu" "B.Cu")
		(net "GND")
	)
	(via
		(at 234.162346 -192.8749)
		(size 0.7112)
		(drill 0.4064)
		(layers "F.Cu" "B.Cu")
		(net "GND")
	)
	(via
		(at 32.257746 -478.1677)
		(size 0.7112)
		(drill 0.4064)
		(layers "F.Cu" "B.Cu")
		(net "GND")
	)
	(via
		(at 6.806946 -222.1357)
		(size 0.7112)
		(drill 0.4064)
		(layers "F.Cu" "B.Cu")
		(net "GND")
	)
	(via
		(at 15.112746 -19.3167)
		(size 0.7112)
		(drill 0.4064)
		(layers "F.Cu" "B.Cu")
		(net "GND")
	)
	(via
		(at 86.258146 -274.7137)
		(size 0.7112)
		(drill 0.4064)
		(layers "F.Cu" "B.Cu")
		(net "GND")
	)
	(via
		(at 184.403746 -23.3807)
		(size 0.7112)
		(drill 0.4064)
		(layers "F.Cu" "B.Cu")
		(net "GND")
	)
	(via
		(at 76.936346 -154.4193)
		(size 0.7112)
		(drill 0.4064)
		(layers "F.Cu" "B.Cu")
		(net "GND")
	)
	(via
		(at 259.333746 -481.8507)
		(size 0.7112)
		(drill 0.4064)
		(layers "F.Cu" "B.Cu")
		(net "GND")
	)
	(via
		(at 146.303746 -484.3907)
		(size 0.7112)
		(drill 0.4064)
		(layers "F.Cu" "B.Cu")
		(net "GND")
	)
	(via
		(at 112.572546 -310.9595)
		(size 0.7112)
		(drill 0.4064)
		(layers "F.Cu" "B.Cu")
		(net "GND")
	)
	(via
		(at 221.162626 -154.86507)
		(size 0.7112)
		(drill 0.4064)
		(layers "F.Cu" "B.Cu")
		(net "GND")
	)
	(via
		(at 215.899746 -474.3577)
		(size 0.5588)
		(drill 0.3048)
		(layers "F.Cu" "B.Cu")
		(net "GND")
	)
	(via
		(at 259.333746 -192.2907)
		(size 0.7112)
		(drill 0.4064)
		(layers "F.Cu" "B.Cu")
		(net "GND")
	)
	(via
		(at 31.749746 -410.4767)
		(size 0.7112)
		(drill 0.4064)
		(layers "F.Cu" "B.Cu")
		(net "GND")
	)
	(via
		(at 173.049946 -353.8601)
		(size 0.7112)
		(drill 0.4064)
		(layers "F.Cu" "B.Cu")
		(net "GND")
	)
	(via
		(at 74.167746 -23.8887)
		(size 0.5588)
		(drill 0.3048)
		(layers "F.Cu" "B.Cu")
		(net "GND")
	)
	(via
		(at 259.206746 -228.6127)
		(size 0.7112)
		(drill 0.4064)
		(layers "F.Cu" "B.Cu")
		(net "GND")
	)
	(via
		(at 64.388746 -238.2647)
		(size 0.7112)
		(drill 0.4064)
		(layers "F.Cu" "B.Cu")
		(net "GND")
	)
	(via
		(at 152.018746 -325.2597)
		(size 0.7112)
		(drill 0.4064)
		(layers "F.Cu" "B.Cu")
		(net "GND")
	)
	(via
		(at 199.542146 -468.5665)
		(size 0.7112)
		(drill 0.4064)
		(layers "F.Cu" "B.Cu")
		(net "GND")
	)
	(via
		(at 39.98976 -72.116696)
		(size 0.5588)
		(drill 0.3048)
		(layers "F.Cu" "B.Cu")
		(net "GND")
	)
	(via
		(at 249.681746 -48.0187)
		(size 0.7112)
		(drill 0.4064)
		(layers "F.Cu" "B.Cu")
		(net "GND")
	)
	(via
		(at 177.444146 -398.4117)
		(size 0.7112)
		(drill 0.4064)
		(layers "F.Cu" "B.Cu")
		(net "GND")
	)
	(via
		(at 171.449746 -5.2197)
		(size 0.7112)
		(drill 0.4064)
		(layers "F.Cu" "B.Cu")
		(net "GND")
	)
	(via
		(at 97.815146 -501.8913)
		(size 0.7112)
		(drill 0.4064)
		(layers "F.Cu" "B.Cu")
		(net "GND")
	)
	(via
		(at 77.342746 -293.7891)
		(size 0.7112)
		(drill 0.4064)
		(layers "F.Cu" "B.Cu")
		(net "GND")
	)
	(via
		(at 28.269946 -208.5467)
		(size 0.7112)
		(drill 0.4064)
		(layers "F.Cu" "B.Cu")
		(net "GND")
	)
	(via
		(at 136.981946 -237.7059)
		(size 0.7112)
		(drill 0.4064)
		(layers "F.Cu" "B.Cu")
		(net "GND")
	)
	(via
		(at 154.279346 -96.5835)
		(size 0.7112)
		(drill 0.4064)
		(layers "F.Cu" "B.Cu")
		(net "GND")
	)
	(via
		(at 65.912746 -447.2051)
		(size 0.7112)
		(drill 0.4064)
		(layers "F.Cu" "B.Cu")
		(net "GND")
	)
	(via
		(at 252.602746 -242.8367)
		(size 0.7112)
		(drill 0.4064)
		(layers "F.Cu" "B.Cu")
		(net "GND")
	)
	(via
		(at 104.332278 -450.309488)
		(size 0.7112)
		(drill 0.4064)
		(layers "F.Cu" "B.Cu")
		(net "GND")
	)
	(via
		(at 128.371346 -292.9255)
		(size 0.7112)
		(drill 0.4064)
		(layers "F.Cu" "B.Cu")
		(net "GND")
	)
	(via
		(at 253.517146 -291.5793)
		(size 0.7112)
		(drill 0.4064)
		(layers "F.Cu" "B.Cu")
		(net "GND")
	)
	(via
		(at 108.711746 -151.7777)
		(size 0.7112)
		(drill 0.4064)
		(layers "F.Cu" "B.Cu")
		(net "GND")
	)
	(via
		(at 27.311604 -134.364984)
		(size 0.5588)
		(drill 0.3048)
		(layers "F.Cu" "B.Cu")
		(net "GND")
	)
	(via
		(at 125.424946 -502.2215)
		(size 0.7112)
		(drill 0.4064)
		(layers "F.Cu" "B.Cu")
		(net "GND")
	)
	(via
		(at 10.413746 -10.6807)
		(size 0.7112)
		(drill 0.4064)
		(layers "F.Cu" "B.Cu")
		(net "GND")
	)
	(via
		(at 54.372002 -80.800956)
		(size 0.5588)
		(drill 0.3048)
		(layers "F.Cu" "B.Cu")
		(net "GND")
	)
	(via
		(at 217.423746 -1.6637)
		(size 0.7112)
		(drill 0.4064)
		(layers "F.Cu" "B.Cu")
		(net "GND")
	)
	(via
		(at 252.729746 -186.1947)
		(size 0.7112)
		(drill 0.4064)
		(layers "F.Cu" "B.Cu")
		(net "GND")
	)
	(via
		(at 230.479346 -85.1535)
		(size 0.7112)
		(drill 0.4064)
		(layers "F.Cu" "B.Cu")
		(net "GND")
	)
	(via
		(at 33.781746 -35.9537)
		(size 0.7112)
		(drill 0.4064)
		(layers "F.Cu" "B.Cu")
		(net "GND")
	)
	(via
		(at 68.097146 -202.0443)
		(size 0.7112)
		(drill 0.4064)
		(layers "F.Cu" "B.Cu")
		(net "GND")
	)
	(via
		(at 255.218946 -58.7883)
		(size 0.7112)
		(drill 0.4064)
		(layers "F.Cu" "B.Cu")
		(net "GND")
	)
	(via
		(at 106.781346 -496.2017)
		(size 0.7112)
		(drill 0.4064)
		(layers "F.Cu" "B.Cu")
		(net "GND")
	)
	(via
		(at 259.841746 -466.6107)
		(size 0.7112)
		(drill 0.4064)
		(layers "F.Cu" "B.Cu")
		(net "GND")
	)
	(via
		(at 32.6644 -162.687)
		(size 0.5588)
		(drill 0.3048)
		(layers "F.Cu" "B.Cu")
		(net "GND")
	)
	(via
		(at 74.066146 -113.3221)
		(size 0.7112)
		(drill 0.4064)
		(layers "F.Cu" "B.Cu")
		(net "GND")
	)
	(via
		(at 169.722546 -298.1579)
		(size 0.7112)
		(drill 0.4064)
		(layers "F.Cu" "B.Cu")
		(net "GND")
	)
	(via
		(at 221.1324 -88.0618)
		(size 0.7112)
		(drill 0.4064)
		(layers "F.Cu" "B.Cu")
		(net "GND")
	)
	(via
		(at 221.335346 -328.0283)
		(size 0.7112)
		(drill 0.4064)
		(layers "F.Cu" "B.Cu")
		(net "GND")
	)
	(via
		(at 69.087746 -54.8767)
		(size 0.7112)
		(drill 0.4064)
		(layers "F.Cu" "B.Cu")
		(net "GND")
	)
	(via
		(at 69.468746 -430.2887)
		(size 0.7112)
		(drill 0.4064)
		(layers "F.Cu" "B.Cu")
		(net "GND")
	)
	(via
		(at 87.020146 -172.4279)
		(size 0.7112)
		(drill 0.4064)
		(layers "F.Cu" "B.Cu")
		(net "GND")
	)
	(via
		(at 215.010746 -297.2943)
		(size 0.7112)
		(drill 0.4064)
		(layers "F.Cu" "B.Cu")
		(net "GND")
	)
	(via
		(at 84.670646 -331.978)
		(size 0.7112)
		(drill 0.4064)
		(layers "F.Cu" "B.Cu")
		(net "GND")
	)
	(via
		(at 111.150146 -292.1127)
		(size 0.7112)
		(drill 0.4064)
		(layers "F.Cu" "B.Cu")
		(net "GND")
	)
	(via
		(at 15.112746 -22.9997)
		(size 0.7112)
		(drill 0.4064)
		(layers "F.Cu" "B.Cu")
		(net "GND")
	)
	(via
		(at 81.559146 -228.5111)
		(size 0.7112)
		(drill 0.4064)
		(layers "F.Cu" "B.Cu")
		(net "GND")
	)
	(via
		(at 60.00115 -478.31375)
		(size 0.5588)
		(drill 0.3048)
		(layers "F.Cu" "B.Cu")
		(net "GND")
	)
	(via
		(at 107.035346 -484.3907)
		(size 0.7112)
		(drill 0.4064)
		(layers "F.Cu" "B.Cu")
		(net "GND")
	)
	(via
		(at 212.115146 -148.2217)
		(size 0.7112)
		(drill 0.4064)
		(layers "F.Cu" "B.Cu")
		(net "GND")
	)
	(via
		(at 136.854946 -358.0765)
		(size 0.7112)
		(drill 0.4064)
		(layers "F.Cu" "B.Cu")
		(net "GND")
	)
	(via
		(at 6.095746 -175.0187)
		(size 0.5588)
		(drill 0.3048)
		(layers "F.Cu" "B.Cu")
		(net "GND")
	)
	(via
		(at 176.529746 -252.2347)
		(size 0.7112)
		(drill 0.4064)
		(layers "F.Cu" "B.Cu")
		(net "GND")
	)
	(via
		(at 213.334346 -396.7607)
		(size 0.7112)
		(drill 0.4064)
		(layers "F.Cu" "B.Cu")
		(net "GND")
	)
	(via
		(at 31.241746 -478.2947)
		(size 0.7112)
		(drill 0.4064)
		(layers "F.Cu" "B.Cu")
		(net "GND")
	)
	(via
		(at 139.699746 -180.3527)
		(size 0.7112)
		(drill 0.4064)
		(layers "F.Cu" "B.Cu")
		(net "GND")
	)
	(via
		(at 125.094746 -496.7097)
		(size 0.7112)
		(drill 0.4064)
		(layers "F.Cu" "B.Cu")
		(net "GND")
	)
	(via
		(at 80.060546 -220.8403)
		(size 0.7112)
		(drill 0.4064)
		(layers "F.Cu" "B.Cu")
		(net "GND")
	)
	(via
		(at 40.386 -275.082)
		(size 0.5588)
		(drill 0.3048)
		(layers "F.Cu" "B.Cu")
		(net "GND")
	)
	(via
		(at 206.120746 -198.6407)
		(size 0.7112)
		(drill 0.4064)
		(layers "F.Cu" "B.Cu")
		(net "GND")
	)
	(via
		(at 218.473782 -275.372068)
		(size 0.5588)
		(drill 0.3048)
		(layers "F.Cu" "B.Cu")
		(net "GND")
	)
	(via
		(at 213.995 -456.946)
		(size 0.7112)
		(drill 0.4064)
		(layers "F.Cu" "B.Cu")
		(net "GND")
	)
	(via
		(at 70.367906 -188.0362)
		(size 0.5588)
		(drill 0.3048)
		(layers "F.Cu" "B.Cu")
		(net "GND")
	)
	(via
		(at 104.901746 -78.1177)
		(size 0.7112)
		(drill 0.4064)
		(layers "F.Cu" "B.Cu")
		(net "GND")
	)
	(via
		(at 16.636746 -6.8707)
		(size 0.7112)
		(drill 0.4064)
		(layers "F.Cu" "B.Cu")
		(net "GND")
	)
	(via
		(at 125.475746 -206.6417)
		(size 0.7112)
		(drill 0.4064)
		(layers "F.Cu" "B.Cu")
		(net "GND")
	)
	(via
		(at 158.876746 -351.3963)
		(size 0.7112)
		(drill 0.4064)
		(layers "F.Cu" "B.Cu")
		(net "GND")
	)
	(via
		(at 57.6072 -427.7868)
		(size 0.7112)
		(drill 0.4064)
		(layers "F.Cu" "B.Cu")
		(net "GND")
	)
	(via
		(at 62.026546 -122.7709)
		(size 0.7112)
		(drill 0.4064)
		(layers "F.Cu" "B.Cu")
		(net "GND")
	)
	(via
		(at 198.119746 -436.1307)
		(size 0.7112)
		(drill 0.4064)
		(layers "F.Cu" "B.Cu")
		(net "GND")
	)
	(via
		(at 64.77 -285.9278)
		(size 0.5588)
		(drill 0.3048)
		(layers "F.Cu" "B.Cu")
		(net "GND")
	)
	(via
		(at 168.528746 -227.5967)
		(size 0.7112)
		(drill 0.4064)
		(layers "F.Cu" "B.Cu")
		(net "GND")
	)
	(via
		(at 159.892746 -216.6747)
		(size 0.7112)
		(drill 0.4064)
		(layers "F.Cu" "B.Cu")
		(net "GND")
	)
	(via
		(at 193.675 -186.436)
		(size 0.5588)
		(drill 0.3048)
		(layers "F.Cu" "B.Cu")
		(net "GND")
	)
	(via
		(at 213.105746 -79.6417)
		(size 0.7112)
		(drill 0.4064)
		(layers "F.Cu" "B.Cu")
		(net "GND")
	)
	(via
		(at 67.258946 -240.4999)
		(size 0.7112)
		(drill 0.4064)
		(layers "F.Cu" "B.Cu")
		(net "GND")
	)
	(via
		(at 81.609946 -257.1623)
		(size 0.7112)
		(drill 0.4064)
		(layers "F.Cu" "B.Cu")
		(net "GND")
	)
	(via
		(at 5.943346 -120.97893)
		(size 0.5588)
		(drill 0.3048)
		(layers "F.Cu" "B.Cu")
		(net "GND")
	)
	(via
		(at 95.249746 -420.8145)
		(size 0.7112)
		(drill 0.4064)
		(layers "F.Cu" "B.Cu")
		(net "GND")
	)
	(via
		(at 176.174146 -407.0223)
		(size 0.7112)
		(drill 0.4064)
		(layers "F.Cu" "B.Cu")
		(net "GND")
	)
	(via
		(at 219.2782 -293.0652)
		(size 0.7112)
		(drill 0.4064)
		(layers "F.Cu" "B.Cu")
		(net "GND")
	)
	(via
		(at 245.744746 -16.2687)
		(size 0.7112)
		(drill 0.4064)
		(layers "F.Cu" "B.Cu")
		(net "GND")
	)
	(via
		(at 5.461 -285.115)
		(size 0.7112)
		(drill 0.4064)
		(layers "F.Cu" "B.Cu")
		(net "GND")
	)
	(via
		(at 186.181746 -411.4927)
		(size 0.7112)
		(drill 0.4064)
		(layers "F.Cu" "B.Cu")
		(net "GND")
	)
	(via
		(at 38.480746 -297.9547)
		(size 0.7112)
		(drill 0.4064)
		(layers "F.Cu" "B.Cu")
		(net "GND")
	)
	(via
		(at 163.016946 -288.9631)
		(size 0.7112)
		(drill 0.4064)
		(layers "F.Cu" "B.Cu")
		(net "GND")
	)
	(via
		(at 71.881746 -279.2857)
		(size 0.7112)
		(drill 0.4064)
		(layers "F.Cu" "B.Cu")
		(net "GND")
	)
	(via
		(at 73.507346 -244.6909)
		(size 0.7112)
		(drill 0.4064)
		(layers "F.Cu" "B.Cu")
		(net "GND")
	)
	(via
		(at 22.7076 -237.5916)
		(size 0.5588)
		(drill 0.3048)
		(layers "F.Cu" "B.Cu")
		(net "GND")
	)
	(via
		(at 106.247946 -396.5575)
		(size 0.7112)
		(drill 0.4064)
		(layers "F.Cu" "B.Cu")
		(net "GND")
	)
	(via
		(at 59.308746 -245.3767)
		(size 0.7112)
		(drill 0.4064)
		(layers "F.Cu" "B.Cu")
		(net "GND")
	)
	(via
		(at 191.109346 -267.3477)
		(size 0.7112)
		(drill 0.4064)
		(layers "F.Cu" "B.Cu")
		(net "GND")
	)
	(via
		(at 209.524346 -127.1143)
		(size 0.7112)
		(drill 0.4064)
		(layers "F.Cu" "B.Cu")
		(net "GND")
	)
	(via
		(at 92.709746 -1.1557)
		(size 0.7112)
		(drill 0.4064)
		(layers "F.Cu" "B.Cu")
		(net "GND")
	)
	(via
		(at 86.918546 -155.7147)
		(size 0.7112)
		(drill 0.4064)
		(layers "F.Cu" "B.Cu")
		(net "GND")
	)
	(via
		(at 191.947546 -134.2771)
		(size 0.7112)
		(drill 0.4064)
		(layers "F.Cu" "B.Cu")
		(net "GND")
	)
	(via
		(at 82.968846 -309.5879)
		(size 0.7112)
		(drill 0.4064)
		(layers "F.Cu" "B.Cu")
		(net "GND")
	)
	(via
		(at 2.920746 -36.0807)
		(size 0.7112)
		(drill 0.4064)
		(layers "F.Cu" "B.Cu")
		(net "GND")
	)
	(via
		(at 36.446714 -471.5256)
		(size 0.7112)
		(drill 0.4064)
		(layers "F.Cu" "B.Cu")
		(net "GND")
	)
	(via
		(at 31.749746 -411.4927)
		(size 0.7112)
		(drill 0.4064)
		(layers "F.Cu" "B.Cu")
		(net "GND")
	)
	(via
		(at 184.784746 -280.9367)
		(size 0.7112)
		(drill 0.4064)
		(layers "F.Cu" "B.Cu")
		(net "GND")
	)
	(via
		(at 55.371746 -357.8479)
		(size 0.7112)
		(drill 0.4064)
		(layers "F.Cu" "B.Cu")
		(net "GND")
	)
	(via
		(at 233.425746 -166.6367)
		(size 0.7112)
		(drill 0.4064)
		(layers "F.Cu" "B.Cu")
		(net "GND")
	)
	(via
		(at 141.147546 -336.0293)
		(size 0.7112)
		(drill 0.4064)
		(layers "F.Cu" "B.Cu")
		(net "GND")
	)
	(via
		(at 167.715946 -498.9957)
		(size 0.7112)
		(drill 0.4064)
		(layers "F.Cu" "B.Cu")
		(net "GND")
	)
	(via
		(at 41.528746 -364.0709)
		(size 0.7112)
		(drill 0.4064)
		(layers "F.Cu" "B.Cu")
		(net "GND")
	)
	(via
		(at 85.724746 -471.4113)
		(size 0.7112)
		(drill 0.4064)
		(layers "F.Cu" "B.Cu")
		(net "GND")
	)
	(via
		(at 163.829746 -491.2487)
		(size 0.7112)
		(drill 0.4064)
		(layers "F.Cu" "B.Cu")
		(net "GND")
	)
	(via
		(at 59.054746 -263.6647)
		(size 0.7112)
		(drill 0.4064)
		(layers "F.Cu" "B.Cu")
		(net "GND")
	)
	(via
		(at 136.143746 -1.6637)
		(size 0.7112)
		(drill 0.4064)
		(layers "F.Cu" "B.Cu")
		(net "GND")
	)
	(via
		(at 58.800746 -400.0627)
		(size 0.7112)
		(drill 0.4064)
		(layers "F.Cu" "B.Cu")
		(net "GND")
	)
	(via
		(at 129.844546 -198.6407)
		(size 0.7112)
		(drill 0.4064)
		(layers "F.Cu" "B.Cu")
		(net "GND")
	)
	(via
		(at 12.318746 -61.7347)
		(size 0.7112)
		(drill 0.4064)
		(layers "F.Cu" "B.Cu")
		(net "GND")
	)
	(via
		(at 81.813146 -232.0671)
		(size 0.7112)
		(drill 0.4064)
		(layers "F.Cu" "B.Cu")
		(net "GND")
	)
	(via
		(at 170.687746 -336.5373)
		(size 0.7112)
		(drill 0.4064)
		(layers "F.Cu" "B.Cu")
		(net "GND")
	)
	(via
		(at 146.430746 -213.8807)
		(size 0.7112)
		(drill 0.4064)
		(layers "F.Cu" "B.Cu")
		(net "GND")
	)
	(via
		(at 181.279546 -115.6843)
		(size 0.7112)
		(drill 0.4064)
		(layers "F.Cu" "B.Cu")
		(net "GND")
	)
	(via
		(at 117.982746 -227.5967)
		(size 0.7112)
		(drill 0.4064)
		(layers "F.Cu" "B.Cu")
		(net "GND")
	)
	(via
		(at 54.645052 -18.429986)
		(size 0.5588)
		(drill 0.3048)
		(layers "F.Cu" "B.Cu")
		(net "GND")
	)
	(via
		(at 75.945746 -471.4113)
		(size 0.7112)
		(drill 0.4064)
		(layers "F.Cu" "B.Cu")
		(net "GND")
	)
	(via
		(at 79.069946 -14.0843)
		(size 0.7112)
		(drill 0.4064)
		(layers "F.Cu" "B.Cu")
		(net "GND")
	)
	(via
		(at 143.382746 -283.4767)
		(size 0.7112)
		(drill 0.4064)
		(layers "F.Cu" "B.Cu")
		(net "GND")
	)
	(via
		(at 199.374506 -186.3217)
		(size 0.5588)
		(drill 0.3048)
		(layers "F.Cu" "B.Cu")
		(net "GND")
	)
	(via
		(at 118.465346 -77.4573)
		(size 0.7112)
		(drill 0.4064)
		(layers "F.Cu" "B.Cu")
		(net "GND")
	)
	(via
		(at 163.588446 -459.951836)
		(size 0.7112)
		(drill 0.4064)
		(layers "F.Cu" "B.Cu")
		(net "GND")
	)
	(via
		(at 91.160346 -166.9161)
		(size 0.7112)
		(drill 0.4064)
		(layers "F.Cu" "B.Cu")
		(net "GND")
	)
	(via
		(at 136.346946 -364.8329)
		(size 0.7112)
		(drill 0.4064)
		(layers "F.Cu" "B.Cu")
		(net "GND")
	)
	(via
		(at 241.477546 -325.5645)
		(size 0.7112)
		(drill 0.4064)
		(layers "F.Cu" "B.Cu")
		(net "GND")
	)
	(via
		(at 23.875746 -14.8717)
		(size 0.5588)
		(drill 0.3048)
		(layers "F.Cu" "B.Cu")
		(net "GND")
	)
	(via
		(at 50.1904 -430.5046)
		(size 0.7112)
		(drill 0.4064)
		(layers "F.Cu" "B.Cu")
		(net "GND")
	)
	(via
		(at 80.771746 -288.9377)
		(size 0.7112)
		(drill 0.4064)
		(layers "F.Cu" "B.Cu")
		(net "GND")
	)
	(via
		(at 132.587746 -232.2957)
		(size 0.7112)
		(drill 0.4064)
		(layers "F.Cu" "B.Cu")
		(net "GND")
	)
	(via
		(at 259.333746 -26.6827)
		(size 0.7112)
		(drill 0.4064)
		(layers "F.Cu" "B.Cu")
		(net "GND")
	)
	(via
		(at 121.919746 -147.5867)
		(size 0.7112)
		(drill 0.4064)
		(layers "F.Cu" "B.Cu")
		(net "GND")
	)
	(via
		(at 182.371746 -296.9641)
		(size 0.7112)
		(drill 0.4064)
		(layers "F.Cu" "B.Cu")
		(net "GND")
	)
	(via
		(at 58.394346 -317.6397)
		(size 0.7112)
		(drill 0.4064)
		(layers "F.Cu" "B.Cu")
		(net "GND")
	)
	(via
		(at 83.895946 -221.4499)
		(size 0.7112)
		(drill 0.4064)
		(layers "F.Cu" "B.Cu")
		(net "GND")
	)
	(via
		(at 234.073446 -454.27265)
		(size 0.5588)
		(drill 0.3048)
		(layers "F.Cu" "B.Cu")
		(net "GND")
	)
	(via
		(at 65.404746 -126.5047)
		(size 0.7112)
		(drill 0.4064)
		(layers "F.Cu" "B.Cu")
		(net "GND")
	)
	(via
		(at 101.726746 -38.4937)
		(size 0.7112)
		(drill 0.4064)
		(layers "F.Cu" "B.Cu")
		(net "GND")
	)
	(via
		(at 86.715346 -181.6227)
		(size 0.7112)
		(drill 0.4064)
		(layers "F.Cu" "B.Cu")
		(net "GND")
	)
	(via
		(at 81.355946 -417.3093)
		(size 0.7112)
		(drill 0.4064)
		(layers "F.Cu" "B.Cu")
		(net "GND")
	)
	(via
		(at 95.656146 -328.6633)
		(size 0.7112)
		(drill 0.4064)
		(layers "F.Cu" "B.Cu")
		(net "GND")
	)
	(via
		(at 19.1262 -115.3414)
		(size 0.7112)
		(drill 0.4064)
		(layers "F.Cu" "B.Cu")
		(net "GND")
	)
	(via
		(at 40.132 -463.6516)
		(size 0.7112)
		(drill 0.4064)
		(layers "F.Cu" "B.Cu")
		(net "GND")
	)
	(via
		(at 130.682746 -255.9177)
		(size 0.7112)
		(drill 0.4064)
		(layers "F.Cu" "B.Cu")
		(net "GND")
	)
	(via
		(at 139.394946 -321.9069)
		(size 0.7112)
		(drill 0.4064)
		(layers "F.Cu" "B.Cu")
		(net "GND")
	)
	(via
		(at 155.574746 -410.3497)
		(size 0.7112)
		(drill 0.4064)
		(layers "F.Cu" "B.Cu")
		(net "GND")
	)
	(via
		(at 23.589742 -433.876704)
		(size 0.5588)
		(drill 0.3048)
		(layers "F.Cu" "B.Cu")
		(net "GND")
	)
	(via
		(at 5.409946 -330.2635)
		(size 0.7112)
		(drill 0.4064)
		(layers "F.Cu" "B.Cu")
		(net "GND")
	)
	(via
		(at 178.561746 -166.6367)
		(size 0.7112)
		(drill 0.4064)
		(layers "F.Cu" "B.Cu")
		(net "GND")
	)
	(via
		(at 245.5926 -401.1168)
		(size 0.7112)
		(drill 0.4064)
		(layers "F.Cu" "B.Cu")
		(net "GND")
	)
	(via
		(at 108.356146 -105.4989)
		(size 0.7112)
		(drill 0.4064)
		(layers "F.Cu" "B.Cu")
		(net "GND")
	)
	(via
		(at 84.670646 -376.4026)
		(size 0.7112)
		(drill 0.4064)
		(layers "F.Cu" "B.Cu")
		(net "GND")
	)
	(via
		(at 31.749746 -163.3347)
		(size 0.5588)
		(drill 0.3048)
		(layers "F.Cu" "B.Cu")
		(net "GND")
	)
	(via
		(at 5.968746 -406.9207)
		(size 0.5588)
		(drill 0.3048)
		(layers "F.Cu" "B.Cu")
		(net "GND")
	)
	(via
		(at 13.258546 -86.9569)
		(size 0.7112)
		(drill 0.4064)
		(layers "F.Cu" "B.Cu")
		(net "GND")
	)
	(via
		(at 210.057746 -249.4661)
		(size 0.7112)
		(drill 0.4064)
		(layers "F.Cu" "B.Cu")
		(net "GND")
	)
	(via
		(at 23.774146 -147.633944)
		(size 0.7112)
		(drill 0.4064)
		(layers "F.Cu" "B.Cu")
		(net "GND")
	)
	(via
		(at 259.206746 -274.7137)
		(size 0.7112)
		(drill 0.4064)
		(layers "F.Cu" "B.Cu")
		(net "GND")
	)
	(via
		(at 67.436746 -349.7453)
		(size 0.7112)
		(drill 0.4064)
		(layers "F.Cu" "B.Cu")
		(net "GND")
	)
	(via
		(at 135.254746 -490.3597)
		(size 0.7112)
		(drill 0.4064)
		(layers "F.Cu" "B.Cu")
		(net "GND")
	)
	(via
		(at 28.956 -362.0516)
		(size 0.5588)
		(drill 0.3048)
		(layers "F.Cu" "B.Cu")
		(net "GND")
	)
	(via
		(at 31.038546 -374.9167)
		(size 0.5588)
		(drill 0.3048)
		(layers "F.Cu" "B.Cu")
		(net "GND")
	)
	(via
		(at 229.742746 -107.2007)
		(size 0.7112)
		(drill 0.4064)
		(layers "F.Cu" "B.Cu")
		(net "GND")
	)
	(via
		(at 183.6928 -69.977)
		(size 0.7112)
		(drill 0.4064)
		(layers "F.Cu" "B.Cu")
		(net "GND")
	)
	(via
		(at 192.734946 -302.2981)
		(size 0.7112)
		(drill 0.4064)
		(layers "F.Cu" "B.Cu")
		(net "GND")
	)
	(via
		(at 79.654146 -479.8695)
		(size 0.7112)
		(drill 0.4064)
		(layers "F.Cu" "B.Cu")
		(net "GND")
	)
	(via
		(at 52.069746 -374.0531)
		(size 0.7112)
		(drill 0.4064)
		(layers "F.Cu" "B.Cu")
		(net "GND")
	)
	(via
		(at 3.937 -42.164)
		(size 0.7112)
		(drill 0.4064)
		(layers "F.Cu" "B.Cu")
		(net "GND")
	)
	(via
		(at 130.276346 -209.1817)
		(size 0.7112)
		(drill 0.4064)
		(layers "F.Cu" "B.Cu")
		(net "GND")
	)
	(via
		(at 235.841032 -22.287738)
		(size 0.5588)
		(drill 0.3048)
		(layers "F.Cu" "B.Cu")
		(net "GND")
	)
	(via
		(at 50.266346 -41.92905)
		(size 0.5588)
		(drill 0.3048)
		(layers "F.Cu" "B.Cu")
		(net "GND")
	)
	(via
		(at 235.102146 -409.4607)
		(size 0.7112)
		(drill 0.4064)
		(layers "F.Cu" "B.Cu")
		(net "GND")
	)
	(via
		(at 33.222946 -76.2635)
		(size 0.7112)
		(drill 0.4064)
		(layers "F.Cu" "B.Cu")
		(net "GND")
	)
	(via
		(at 131.317746 -360.1847)
		(size 0.7112)
		(drill 0.4064)
		(layers "F.Cu" "B.Cu")
		(net "GND")
	)
	(via
		(at 245.5672 -389.8392)
		(size 0.7112)
		(drill 0.4064)
		(layers "F.Cu" "B.Cu")
		(net "GND")
	)
	(via
		(at 174.523146 -209.2071)
		(size 0.7112)
		(drill 0.4064)
		(layers "F.Cu" "B.Cu")
		(net "GND")
	)
	(via
		(at 232.384346 -485.7623)
		(size 0.7112)
		(drill 0.4064)
		(layers "F.Cu" "B.Cu")
		(net "GND")
	)
	(via
		(at 10.743946 -143.2941)
		(size 0.7112)
		(drill 0.4064)
		(layers "F.Cu" "B.Cu")
		(net "GND")
	)
	(via
		(at 223.367346 -456.7301)
		(size 0.7112)
		(drill 0.4064)
		(layers "F.Cu" "B.Cu")
		(net "GND")
	)
	(via
		(at 152.780746 -242.4557)
		(size 0.7112)
		(drill 0.4064)
		(layers "F.Cu" "B.Cu")
		(net "GND")
	)
	(via
		(at 195.833746 -75.0697)
		(size 0.5588)
		(drill 0.3048)
		(layers "F.Cu" "B.Cu")
		(net "GND")
	)
	(via
		(at 57.911746 -361.0737)
		(size 0.7112)
		(drill 0.4064)
		(layers "F.Cu" "B.Cu")
		(net "GND")
	)
	(via
		(at 35.0266 -280.2636)
		(size 0.7112)
		(drill 0.4064)
		(layers "F.Cu" "B.Cu")
		(net "GND")
	)
	(via
		(at 199.516746 -162.8267)
		(size 0.7112)
		(drill 0.4064)
		(layers "F.Cu" "B.Cu")
		(net "GND")
	)
	(via
		(at 60.375546 -108.2167)
		(size 0.7112)
		(drill 0.4064)
		(layers "F.Cu" "B.Cu")
		(net "GND")
	)
	(via
		(at 204.876146 -302.1965)
		(size 0.7112)
		(drill 0.4064)
		(layers "F.Cu" "B.Cu")
		(net "GND")
	)
	(via
		(at 194.335146 -422.8973)
		(size 0.7112)
		(drill 0.4064)
		(layers "F.Cu" "B.Cu")
		(net "GND")
	)
	(via
		(at 205.282546 -327.7489)
		(size 0.7112)
		(drill 0.4064)
		(layers "F.Cu" "B.Cu")
		(net "GND")
	)
	(via
		(at 170.535346 -412.8389)
		(size 0.7112)
		(drill 0.4064)
		(layers "F.Cu" "B.Cu")
		(net "GND")
	)
	(via
		(at 30.5054 -414.8074)
		(size 0.7112)
		(drill 0.4064)
		(layers "F.Cu" "B.Cu")
		(net "GND")
	)
	(via
		(at 163.829746 -496.0747)
		(size 0.7112)
		(drill 0.4064)
		(layers "F.Cu" "B.Cu")
		(net "GND")
	)
	(via
		(at 27.939746 -344.1827)
		(size 0.5588)
		(drill 0.3048)
		(layers "F.Cu" "B.Cu")
		(net "GND")
	)
	(via
		(at 200.532746 -319.2907)
		(size 0.7112)
		(drill 0.4064)
		(layers "F.Cu" "B.Cu")
		(net "GND")
	)
	(via
		(at 181.228746 -271.4117)
		(size 0.7112)
		(drill 0.4064)
		(layers "F.Cu" "B.Cu")
		(net "GND")
	)
	(via
		(at 258.317746 -319.0367)
		(size 0.7112)
		(drill 0.4064)
		(layers "F.Cu" "B.Cu")
		(net "GND")
	)
	(via
		(at 202.767946 -341.4395)
		(size 0.7112)
		(drill 0.4064)
		(layers "F.Cu" "B.Cu")
		(net "GND")
	)
	(via
		(at 61.315346 -331.0255)
		(size 0.7112)
		(drill 0.4064)
		(layers "F.Cu" "B.Cu")
		(net "GND")
	)
	(via
		(at 244.1956 -391.3632)
		(size 0.7112)
		(drill 0.4064)
		(layers "F.Cu" "B.Cu")
		(net "GND")
	)
	(via
		(at 93.471746 -492.8235)
		(size 0.7112)
		(drill 0.4064)
		(layers "F.Cu" "B.Cu")
		(net "GND")
	)
	(via
		(at 259.587746 -132.9817)
		(size 0.7112)
		(drill 0.4064)
		(layers "F.Cu" "B.Cu")
		(net "GND")
	)
	(via
		(at 144.297146 -23.2537)
		(size 0.7112)
		(drill 0.4064)
		(layers "F.Cu" "B.Cu")
		(net "GND")
	)
	(via
		(at 182.016146 -187.1599)
		(size 0.7112)
		(drill 0.4064)
		(layers "F.Cu" "B.Cu")
		(net "GND")
	)
	(via
		(at 246.887746 -253.1237)
		(size 0.7112)
		(drill 0.4064)
		(layers "F.Cu" "B.Cu")
		(net "GND")
	)
	(via
		(at 62.382146 -196.4563)
		(size 0.7112)
		(drill 0.4064)
		(layers "F.Cu" "B.Cu")
		(net "GND")
	)
	(via
		(at 109.854746 -410.8577)
		(size 0.7112)
		(drill 0.4064)
		(layers "F.Cu" "B.Cu")
		(net "GND")
	)
	(via
		(at 252.348746 -214.1347)
		(size 0.7112)
		(drill 0.4064)
		(layers "F.Cu" "B.Cu")
		(net "GND")
	)
	(via
		(at 142.950946 -37.2745)
		(size 0.7112)
		(drill 0.4064)
		(layers "F.Cu" "B.Cu")
		(net "GND")
	)
	(via
		(at 117.855746 -167.5257)
		(size 0.7112)
		(drill 0.4064)
		(layers "F.Cu" "B.Cu")
		(net "GND")
	)
	(via
		(at 253.644146 -322.6943)
		(size 0.7112)
		(drill 0.4064)
		(layers "F.Cu" "B.Cu")
		(net "GND")
	)
	(via
		(at 197.967346 -50.9397)
		(size 0.7112)
		(drill 0.4064)
		(layers "F.Cu" "B.Cu")
		(net "GND")
	)
	(via
		(at 156.641546 -245.6815)
		(size 0.7112)
		(drill 0.4064)
		(layers "F.Cu" "B.Cu")
		(net "GND")
	)
	(via
		(at 70.611746 -138.5189)
		(size 0.7112)
		(drill 0.4064)
		(layers "F.Cu" "B.Cu")
		(net "GND")
	)
	(via
		(at 4.597146 -341.2617)
		(size 0.7112)
		(drill 0.4064)
		(layers "F.Cu" "B.Cu")
		(net "GND")
	)
	(via
		(at 259.206746 -223.6597)
		(size 0.7112)
		(drill 0.4064)
		(layers "F.Cu" "B.Cu")
		(net "GND")
	)
	(via
		(at 31.368746 -443.7507)
		(size 0.7112)
		(drill 0.4064)
		(layers "F.Cu" "B.Cu")
		(net "GND")
	)
	(via
		(at 188.086746 -318.1477)
		(size 0.7112)
		(drill 0.4064)
		(layers "F.Cu" "B.Cu")
		(net "GND")
	)
	(via
		(at 146.176746 -203.7207)
		(size 0.7112)
		(drill 0.4064)
		(layers "F.Cu" "B.Cu")
		(net "GND")
	)
	(via
		(at 257.885946 -448.5513)
		(size 0.7112)
		(drill 0.4064)
		(layers "F.Cu" "B.Cu")
		(net "GND")
	)
	(via
		(at 5.765546 -404.932896)
		(size 0.5588)
		(drill 0.3048)
		(layers "F.Cu" "B.Cu")
		(net "GND")
	)
	(via
		(at 234.060746 -253.7587)
		(size 0.7112)
		(drill 0.4064)
		(layers "F.Cu" "B.Cu")
		(net "GND")
	)
	(via
		(at 110.057946 -495.4397)
		(size 0.7112)
		(drill 0.4064)
		(layers "F.Cu" "B.Cu")
		(net "GND")
	)
	(via
		(at 127.736346 -434.2511)
		(size 0.7112)
		(drill 0.4064)
		(layers "F.Cu" "B.Cu")
		(net "GND")
	)
	(via
		(at 52.653946 -256.0701)
		(size 0.7112)
		(drill 0.4064)
		(layers "F.Cu" "B.Cu")
		(net "GND")
	)
	(via
		(at 117.601746 -224.5487)
		(size 0.7112)
		(drill 0.4064)
		(layers "F.Cu" "B.Cu")
		(net "GND")
	)
	(via
		(at 23.621746 -24.416512)
		(size 0.5588)
		(drill 0.3048)
		(layers "F.Cu" "B.Cu")
		(net "GND")
	)
	(via
		(at 158.622746 -5.8547)
		(size 0.7112)
		(drill 0.4064)
		(layers "F.Cu" "B.Cu")
		(net "GND")
	)
	(via
		(at 167.563546 -367.2713)
		(size 0.7112)
		(drill 0.4064)
		(layers "F.Cu" "B.Cu")
		(net "GND")
	)
	(via
		(at 6.044946 -383.0447)
		(size 0.5588)
		(drill 0.3048)
		(layers "F.Cu" "B.Cu")
		(net "GND")
	)
	(via
		(at 136.905746 -388.2009)
		(size 0.7112)
		(drill 0.4064)
		(layers "F.Cu" "B.Cu")
		(net "GND")
	)
	(via
		(at 35.941 -180.594)
		(size 0.5588)
		(drill 0.3048)
		(layers "F.Cu" "B.Cu")
		(net "GND")
	)
	(via
		(at 254.406146 -488.0483)
		(size 0.7112)
		(drill 0.4064)
		(layers "F.Cu" "B.Cu")
		(net "GND")
	)
	(via
		(at 203.961746 -141.7447)
		(size 0.7112)
		(drill 0.4064)
		(layers "F.Cu" "B.Cu")
		(net "GND")
	)
	(via
		(at 206.375 -482.219)
		(size 0.5588)
		(drill 0.3048)
		(layers "F.Cu" "B.Cu")
		(net "GND")
	)
	(via
		(at 255.853946 -105.3973)
		(size 0.7112)
		(drill 0.4064)
		(layers "F.Cu" "B.Cu")
		(net "GND")
	)
	(via
		(at 225.3996 -65.9638)
		(size 0.7112)
		(drill 0.4064)
		(layers "F.Cu" "B.Cu")
		(net "GND")
	)
	(via
		(at 135.254746 -415.4297)
		(size 0.7112)
		(drill 0.4064)
		(layers "F.Cu" "B.Cu")
		(net "GND")
	)
	(via
		(at 177.977546 -46.1645)
		(size 0.7112)
		(drill 0.4064)
		(layers "F.Cu" "B.Cu")
		(net "GND")
	)
	(via
		(at 159.054546 -300.5963)
		(size 0.7112)
		(drill 0.4064)
		(layers "F.Cu" "B.Cu")
		(net "GND")
	)
	(via
		(at 220.268546 -239.1029)
		(size 0.7112)
		(drill 0.4064)
		(layers "F.Cu" "B.Cu")
		(net "GND")
	)
	(via
		(at 188.493146 -335.4451)
		(size 0.7112)
		(drill 0.4064)
		(layers "F.Cu" "B.Cu")
		(net "GND")
	)
	(via
		(at 40.0304 -285.736792)
		(size 0.5588)
		(drill 0.3048)
		(layers "F.Cu" "B.Cu")
		(net "GND")
	)
	(via
		(at 18.490946 -249.6693)
		(size 0.7112)
		(drill 0.4064)
		(layers "F.Cu" "B.Cu")
		(net "GND")
	)
	(via
		(at 225.275902 -368.04854)
		(size 0.7112)
		(drill 0.4064)
		(layers "F.Cu" "B.Cu")
		(net "GND")
	)
	(via
		(at 118.236746 -321.4497)
		(size 0.7112)
		(drill 0.4064)
		(layers "F.Cu" "B.Cu")
		(net "GND")
	)
	(via
		(at 209.168746 -432.3207)
		(size 0.7112)
		(drill 0.4064)
		(layers "F.Cu" "B.Cu")
		(net "GND")
	)
	(via
		(at 39.953946 -1.3081)
		(size 0.7112)
		(drill 0.4064)
		(layers "F.Cu" "B.Cu")
		(net "GND")
	)
	(via
		(at 117.601746 -219.7227)
		(size 0.7112)
		(drill 0.4064)
		(layers "F.Cu" "B.Cu")
		(net "GND")
	)
	(via
		(at 83.819746 -129.6543)
		(size 0.7112)
		(drill 0.4064)
		(layers "F.Cu" "B.Cu")
		(net "GND")
	)
	(via
		(at 64.643 -504.825)
		(size 0.7112)
		(drill 0.4064)
		(layers "F.Cu" "B.Cu")
		(net "GND")
	)
	(via
		(at 242.010946 -50.5841)
		(size 0.7112)
		(drill 0.4064)
		(layers "F.Cu" "B.Cu")
		(net "GND")
	)
	(via
		(at 223.450658 -371.778784)
		(size 0.7112)
		(drill 0.4064)
		(layers "F.Cu" "B.Cu")
		(net "GND")
	)
	(via
		(at 69.341746 -245.2497)
		(size 0.7112)
		(drill 0.4064)
		(layers "F.Cu" "B.Cu")
		(net "GND")
	)
	(via
		(at 87.248746 -15.2781)
		(size 0.5588)
		(drill 0.3048)
		(layers "F.Cu" "B.Cu")
		(net "GND")
	)
	(via
		(at 203.453746 -230.3907)
		(size 0.7112)
		(drill 0.4064)
		(layers "F.Cu" "B.Cu")
		(net "GND")
	)
	(via
		(at 128.879346 -427.5709)
		(size 0.7112)
		(drill 0.4064)
		(layers "F.Cu" "B.Cu")
		(net "GND")
	)
	(via
		(at 83.514946 -94.5769)
		(size 0.7112)
		(drill 0.4064)
		(layers "F.Cu" "B.Cu")
		(net "GND")
	)
	(via
		(at 148.157946 -249.0343)
		(size 0.7112)
		(drill 0.4064)
		(layers "F.Cu" "B.Cu")
		(net "GND")
	)
	(via
		(at 89.408 -431.9016)
		(size 0.7112)
		(drill 0.4064)
		(layers "F.Cu" "B.Cu")
		(net "GND")
	)
	(via
		(at 154.812746 -429.7807)
		(size 0.7112)
		(drill 0.4064)
		(layers "F.Cu" "B.Cu")
		(net "GND")
	)
	(via
		(at 85.953346 -228.8667)
		(size 0.7112)
		(drill 0.4064)
		(layers "F.Cu" "B.Cu")
		(net "GND")
	)
	(via
		(at 124.586746 -122.6947)
		(size 0.7112)
		(drill 0.4064)
		(layers "F.Cu" "B.Cu")
		(net "GND")
	)
	(via
		(at 210.235546 -226.6823)
		(size 0.7112)
		(drill 0.4064)
		(layers "F.Cu" "B.Cu")
		(net "GND")
	)
	(via
		(at 166.115746 -72.7837)
		(size 0.7112)
		(drill 0.4064)
		(layers "F.Cu" "B.Cu")
		(net "GND")
	)
	(via
		(at 64.109346 -336.8929)
		(size 0.7112)
		(drill 0.4064)
		(layers "F.Cu" "B.Cu")
		(net "GND")
	)
	(via
		(at 67.2592 -320.3702)
		(size 0.7112)
		(drill 0.4064)
		(layers "F.Cu" "B.Cu")
		(net "GND")
	)
	(via
		(at 53.847746 -398.4117)
		(size 0.7112)
		(drill 0.4064)
		(layers "F.Cu" "B.Cu")
		(net "GND")
	)
	(via
		(at 35.779456 -265.40079)
		(size 0.7112)
		(drill 0.4064)
		(layers "F.Cu" "B.Cu")
		(net "GND")
	)
	(via
		(at 145.541746 -425.5897)
		(size 0.7112)
		(drill 0.4064)
		(layers "F.Cu" "B.Cu")
		(net "GND")
	)
	(via
		(at 85.877146 -206.1591)
		(size 0.7112)
		(drill 0.4064)
		(layers "F.Cu" "B.Cu")
		(net "GND")
	)
	(via
		(at 79.2734 -360.8578)
		(size 0.7112)
		(drill 0.4064)
		(layers "F.Cu" "B.Cu")
		(net "GND")
	)
	(via
		(at 221.340934 -481.576888)
		(size 0.5588)
		(drill 0.3048)
		(layers "F.Cu" "B.Cu")
		(net "GND")
	)
	(via
		(at 62.484 -13.2334)
		(size 0.7112)
		(drill 0.4064)
		(layers "F.Cu" "B.Cu")
		(net "GND")
	)
	(via
		(at 59.0296 -56.0578)
		(size 0.7112)
		(drill 0.4064)
		(layers "F.Cu" "B.Cu")
		(net "GND")
	)
	(via
		(at 213.4616 -464.0834)
		(size 0.7112)
		(drill 0.3556)
		(layers "F.Cu" "B.Cu")
		(net "GND")
	)
	(via
		(at 106.044746 -27.4447)
		(size 0.7112)
		(drill 0.4064)
		(layers "F.Cu" "B.Cu")
		(net "GND")
	)
	(via
		(at 146.913346 -112.0267)
		(size 0.7112)
		(drill 0.4064)
		(layers "F.Cu" "B.Cu")
		(net "GND")
	)
	(via
		(at 61.493146 -129.9845)
		(size 0.7112)
		(drill 0.4064)
		(layers "F.Cu" "B.Cu")
		(net "GND")
	)
	(via
		(at 249.935746 -112.9157)
		(size 0.7112)
		(drill 0.4064)
		(layers "F.Cu" "B.Cu")
		(net "GND")
	)
	(via
		(at 147.065746 -283.0957)
		(size 0.7112)
		(drill 0.4064)
		(layers "F.Cu" "B.Cu")
		(net "GND")
	)
	(via
		(at 37.0586 -295.4528)
		(size 0.7112)
		(drill 0.4064)
		(layers "F.Cu" "B.Cu")
		(net "GND")
	)
	(via
		(at 240.994946 -266.1793)
		(size 0.7112)
		(drill 0.4064)
		(layers "F.Cu" "B.Cu")
		(net "GND")
	)
	(via
		(at 20.193 -504.825)
		(size 0.7112)
		(drill 0.4064)
		(layers "F.Cu" "B.Cu")
		(net "GND")
	)
	(via
		(at 118.236746 -326.2757)
		(size 0.7112)
		(drill 0.4064)
		(layers "F.Cu" "B.Cu")
		(net "GND")
	)
	(via
		(at 49.910746 -308.7497)
		(size 0.7112)
		(drill 0.4064)
		(layers "F.Cu" "B.Cu")
		(net "GND")
	)
	(via
		(at 98.272346 -76.0095)
		(size 0.7112)
		(drill 0.4064)
		(layers "F.Cu" "B.Cu")
		(net "GND")
	)
	(via
		(at 226.7458 -438.8612)
		(size 0.7112)
		(drill 0.4064)
		(layers "F.Cu" "B.Cu")
		(net "GND")
	)
	(via
		(at 247.903746 -279.6667)
		(size 0.7112)
		(drill 0.4064)
		(layers "F.Cu" "B.Cu")
		(net "GND")
	)
	(via
		(at 53.390546 -298.0563)
		(size 0.7112)
		(drill 0.4064)
		(layers "F.Cu" "B.Cu")
		(net "GND")
	)
	(via
		(at 204.851 -174.5615)
		(size 0.5588)
		(drill 0.3048)
		(layers "F.Cu" "B.Cu")
		(net "GND")
	)
	(via
		(at 135.762746 -204.7113)
		(size 0.7112)
		(drill 0.4064)
		(layers "F.Cu" "B.Cu")
		(net "GND")
	)
	(via
		(at 123.062746 -275.8059)
		(size 0.7112)
		(drill 0.4064)
		(layers "F.Cu" "B.Cu")
		(net "GND")
	)
	(via
		(at 215.610694 -371.465602)
		(size 0.5588)
		(drill 0.3048)
		(layers "F.Cu" "B.Cu")
		(net "GND")
	)
	(via
		(at 248.005346 -450.1515)
		(size 0.7112)
		(drill 0.4064)
		(layers "F.Cu" "B.Cu")
		(net "GND")
	)
	(via
		(at 228.345746 -153.5557)
		(size 0.7112)
		(drill 0.4064)
		(layers "F.Cu" "B.Cu")
		(net "GND")
	)
	(via
		(at 10.667746 -50.8127)
		(size 0.5588)
		(drill 0.3048)
		(layers "F.Cu" "B.Cu")
		(net "GND")
	)
	(via
		(at 205.790546 -319.3669)
		(size 0.7112)
		(drill 0.4064)
		(layers "F.Cu" "B.Cu")
		(net "GND")
	)
	(via
		(at 39.98976 -79.736696)
		(size 0.5588)
		(drill 0.3048)
		(layers "F.Cu" "B.Cu")
		(net "GND")
	)
	(via
		(at 252.043946 -489.9787)
		(size 0.7112)
		(drill 0.4064)
		(layers "F.Cu" "B.Cu")
		(net "GND")
	)
	(via
		(at 108.8644 -429.5648)
		(size 0.7112)
		(drill 0.4064)
		(layers "F.Cu" "B.Cu")
		(net "GND")
	)
	(via
		(at 223.3168 -431.4698)
		(size 0.7112)
		(drill 0.4064)
		(layers "F.Cu" "B.Cu")
		(net "GND")
	)
	(via
		(at 46.482 -504.825)
		(size 0.7112)
		(drill 0.4064)
		(layers "F.Cu" "B.Cu")
		(net "GND")
	)
	(via
		(at 35.407346 -94.5769)
		(size 0.7112)
		(drill 0.4064)
		(layers "F.Cu" "B.Cu")
		(net "GND")
	)
	(via
		(at 235.076746 -319.6717)
		(size 0.7112)
		(drill 0.4064)
		(layers "F.Cu" "B.Cu")
		(net "GND")
	)
	(via
		(at 146.329146 -122.3899)
		(size 0.7112)
		(drill 0.4064)
		(layers "F.Cu" "B.Cu")
		(net "GND")
	)
	(via
		(at 167.525446 -459.901036)
		(size 0.5588)
		(drill 0.3048)
		(layers "F.Cu" "B.Cu")
		(net "GND")
	)
	(via
		(at 221.433644 -51.796696)
		(size 0.7112)
		(drill 0.4064)
		(layers "F.Cu" "B.Cu")
		(net "GND")
	)
	(via
		(at 175.615346 -139.2809)
		(size 0.7112)
		(drill 0.4064)
		(layers "F.Cu" "B.Cu")
		(net "GND")
	)
	(via
		(at 116.915946 -487.7689)
		(size 0.7112)
		(drill 0.4064)
		(layers "F.Cu" "B.Cu")
		(net "GND")
	)
	(via
		(at 176.428146 -449.1863)
		(size 0.7112)
		(drill 0.4064)
		(layers "F.Cu" "B.Cu")
		(net "GND")
	)
	(via
		(at 6.095746 -471.9193)
		(size 0.7112)
		(drill 0.4064)
		(layers "F.Cu" "B.Cu")
		(net "GND")
	)
	(via
		(at 219.456 -400.8628)
		(size 0.7112)
		(drill 0.4064)
		(layers "F.Cu" "B.Cu")
		(net "GND")
	)
	(via
		(at 194.286632 -494.434368)
		(size 0.5588)
		(drill 0.3048)
		(layers "F.Cu" "B.Cu")
		(net "GND")
	)
	(via
		(at 55.244746 -249.1867)
		(size 0.7112)
		(drill 0.4064)
		(layers "F.Cu" "B.Cu")
		(net "GND")
	)
	(via
		(at 79.628746 -487.4387)
		(size 0.5588)
		(drill 0.3048)
		(layers "F.Cu" "B.Cu")
		(net "GND")
	)
	(via
		(at 169.163746 -158.3817)
		(size 0.7112)
		(drill 0.4064)
		(layers "F.Cu" "B.Cu")
		(net "GND")
	)
	(via
		(at 41.528746 -35.5727)
		(size 0.7112)
		(drill 0.4064)
		(layers "F.Cu" "B.Cu")
		(net "GND")
	)
	(via
		(at 9.143746 -384.6957)
		(size 0.5588)
		(drill 0.3048)
		(layers "F.Cu" "B.Cu")
		(net "GND")
	)
	(via
		(at 80.390746 -285.6357)
		(size 0.7112)
		(drill 0.4064)
		(layers "F.Cu" "B.Cu")
		(net "GND")
	)
	(via
		(at 46.049946 -67.9069)
		(size 0.7112)
		(drill 0.4064)
		(layers "F.Cu" "B.Cu")
		(net "GND")
	)
	(via
		(at 191.845946 -483.1461)
		(size 0.7112)
		(drill 0.4064)
		(layers "F.Cu" "B.Cu")
		(net "GND")
	)
	(via
		(at 144.652746 -409.0797)
		(size 0.7112)
		(drill 0.4064)
		(layers "F.Cu" "B.Cu")
		(net "GND")
	)
	(via
		(at 182.143146 -432.4223)
		(size 0.7112)
		(drill 0.4064)
		(layers "F.Cu" "B.Cu")
		(net "GND")
	)
	(via
		(at 108.330746 -471.2843)
		(size 0.7112)
		(drill 0.4064)
		(layers "F.Cu" "B.Cu")
		(net "GND")
	)
	(via
		(at 159.638746 -415.7091)
		(size 0.7112)
		(drill 0.4064)
		(layers "F.Cu" "B.Cu")
		(net "GND")
	)
	(via
		(at 81.482946 -147.8407)
		(size 0.7112)
		(drill 0.4064)
		(layers "F.Cu" "B.Cu")
		(net "GND")
	)
	(via
		(at 106.578146 -116.4717)
		(size 0.7112)
		(drill 0.4064)
		(layers "F.Cu" "B.Cu")
		(net "GND")
	)
	(via
		(at 184.276746 -317.6651)
		(size 0.7112)
		(drill 0.4064)
		(layers "F.Cu" "B.Cu")
		(net "GND")
	)
	(via
		(at 43.763946 -372.3259)
		(size 0.7112)
		(drill 0.4064)
		(layers "F.Cu" "B.Cu")
		(net "GND")
	)
	(via
		(at 46.2026 -425.5262)
		(size 0.7112)
		(drill 0.4064)
		(layers "F.Cu" "B.Cu")
		(net "GND")
	)
	(via
		(at 60.629546 -457.6699)
		(size 0.7112)
		(drill 0.4064)
		(layers "F.Cu" "B.Cu")
		(net "GND")
	)
	(via
		(at 70.865746 -1.2827)
		(size 0.7112)
		(drill 0.4064)
		(layers "F.Cu" "B.Cu")
		(net "GND")
	)
	(via
		(at 215.391746 -89.5477)
		(size 0.7112)
		(drill 0.4064)
		(layers "F.Cu" "B.Cu")
		(net "GND")
	)
	(via
		(at 115.569746 -111.3917)
		(size 0.7112)
		(drill 0.4064)
		(layers "F.Cu" "B.Cu")
		(net "GND")
	)
	(via
		(at 236.854746 -56.7817)
		(size 0.7112)
		(drill 0.4064)
		(layers "F.Cu" "B.Cu")
		(net "GND")
	)
	(via
		(at 85.953346 -100.4951)
		(size 0.7112)
		(drill 0.4064)
		(layers "F.Cu" "B.Cu")
		(net "GND")
	)
	(via
		(at 158.876746 -55.2577)
		(size 0.7112)
		(drill 0.4064)
		(layers "F.Cu" "B.Cu")
		(net "GND")
	)
	(via
		(at 64.134746 -184.4167)
		(size 0.5588)
		(drill 0.3048)
		(layers "F.Cu" "B.Cu")
		(net "GND")
	)
	(via
		(at 171.576746 -18.9357)
		(size 0.7112)
		(drill 0.4064)
		(layers "F.Cu" "B.Cu")
		(net "GND")
	)
	(via
		(at 231.469946 -457.4159)
		(size 0.7112)
		(drill 0.4064)
		(layers "F.Cu" "B.Cu")
		(net "GND")
	)
	(via
		(at 255.472946 -68.9483)
		(size 0.7112)
		(drill 0.4064)
		(layers "F.Cu" "B.Cu")
		(net "GND")
	)
	(via
		(at 107.517946 -252.4887)
		(size 0.7112)
		(drill 0.4064)
		(layers "F.Cu" "B.Cu")
		(net "GND")
	)
	(via
		(at 192.658746 -348.2467)
		(size 0.5588)
		(drill 0.3048)
		(layers "F.Cu" "B.Cu")
		(net "GND")
	)
	(via
		(at 135.508746 -478.5487)
		(size 0.7112)
		(drill 0.4064)
		(layers "F.Cu" "B.Cu")
		(net "GND")
	)
	(via
		(at 83.2866 -117.6528)
		(size 0.7112)
		(drill 0.4064)
		(layers "F.Cu" "B.Cu")
		(net "GND")
	)
	(via
		(at 81.533746 -433.3367)
		(size 0.7112)
		(drill 0.4064)
		(layers "F.Cu" "B.Cu")
		(net "GND")
	)
	(via
		(at 63.372746 -280.4541)
		(size 0.7112)
		(drill 0.4064)
		(layers "F.Cu" "B.Cu")
		(net "GND")
	)
	(via
		(at 9.7536 -130.7846)
		(size 0.5588)
		(drill 0.3048)
		(layers "F.Cu" "B.Cu")
		(net "GND")
	)
	(via
		(at 136.778746 -280.1747)
		(size 0.7112)
		(drill 0.4064)
		(layers "F.Cu" "B.Cu")
		(net "GND")
	)
	(via
		(at 209.854546 -328.7903)
		(size 0.7112)
		(drill 0.4064)
		(layers "F.Cu" "B.Cu")
		(net "GND")
	)
	(via
		(at 208.0006 -475.1832)
		(size 0.7112)
		(drill 0.4064)
		(layers "F.Cu" "B.Cu")
		(net "GND")
	)
	(via
		(at 204.037946 -362.3691)
		(size 0.7112)
		(drill 0.4064)
		(layers "F.Cu" "B.Cu")
		(net "GND")
	)
	(via
		(at 123.265946 -135.7757)
		(size 0.7112)
		(drill 0.4064)
		(layers "F.Cu" "B.Cu")
		(net "GND")
	)
	(via
		(at 23.748746 -227.876608)
		(size 0.7112)
		(drill 0.4064)
		(layers "F.Cu" "B.Cu")
		(net "GND")
	)
	(via
		(at 33.8328 -287.5534)
		(size 0.7112)
		(drill 0.4064)
		(layers "F.Cu" "B.Cu")
		(net "GND")
	)
	(via
		(at 129.869946 -114.0841)
		(size 0.7112)
		(drill 0.4064)
		(layers "F.Cu" "B.Cu")
		(net "GND")
	)
	(via
		(at 81.7626 -92.6084)
		(size 0.5588)
		(drill 0.3048)
		(layers "F.Cu" "B.Cu")
		(net "GND")
	)
	(via
		(at 41.147746 -214.2617)
		(size 0.7112)
		(drill 0.4064)
		(layers "F.Cu" "B.Cu")
		(net "GND")
	)
	(via
		(at 65.023746 -282.4861)
		(size 0.7112)
		(drill 0.3556)
		(layers "F.Cu" "B.Cu")
		(net "GND")
	)
	(via
		(at 29.463746 -478.1677)
		(size 0.7112)
		(drill 0.4064)
		(layers "F.Cu" "B.Cu")
		(net "GND")
	)
	(via
		(at 234.289346 -212.4329)
		(size 0.7112)
		(drill 0.4064)
		(layers "F.Cu" "B.Cu")
		(net "GND")
	)
	(via
		(at 233.654346 -235.0389)
		(size 0.7112)
		(drill 0.4064)
		(layers "F.Cu" "B.Cu")
		(net "GND")
	)
	(via
		(at 166.750746 -431.0507)
		(size 0.7112)
		(drill 0.4064)
		(layers "F.Cu" "B.Cu")
		(net "GND")
	)
	(via
		(at 246.760746 -266.2047)
		(size 0.7112)
		(drill 0.4064)
		(layers "F.Cu" "B.Cu")
		(net "GND")
	)
	(via
		(at 235.330746 -369.9637)
		(size 0.7112)
		(drill 0.4064)
		(layers "F.Cu" "B.Cu")
		(net "GND")
	)
	(via
		(at 175.894746 -270.0147)
		(size 0.7112)
		(drill 0.4064)
		(layers "F.Cu" "B.Cu")
		(net "GND")
	)
	(via
		(at 212.381846 -181.3687)
		(size 0.7112)
		(drill 0.4064)
		(layers "F.Cu" "B.Cu")
		(net "GND")
	)
	(via
		(at 197.586346 -261.1247)
		(size 0.7112)
		(drill 0.4064)
		(layers "F.Cu" "B.Cu")
		(net "GND")
	)
	(via
		(at 165.607746 -182.4609)
		(size 0.7112)
		(drill 0.4064)
		(layers "F.Cu" "B.Cu")
		(net "GND")
	)
	(via
		(at 162.966146 -214.1855)
		(size 0.7112)
		(drill 0.4064)
		(layers "F.Cu" "B.Cu")
		(net "GND")
	)
	(via
		(at 75.005946 -475.0435)
		(size 0.7112)
		(drill 0.4064)
		(layers "F.Cu" "B.Cu")
		(net "GND")
	)
	(via
		(at 21.2598 -134.493)
		(size 0.5588)
		(drill 0.3048)
		(layers "F.Cu" "B.Cu")
		(net "GND")
	)
	(via
		(at 24.336756 -34.56051)
		(size 0.7112)
		(drill 0.4064)
		(layers "F.Cu" "B.Cu")
		(net "GND")
	)
	(via
		(at 31.114746 -423.8117)
		(size 0.7112)
		(drill 0.4064)
		(layers "F.Cu" "B.Cu")
		(net "GND")
	)
	(via
		(at 75.692 -188.849)
		(size 0.5588)
		(drill 0.3048)
		(layers "F.Cu" "B.Cu")
		(net "GND")
	)
	(via
		(at 57.149746 -155.8163)
		(size 0.7112)
		(drill 0.4064)
		(layers "F.Cu" "B.Cu")
		(net "GND")
	)
	(via
		(at 229.945946 -470.5731)
		(size 0.7112)
		(drill 0.4064)
		(layers "F.Cu" "B.Cu")
		(net "GND")
	)
	(via
		(at 247.903746 -323.8627)
		(size 0.7112)
		(drill 0.4064)
		(layers "F.Cu" "B.Cu")
		(net "GND")
	)
	(via
		(at 205.282546 -324.0659)
		(size 0.7112)
		(drill 0.4064)
		(layers "F.Cu" "B.Cu")
		(net "GND")
	)
	(via
		(at 31.3182 -65.024)
		(size 0.5588)
		(drill 0.3048)
		(layers "F.Cu" "B.Cu")
		(net "GND")
	)
	(via
		(at 145.668746 -263.2837)
		(size 0.7112)
		(drill 0.4064)
		(layers "F.Cu" "B.Cu")
		(net "GND")
	)
	(via
		(at 244.093746 -1.6637)
		(size 0.7112)
		(drill 0.4064)
		(layers "F.Cu" "B.Cu")
		(net "GND")
	)
	(via
		(at 221.487746 -381.11684)
		(size 0.5588)
		(drill 0.3048)
		(layers "F.Cu" "B.Cu")
		(net "GND")
	)
	(via
		(at 57.022746 -400.0627)
		(size 0.7112)
		(drill 0.4064)
		(layers "F.Cu" "B.Cu")
		(net "GND")
	)
	(via
		(at 32.029146 -100.6221)
		(size 0.7112)
		(drill 0.4064)
		(layers "F.Cu" "B.Cu")
		(net "GND")
	)
	(via
		(at 140.766546 -419.5953)
		(size 0.7112)
		(drill 0.4064)
		(layers "F.Cu" "B.Cu")
		(net "GND")
	)
	(via
		(at 110.363 -401.193)
		(size 0.7112)
		(drill 0.4064)
		(layers "F.Cu" "B.Cu")
		(net "GND")
	)
	(via
		(at 42.798746 -215.065102)
		(size 0.7112)
		(drill 0.4064)
		(layers "F.Cu" "B.Cu")
		(net "GND")
	)
	(via
		(at 64.947546 -437.5277)
		(size 0.7112)
		(drill 0.4064)
		(layers "F.Cu" "B.Cu")
		(net "GND")
	)
	(via
		(at 25.781 -136.271)
		(size 0.7112)
		(drill 0.4064)
		(layers "F.Cu" "B.Cu")
		(net "GND")
	)
	(via
		(at 112.674146 -240.1951)
		(size 0.7112)
		(drill 0.4064)
		(layers "F.Cu" "B.Cu")
		(net "GND")
	)
	(via
		(at 222.249746 -266.5857)
		(size 0.5588)
		(drill 0.3048)
		(layers "F.Cu" "B.Cu")
		(net "GND")
	)
	(via
		(at 83.337146 -238.0615)
		(size 0.7112)
		(drill 0.4064)
		(layers "F.Cu" "B.Cu")
		(net "GND")
	)
	(via
		(at 52.323746 -248.4755)
		(size 0.7112)
		(drill 0.4064)
		(layers "F.Cu" "B.Cu")
		(net "GND")
	)
	(via
		(at 170.789346 -383.2225)
		(size 0.7112)
		(drill 0.4064)
		(layers "F.Cu" "B.Cu")
		(net "GND")
	)
	(via
		(at 139.191746 -487.7689)
		(size 0.7112)
		(drill 0.4064)
		(layers "F.Cu" "B.Cu")
		(net "GND")
	)
	(via
		(at 99.821746 -85.6107)
		(size 0.7112)
		(drill 0.3556)
		(layers "F.Cu" "B.Cu")
		(net "GND")
	)
	(via
		(at 7.264146 -196.9643)
		(size 0.7112)
		(drill 0.4064)
		(layers "F.Cu" "B.Cu")
		(net "GND")
	)
	(via
		(at 5.1816 -266.2682)
		(size 0.5588)
		(drill 0.3048)
		(layers "F.Cu" "B.Cu")
		(net "GND")
	)
	(via
		(at 83.819746 -1.2827)
		(size 0.7112)
		(drill 0.4064)
		(layers "F.Cu" "B.Cu")
		(net "GND")
	)
	(via
		(at 166.242746 -343.9287)
		(size 0.7112)
		(drill 0.4064)
		(layers "F.Cu" "B.Cu")
		(net "GND")
	)
	(via
		(at 76.580746 -235.4707)
		(size 0.7112)
		(drill 0.3556)
		(layers "F.Cu" "B.Cu")
		(net "GND")
	)
	(via
		(at 246.125746 -175.3997)
		(size 0.7112)
		(drill 0.4064)
		(layers "F.Cu" "B.Cu")
		(net "GND")
	)
	(via
		(at 247.0658 -394.5382)
		(size 0.7112)
		(drill 0.4064)
		(layers "F.Cu" "B.Cu")
		(net "GND")
	)
	(via
		(at 133.603746 -316.3697)
		(size 0.7112)
		(drill 0.4064)
		(layers "F.Cu" "B.Cu")
		(net "GND")
	)
	(via
		(at 108.406946 -359.6767)
		(size 0.7112)
		(drill 0.4064)
		(layers "F.Cu" "B.Cu")
		(net "GND")
	)
	(via
		(at 10.007346 -195.2625)
		(size 0.7112)
		(drill 0.4064)
		(layers "F.Cu" "B.Cu")
		(net "GND")
	)
	(via
		(at 148.157946 -244.2083)
		(size 0.7112)
		(drill 0.4064)
		(layers "F.Cu" "B.Cu")
		(net "GND")
	)
	(via
		(at 7.543546 -98.674936)
		(size 0.5588)
		(drill 0.3048)
		(layers "F.Cu" "B.Cu")
		(net "GND")
	)
	(via
		(at 97.154746 -1.2827)
		(size 0.7112)
		(drill 0.4064)
		(layers "F.Cu" "B.Cu")
		(net "GND")
	)
	(via
		(at 7.2898 -114.7826)
		(size 0.5588)
		(drill 0.3048)
		(layers "F.Cu" "B.Cu")
		(net "GND")
	)
	(via
		(at 30.225746 -424.3197)
		(size 0.7112)
		(drill 0.4064)
		(layers "F.Cu" "B.Cu")
		(net "GND")
	)
	(via
		(at 234.594146 -415.1249)
		(size 0.7112)
		(drill 0.4064)
		(layers "F.Cu" "B.Cu")
		(net "GND")
	)
	(via
		(at 221.509844 -275.576792)
		(size 0.5588)
		(drill 0.3048)
		(layers "F.Cu" "B.Cu")
		(net "GND")
	)
	(via
		(at 198.043546 -474.4593)
		(size 0.7112)
		(drill 0.4064)
		(layers "F.Cu" "B.Cu")
		(net "GND")
	)
	(via
		(at 107.441746 -451.7517)
		(size 0.7112)
		(drill 0.4064)
		(layers "F.Cu" "B.Cu")
		(net "GND")
	)
	(via
		(at 7.873746 -365.2647)
		(size 0.5588)
		(drill 0.3048)
		(layers "F.Cu" "B.Cu")
		(net "GND")
	)
	(via
		(at 105.435146 -107.3277)
		(size 0.7112)
		(drill 0.4064)
		(layers "F.Cu" "B.Cu")
		(net "GND")
	)
	(via
		(at 180.847746 -82.5627)
		(size 0.7112)
		(drill 0.4064)
		(layers "F.Cu" "B.Cu")
		(net "GND")
	)
	(via
		(at 108.584746 -422.1607)
		(size 0.7112)
		(drill 0.4064)
		(layers "F.Cu" "B.Cu")
		(net "GND")
	)
	(via
		(at 66.725546 -52.9717)
		(size 0.7112)
		(drill 0.4064)
		(layers "F.Cu" "B.Cu")
		(net "GND")
	)
	(via
		(at 233.781346 -217.1319)
		(size 0.7112)
		(drill 0.4064)
		(layers "F.Cu" "B.Cu")
		(net "GND")
	)
	(via
		(at 165.734746 -408.8257)
		(size 0.7112)
		(drill 0.4064)
		(layers "F.Cu" "B.Cu")
		(net "GND")
	)
	(via
		(at 64.744346 -236.0295)
		(size 0.7112)
		(drill 0.4064)
		(layers "F.Cu" "B.Cu")
		(net "GND")
	)
	(via
		(at 259.740146 -336.0293)
		(size 0.7112)
		(drill 0.4064)
		(layers "F.Cu" "B.Cu")
		(net "GND")
	)
	(via
		(at 155.4226 -400.7866)
		(size 0.7112)
		(drill 0.4064)
		(layers "F.Cu" "B.Cu")
		(net "GND")
	)
	(via
		(at 90.931746 -456.1967)
		(size 0.7112)
		(drill 0.4064)
		(layers "F.Cu" "B.Cu")
		(net "GND")
	)
	(via
		(at 65.150746 -146.5707)
		(size 0.7112)
		(drill 0.4064)
		(layers "F.Cu" "B.Cu")
		(net "GND")
	)
	(via
		(at 48.767746 -56.2737)
		(size 0.7112)
		(drill 0.4064)
		(layers "F.Cu" "B.Cu")
		(net "GND")
	)
	(via
		(at 35.941 -435.737)
		(size 0.5588)
		(drill 0.3048)
		(layers "F.Cu" "B.Cu")
		(net "GND")
	)
	(via
		(at 5.943346 -162.978846)
		(size 0.5588)
		(drill 0.3048)
		(layers "F.Cu" "B.Cu")
		(net "GND")
	)
	(via
		(at 140.715746 -280.1747)
		(size 0.7112)
		(drill 0.4064)
		(layers "F.Cu" "B.Cu")
		(net "GND")
	)
	(via
		(at 230.225346 -74.9935)
		(size 0.7112)
		(drill 0.4064)
		(layers "F.Cu" "B.Cu")
		(net "GND")
	)
	(via
		(at 177.723546 -40.8305)
		(size 0.7112)
		(drill 0.4064)
		(layers "F.Cu" "B.Cu")
		(net "GND")
	)
	(via
		(at 35.873436 -261.59079)
		(size 0.7112)
		(drill 0.4064)
		(layers "F.Cu" "B.Cu")
		(net "GND")
	)
	(via
		(at 178.891946 -287.6931)
		(size 0.7112)
		(drill 0.4064)
		(layers "F.Cu" "B.Cu")
		(net "GND")
	)
	(via
		(at 228.727 -437.261)
		(size 0.5588)
		(drill 0.3048)
		(layers "F.Cu" "B.Cu")
		(net "GND")
	)
	(via
		(at 83.718146 -264.3505)
		(size 0.7112)
		(drill 0.4064)
		(layers "F.Cu" "B.Cu")
		(net "GND")
	)
	(via
		(at 206.374746 -504.7107)
		(size 0.7112)
		(drill 0.4064)
		(layers "F.Cu" "B.Cu")
		(net "GND")
	)
	(via
		(at 239.572546 -389.0391)
		(size 0.7112)
		(drill 0.4064)
		(layers "F.Cu" "B.Cu")
		(net "GND")
	)
	(via
		(at 32.639 -504.825)
		(size 0.7112)
		(drill 0.4064)
		(layers "F.Cu" "B.Cu")
		(net "GND")
	)
	(via
		(at 216.026746 -396.7607)
		(size 0.7112)
		(drill 0.4064)
		(layers "F.Cu" "B.Cu")
		(net "GND")
	)
	(via
		(at 139.191746 -188.7347)
		(size 0.7112)
		(drill 0.4064)
		(layers "F.Cu" "B.Cu")
		(net "GND")
	)
	(via
		(at 55.016654 -427.8249)
		(size 0.7112)
		(drill 0.4064)
		(layers "F.Cu" "B.Cu")
		(net "GND")
	)
	(via
		(at 163.194746 -133.5405)
		(size 0.7112)
		(drill 0.4064)
		(layers "F.Cu" "B.Cu")
		(net "GND")
	)
	(via
		(at 59.791346 -66.8909)
		(size 0.7112)
		(drill 0.4064)
		(layers "F.Cu" "B.Cu")
		(net "GND")
	)
	(via
		(at 161.417 -407.3906)
		(size 0.7112)
		(drill 0.4064)
		(layers "F.Cu" "B.Cu")
		(net "GND")
	)
	(via
		(at 73.939146 -433.6923)
		(size 0.7112)
		(drill 0.4064)
		(layers "F.Cu" "B.Cu")
		(net "GND")
	)
	(via
		(at 192.226946 -312.9661)
		(size 0.7112)
		(drill 0.4064)
		(layers "F.Cu" "B.Cu")
		(net "GND")
	)
	(via
		(at 139.547346 -330.9239)
		(size 0.7112)
		(drill 0.4064)
		(layers "F.Cu" "B.Cu")
		(net "GND")
	)
	(via
		(at 179.450746 -239.4077)
		(size 0.7112)
		(drill 0.4064)
		(layers "F.Cu" "B.Cu")
		(net "GND")
	)
	(via
		(at 154.304746 -188.2267)
		(size 0.7112)
		(drill 0.4064)
		(layers "F.Cu" "B.Cu")
		(net "GND")
	)
	(via
		(at 64.515746 -425.8437)
		(size 0.7112)
		(drill 0.4064)
		(layers "F.Cu" "B.Cu")
		(net "GND")
	)
	(via
		(at 67.614546 -119.9769)
		(size 0.7112)
		(drill 0.4064)
		(layers "F.Cu" "B.Cu")
		(net "GND")
	)
	(via
		(at 56.286146 -314.2615)
		(size 0.7112)
		(drill 0.4064)
		(layers "F.Cu" "B.Cu")
		(net "GND")
	)
	(via
		(at 165.506146 -305.5747)
		(size 0.7112)
		(drill 0.4064)
		(layers "F.Cu" "B.Cu")
		(net "GND")
	)
	(via
		(at 109.346746 -55.1307)
		(size 0.7112)
		(drill 0.4064)
		(layers "F.Cu" "B.Cu")
		(net "GND")
	)
	(via
		(at 249.199146 -31.3563)
		(size 0.7112)
		(drill 0.4064)
		(layers "F.Cu" "B.Cu")
		(net "GND")
	)
	(via
		(at 162.432746 -246.6721)
		(size 0.7112)
		(drill 0.4064)
		(layers "F.Cu" "B.Cu")
		(net "GND")
	)
	(via
		(at 85.546946 -479.7933)
		(size 0.7112)
		(drill 0.4064)
		(layers "F.Cu" "B.Cu")
		(net "GND")
	)
	(via
		(at 135.381746 -431.9397)
		(size 0.7112)
		(drill 0.4064)
		(layers "F.Cu" "B.Cu")
		(net "GND")
	)
	(via
		(at 70.738746 -411.8737)
		(size 0.7112)
		(drill 0.4064)
		(layers "F.Cu" "B.Cu")
		(net "GND")
	)
	(via
		(at 146.430746 -487.4387)
		(size 0.7112)
		(drill 0.4064)
		(layers "F.Cu" "B.Cu")
		(net "GND")
	)
	(via
		(at 68.732146 -444.2333)
		(size 0.7112)
		(drill 0.4064)
		(layers "F.Cu" "B.Cu")
		(net "GND")
	)
	(via
		(at 247.776746 -292.7477)
		(size 0.7112)
		(drill 0.4064)
		(layers "F.Cu" "B.Cu")
		(net "GND")
	)
	(via
		(at 151.891746 -175.2727)
		(size 0.7112)
		(drill 0.4064)
		(layers "F.Cu" "B.Cu")
		(net "GND")
	)
	(via
		(at 236.981746 -71.8947)
		(size 0.7112)
		(drill 0.4064)
		(layers "F.Cu" "B.Cu")
		(net "GND")
	)
	(via
		(at 251.56795 -415.010092)
		(size 0.5588)
		(drill 0.3048)
		(layers "F.Cu" "B.Cu")
		(net "GND")
	)
	(via
		(at 184.276746 -15.7607)
		(size 0.7112)
		(drill 0.4064)
		(layers "F.Cu" "B.Cu")
		(net "GND")
	)
	(via
		(at 129.0828 -446.5828)
		(size 0.7112)
		(drill 0.4064)
		(layers "F.Cu" "B.Cu")
		(net "GND")
	)
	(via
		(at 241.629946 -142.2781)
		(size 0.7112)
		(drill 0.4064)
		(layers "F.Cu" "B.Cu")
		(net "GND")
	)
	(via
		(at 7.493 -117.0432)
		(size 0.5588)
		(drill 0.3048)
		(layers "F.Cu" "B.Cu")
		(net "GND")
	)
	(via
		(at 5.804154 -349.038926)
		(size 0.5588)
		(drill 0.3048)
		(layers "F.Cu" "B.Cu")
		(net "GND")
	)
	(via
		(at 163.931346 -484.1621)
		(size 0.7112)
		(drill 0.4064)
		(layers "F.Cu" "B.Cu")
		(net "GND")
	)
	(via
		(at 17.2212 -119.3546)
		(size 0.5588)
		(drill 0.3048)
		(layers "F.Cu" "B.Cu")
		(net "GND")
	)
	(via
		(at 12.58697 -143.1417)
		(size 0.7112)
		(drill 0.4064)
		(layers "F.Cu" "B.Cu")
		(net "GND")
	)
	(via
		(at 69.849746 -257.0607)
		(size 0.7112)
		(drill 0.4064)
		(layers "F.Cu" "B.Cu")
		(net "GND")
	)
	(via
		(at 91.287346 -78.0415)
		(size 0.7112)
		(drill 0.4064)
		(layers "F.Cu" "B.Cu")
		(net "GND")
	)
	(via
		(at 176.859946 -188.4299)
		(size 0.7112)
		(drill 0.4064)
		(layers "F.Cu" "B.Cu")
		(net "GND")
	)
	(via
		(at 191.769746 -360.6927)
		(size 0.7112)
		(drill 0.4064)
		(layers "F.Cu" "B.Cu")
		(net "GND")
	)
	(via
		(at 159.257746 -457.2127)
		(size 0.7112)
		(drill 0.4064)
		(layers "F.Cu" "B.Cu")
		(net "GND")
	)
	(via
		(at 172.287946 -253.3269)
		(size 0.7112)
		(drill 0.4064)
		(layers "F.Cu" "B.Cu")
		(net "GND")
	)
	(via
		(at 162.712146 -153.5811)
		(size 0.7112)
		(drill 0.4064)
		(layers "F.Cu" "B.Cu")
		(net "GND")
	)
	(via
		(at 138.963146 -312.6105)
		(size 0.7112)
		(drill 0.4064)
		(layers "F.Cu" "B.Cu")
		(net "GND")
	)
	(via
		(at 72.516746 -442.6077)
		(size 0.7112)
		(drill 0.4064)
		(layers "F.Cu" "B.Cu")
		(net "GND")
	)
	(via
		(at 124.840746 -128.0287)
		(size 0.7112)
		(drill 0.4064)
		(layers "F.Cu" "B.Cu")
		(net "GND")
	)
	(via
		(at 131.698746 -342.1253)
		(size 0.7112)
		(drill 0.4064)
		(layers "F.Cu" "B.Cu")
		(net "GND")
	)
	(via
		(at 232.079546 -127.9271)
		(size 0.7112)
		(drill 0.4064)
		(layers "F.Cu" "B.Cu")
		(net "GND")
	)
	(via
		(at 190.880746 -217.3097)
		(size 0.7112)
		(drill 0.4064)
		(layers "F.Cu" "B.Cu")
		(net "GND")
	)
	(via
		(at 251.1552 -421.2082)
		(size 0.5588)
		(drill 0.3048)
		(layers "F.Cu" "B.Cu")
		(net "GND")
	)
	(via
		(at 259.206746 -86.7537)
		(size 0.7112)
		(drill 0.4064)
		(layers "F.Cu" "B.Cu")
		(net "GND")
	)
	(via
		(at 42.544746 -284.1117)
		(size 0.7112)
		(drill 0.4064)
		(layers "F.Cu" "B.Cu")
		(net "GND")
	)
	(via
		(at 186.943746 -306.3367)
		(size 0.7112)
		(drill 0.4064)
		(layers "F.Cu" "B.Cu")
		(net "GND")
	)
	(via
		(at 129.539746 -162.6997)
		(size 0.7112)
		(drill 0.4064)
		(layers "F.Cu" "B.Cu")
		(net "GND")
	)
	(via
		(at 58.191146 -40.9829)
		(size 0.7112)
		(drill 0.4064)
		(layers "F.Cu" "B.Cu")
		(net "GND")
	)
	(via
		(at 195.376546 -477.3295)
		(size 0.7112)
		(drill 0.4064)
		(layers "F.Cu" "B.Cu")
		(net "GND")
	)
	(via
		(at 72.262746 -105.4227)
		(size 0.7112)
		(drill 0.4064)
		(layers "F.Cu" "B.Cu")
		(net "GND")
	)
	(via
		(at 65.7098 -417.8554)
		(size 0.7112)
		(drill 0.4064)
		(layers "F.Cu" "B.Cu")
		(net "GND")
	)
	(via
		(at 114.934746 -151.6507)
		(size 0.7112)
		(drill 0.4064)
		(layers "F.Cu" "B.Cu")
		(net "GND")
	)
	(via
		(at 252.729746 -189.8777)
		(size 0.7112)
		(drill 0.4064)
		(layers "F.Cu" "B.Cu")
		(net "GND")
	)
	(via
		(at 137.108946 -118.3767)
		(size 0.7112)
		(drill 0.4064)
		(layers "F.Cu" "B.Cu")
		(net "GND")
	)
	(via
		(at 149.478746 -31.8897)
		(size 0.7112)
		(drill 0.4064)
		(layers "F.Cu" "B.Cu")
		(net "GND")
	)
	(via
		(at 2.285746 -225.9457)
		(size 0.7112)
		(drill 0.4064)
		(layers "F.Cu" "B.Cu")
		(net "GND")
	)
	(via
		(at 53.848 -432.1302)
		(size 0.7112)
		(drill 0.4064)
		(layers "F.Cu" "B.Cu")
		(net "GND")
	)
	(via
		(at 163.194746 -504.7107)
		(size 0.7112)
		(drill 0.4064)
		(layers "F.Cu" "B.Cu")
		(net "GND")
	)
	(via
		(at 23.088346 -78.6257)
		(size 0.7112)
		(drill 0.4064)
		(layers "F.Cu" "B.Cu")
		(net "GND")
	)
	(via
		(at 74.421746 -1.1557)
		(size 0.7112)
		(drill 0.4064)
		(layers "F.Cu" "B.Cu")
		(net "GND")
	)
	(via
		(at 71.627746 -126.3777)
		(size 0.7112)
		(drill 0.4064)
		(layers "F.Cu" "B.Cu")
		(net "GND")
	)
	(via
		(at 63.7286 -317.119)
		(size 0.7112)
		(drill 0.4064)
		(layers "F.Cu" "B.Cu")
		(net "GND")
	)
	(via
		(at 80.060546 -235.1913)
		(size 0.7112)
		(drill 0.4064)
		(layers "F.Cu" "B.Cu")
		(net "GND")
	)
	(via
		(at 150.494746 -116.5987)
		(size 0.7112)
		(drill 0.4064)
		(layers "F.Cu" "B.Cu")
		(net "GND")
	)
	(via
		(at 151.790146 -303.7967)
		(size 0.7112)
		(drill 0.4064)
		(layers "F.Cu" "B.Cu")
		(net "GND")
	)
	(via
		(at 159.003746 -148.6027)
		(size 0.7112)
		(drill 0.4064)
		(layers "F.Cu" "B.Cu")
		(net "GND")
	)
	(via
		(at 246.506746 -212.2805)
		(size 0.7112)
		(drill 0.4064)
		(layers "F.Cu" "B.Cu")
		(net "GND")
	)
	(via
		(at 65.785746 -100.7491)
		(size 0.7112)
		(drill 0.4064)
		(layers "F.Cu" "B.Cu")
		(net "GND")
	)
	(via
		(at 185.292746 -55.5117)
		(size 0.7112)
		(drill 0.4064)
		(layers "F.Cu" "B.Cu")
		(net "GND")
	)
	(via
		(at 144.271746 -308.7497)
		(size 0.7112)
		(drill 0.4064)
		(layers "F.Cu" "B.Cu")
		(net "GND")
	)
	(via
		(at 179.806346 -341.9475)
		(size 0.7112)
		(drill 0.4064)
		(layers "F.Cu" "B.Cu")
		(net "GND")
	)
	(via
		(at 210.108546 -412.1785)
		(size 0.7112)
		(drill 0.4064)
		(layers "F.Cu" "B.Cu")
		(net "GND")
	)
	(via
		(at 157.860746 -194.8561)
		(size 0.7112)
		(drill 0.4064)
		(layers "F.Cu" "B.Cu")
		(net "GND")
	)
	(via
		(at 90.805762 -19.568922)
		(size 0.5588)
		(drill 0.3048)
		(layers "F.Cu" "B.Cu")
		(net "GND")
	)
	(via
		(at 83.641946 -279.0317)
		(size 0.7112)
		(drill 0.4064)
		(layers "F.Cu" "B.Cu")
		(net "GND")
	)
	(via
		(at 181.025546 -110.3503)
		(size 0.7112)
		(drill 0.4064)
		(layers "F.Cu" "B.Cu")
		(net "GND")
	)
	(via
		(at 251.459746 -436.3847)
		(size 0.7112)
		(drill 0.4064)
		(layers "F.Cu" "B.Cu")
		(net "GND")
	)
	(via
		(at 66.877946 -243.6749)
		(size 0.7112)
		(drill 0.4064)
		(layers "F.Cu" "B.Cu")
		(net "GND")
	)
	(via
		(at 6.824726 -156.682694)
		(size 0.5588)
		(drill 0.3048)
		(layers "F.Cu" "B.Cu")
		(net "GND")
	)
	(via
		(at 5.765546 -146.7993)
		(size 0.5588)
		(drill 0.3048)
		(layers "F.Cu" "B.Cu")
		(net "GND")
	)
	(via
		(at 82.676746 -63.3603)
		(size 0.7112)
		(drill 0.4064)
		(layers "F.Cu" "B.Cu")
		(net "GND")
	)
	(via
		(at 137.667746 -11.8237)
		(size 0.7112)
		(drill 0.4064)
		(layers "F.Cu" "B.Cu")
		(net "GND")
	)
	(via
		(at 212.470746 -1.6637)
		(size 0.7112)
		(drill 0.4064)
		(layers "F.Cu" "B.Cu")
		(net "GND")
	)
	(via
		(at 200.532746 -279.2857)
		(size 0.7112)
		(drill 0.4064)
		(layers "F.Cu" "B.Cu")
		(net "GND")
	)
	(via
		(at 128.828546 -310.9849)
		(size 0.7112)
		(drill 0.4064)
		(layers "F.Cu" "B.Cu")
		(net "GND")
	)
	(via
		(at 73.837546 -285.1531)
		(size 0.7112)
		(drill 0.4064)
		(layers "F.Cu" "B.Cu")
		(net "GND")
	)
	(via
		(at 96.545146 -434.2511)
		(size 0.7112)
		(drill 0.4064)
		(layers "F.Cu" "B.Cu")
		(net "GND")
	)
	(via
		(at 123.19 -94.7928)
		(size 0.7112)
		(drill 0.4064)
		(layers "F.Cu" "B.Cu")
		(net "GND")
	)
	(via
		(at 33.02 -114.808)
		(size 0.7112)
		(drill 0.4064)
		(layers "F.Cu" "B.Cu")
		(net "GND")
	)
	(via
		(at 64.744346 -327.6473)
		(size 0.7112)
		(drill 0.4064)
		(layers "F.Cu" "B.Cu")
		(net "GND")
	)
	(via
		(at 245.744746 -14.2367)
		(size 0.7112)
		(drill 0.4064)
		(layers "F.Cu" "B.Cu")
		(net "GND")
	)
	(via
		(at 108.711746 -147.3327)
		(size 0.7112)
		(drill 0.4064)
		(layers "F.Cu" "B.Cu")
		(net "GND")
	)
	(via
		(at 61.467746 -1.2827)
		(size 0.7112)
		(drill 0.4064)
		(layers "F.Cu" "B.Cu")
		(net "GND")
	)
	(via
		(at 229.996746 -117.3607)
		(size 0.7112)
		(drill 0.4064)
		(layers "F.Cu" "B.Cu")
		(net "GND")
	)
	(via
		(at 113.918746 -1.5367)
		(size 0.7112)
		(drill 0.4064)
		(layers "F.Cu" "B.Cu")
		(net "GND")
	)
	(via
		(at 232.536746 -482.3587)
		(size 0.7112)
		(drill 0.4064)
		(layers "F.Cu" "B.Cu")
		(net "GND")
	)
	(via
		(at 1.828546 -439.7883)
		(size 0.7112)
		(drill 0.4064)
		(layers "F.Cu" "B.Cu")
		(net "GND")
	)
	(via
		(at 160.476946 -335.9531)
		(size 0.7112)
		(drill 0.4064)
		(layers "F.Cu" "B.Cu")
		(net "GND")
	)
	(via
		(at 91.439746 -481.9777)
		(size 0.7112)
		(drill 0.4064)
		(layers "F.Cu" "B.Cu")
		(net "GND")
	)
	(via
		(at 55.244746 -253.6317)
		(size 0.7112)
		(drill 0.4064)
		(layers "F.Cu" "B.Cu")
		(net "GND")
	)
	(via
		(at 87.401146 -360.9721)
		(size 0.7112)
		(drill 0.4064)
		(layers "F.Cu" "B.Cu")
		(net "GND")
	)
	(via
		(at 245.744746 -11.9507)
		(size 0.7112)
		(drill 0.4064)
		(layers "F.Cu" "B.Cu")
		(net "GND")
	)
	(via
		(at 221.487746 -72.116696)
		(size 0.5588)
		(drill 0.3048)
		(layers "F.Cu" "B.Cu")
		(net "GND")
	)
	(via
		(at 128.676146 -305.3969)
		(size 0.7112)
		(drill 0.4064)
		(layers "F.Cu" "B.Cu")
		(net "GND")
	)
	(via
		(at 239.140746 -1.6637)
		(size 0.7112)
		(drill 0.4064)
		(layers "F.Cu" "B.Cu")
		(net "GND")
	)
	(via
		(at 149.351746 -36.8427)
		(size 0.7112)
		(drill 0.4064)
		(layers "F.Cu" "B.Cu")
		(net "GND")
	)
	(via
		(at 7.2644 -129.159)
		(size 0.5588)
		(drill 0.3048)
		(layers "F.Cu" "B.Cu")
		(net "GND")
	)
	(via
		(at 160.629346 -91.1225)
		(size 0.7112)
		(drill 0.4064)
		(layers "F.Cu" "B.Cu")
		(net "GND")
	)
	(via
		(at 194.4624 -446.2272)
		(size 0.7112)
		(drill 0.4064)
		(layers "F.Cu" "B.Cu")
		(net "GND")
	)
	(via
		(at 181.863746 -442.9887)
		(size 0.7112)
		(drill 0.4064)
		(layers "F.Cu" "B.Cu")
		(net "GND")
	)
	(via
		(at 9.830562 -494.475516)
		(size 0.5588)
		(drill 0.3048)
		(layers "F.Cu" "B.Cu")
		(net "GND")
	)
	(via
		(at 185.140346 -51.9557)
		(size 0.7112)
		(drill 0.4064)
		(layers "F.Cu" "B.Cu")
		(net "GND")
	)
	(via
		(at 233.425746 -162.9537)
		(size 0.7112)
		(drill 0.4064)
		(layers "F.Cu" "B.Cu")
		(net "GND")
	)
	(via
		(at 59.816746 -431.0507)
		(size 0.7112)
		(drill 0.4064)
		(layers "F.Cu" "B.Cu")
		(net "GND")
	)
	(via
		(at 246.252746 -202.1205)
		(size 0.7112)
		(drill 0.4064)
		(layers "F.Cu" "B.Cu")
		(net "GND")
	)
	(via
		(at 3.936746 -91.4527)
		(size 0.7112)
		(drill 0.4064)
		(layers "F.Cu" "B.Cu")
		(net "GND")
	)
	(via
		(at 241.375946 -155.9941)
		(size 0.7112)
		(drill 0.4064)
		(layers "F.Cu" "B.Cu")
		(net "GND")
	)
	(via
		(at 20.2946 -200.9902)
		(size 0.7112)
		(drill 0.4064)
		(layers "F.Cu" "B.Cu")
		(net "GND")
	)
	(via
		(at 32.486092 -371.460014)
		(size 0.5588)
		(drill 0.3048)
		(layers "F.Cu" "B.Cu")
		(net "GND")
	)
	(via
		(at 33.782 -61.087)
		(size 0.7112)
		(drill 0.4064)
		(layers "F.Cu" "B.Cu")
		(net "GND")
	)
	(via
		(at 233.298746 -180.8607)
		(size 0.7112)
		(drill 0.4064)
		(layers "F.Cu" "B.Cu")
		(net "GND")
	)
	(via
		(at 136.981946 -123.3297)
		(size 0.7112)
		(drill 0.4064)
		(layers "F.Cu" "B.Cu")
		(net "GND")
	)
	(via
		(at 75.615546 -173.1899)
		(size 0.7112)
		(drill 0.4064)
		(layers "F.Cu" "B.Cu")
		(net "GND")
	)
	(via
		(at 10.413746 -6.9977)
		(size 0.7112)
		(drill 0.4064)
		(layers "F.Cu" "B.Cu")
		(net "GND")
	)
	(via
		(at 251.967746 -14.2367)
		(size 0.7112)
		(drill 0.4064)
		(layers "F.Cu" "B.Cu")
		(net "GND")
	)
	(via
		(at 64.490346 -460.5655)
		(size 0.7112)
		(drill 0.4064)
		(layers "F.Cu" "B.Cu")
		(net "GND")
	)
	(via
		(at 221.995746 -214.6427)
		(size 0.7112)
		(drill 0.4064)
		(layers "F.Cu" "B.Cu")
		(net "GND")
	)
	(via
		(at 16.712946 -252.4887)
		(size 0.7112)
		(drill 0.4064)
		(layers "F.Cu" "B.Cu")
		(net "GND")
	)
	(via
		(at 55.9054 -429.6918)
		(size 0.7112)
		(drill 0.4064)
		(layers "F.Cu" "B.Cu")
		(net "GND")
	)
	(via
		(at 239.775746 -199.9107)
		(size 0.7112)
		(drill 0.4064)
		(layers "F.Cu" "B.Cu")
		(net "GND")
	)
	(via
		(at 246.9896 -404.368)
		(size 0.7112)
		(drill 0.4064)
		(layers "F.Cu" "B.Cu")
		(net "GND")
	)
	(via
		(at 239.648746 -238.0107)
		(size 0.7112)
		(drill 0.4064)
		(layers "F.Cu" "B.Cu")
		(net "GND")
	)
	(via
		(at 52.450746 -158.3817)
		(size 0.7112)
		(drill 0.4064)
		(layers "F.Cu" "B.Cu")
		(net "GND")
	)
	(via
		(at 50.526696 -247.89765)
		(size 0.5588)
		(drill 0.3048)
		(layers "F.Cu" "B.Cu")
		(net "GND")
	)
	(via
		(at 20.827746 -169.6847)
		(size 0.5588)
		(drill 0.3048)
		(layers "F.Cu" "B.Cu")
		(net "GND")
	)
	(via
		(at 131.927346 -483.8065)
		(size 0.7112)
		(drill 0.4064)
		(layers "F.Cu" "B.Cu")
		(net "GND")
	)
	(via
		(at 19.557746 -385.8387)
		(size 0.7112)
		(drill 0.4064)
		(layers "F.Cu" "B.Cu")
		(net "GND")
	)
	(via
		(at 7.911846 -398.3482)
		(size 0.5588)
		(drill 0.3048)
		(layers "F.Cu" "B.Cu")
		(net "GND")
	)
	(via
		(at 84.581746 -289.1917)
		(size 0.7112)
		(drill 0.4064)
		(layers "F.Cu" "B.Cu")
		(net "GND")
	)
	(via
		(at 26.543 -460.6036)
		(size 0.7112)
		(drill 0.4064)
		(layers "F.Cu" "B.Cu")
		(net "GND")
	)
	(via
		(at 242.518946 -110.2741)
		(size 0.7112)
		(drill 0.4064)
		(layers "F.Cu" "B.Cu")
		(net "GND")
	)
	(via
		(at 56.921146 -195.6435)
		(size 0.7112)
		(drill 0.4064)
		(layers "F.Cu" "B.Cu")
		(net "GND")
	)
	(via
		(at 153.923746 -504.7107)
		(size 0.7112)
		(drill 0.4064)
		(layers "F.Cu" "B.Cu")
		(net "GND")
	)
	(via
		(at 200.329546 -477.2025)
		(size 0.7112)
		(drill 0.4064)
		(layers "F.Cu" "B.Cu")
		(net "GND")
	)
	(via
		(at 135.508746 -55.2577)
		(size 0.7112)
		(drill 0.4064)
		(layers "F.Cu" "B.Cu")
		(net "GND")
	)
	(via
		(at 259.9182 -341.4776)
		(size 0.7112)
		(drill 0.4064)
		(layers "F.Cu" "B.Cu")
		(net "GND")
	)
	(via
		(at 237.108746 -77.2287)
		(size 0.7112)
		(drill 0.4064)
		(layers "F.Cu" "B.Cu")
		(net "GND")
	)
	(via
		(at 1.904746 -325.6407)
		(size 0.7112)
		(drill 0.4064)
		(layers "F.Cu" "B.Cu")
		(net "GND")
	)
	(via
		(at 212.471 -69.8373)
		(size 0.5588)
		(drill 0.3048)
		(layers "F.Cu" "B.Cu")
		(net "GND")
	)
	(via
		(at 190.499746 -245.2497)
		(size 0.7112)
		(drill 0.4064)
		(layers "F.Cu" "B.Cu")
		(net "GND")
	)
	(via
		(at 9.144 -1.423416)
		(size 0.7112)
		(drill 0.4064)
		(layers "F.Cu" "B.Cu")
		(net "GND")
	)
	(via
		(at 187.705746 -123.9647)
		(size 0.7112)
		(drill 0.4064)
		(layers "F.Cu" "B.Cu")
		(net "GND")
	)
	(via
		(at 23.113746 -413.6517)
		(size 0.7112)
		(drill 0.4064)
		(layers "F.Cu" "B.Cu")
		(net "GND")
	)
	(via
		(at 239.140746 -426.6057)
		(size 0.7112)
		(drill 0.4064)
		(layers "F.Cu" "B.Cu")
		(net "GND")
	)
	(via
		(at 27.813 -228.8794)
		(size 0.7112)
		(drill 0.4064)
		(layers "F.Cu" "B.Cu")
		(net "GND")
	)
	(via
		(at 191.503046 -456.741276)
		(size 0.7112)
		(drill 0.4064)
		(layers "F.Cu" "B.Cu")
		(net "GND")
	)
	(via
		(at 94.869 -276.733)
		(size 0.7112)
		(drill 0.4064)
		(layers "F.Cu" "B.Cu")
		(net "GND")
	)
	(via
		(at 69.875146 -260.2865)
		(size 0.7112)
		(drill 0.4064)
		(layers "F.Cu" "B.Cu")
		(net "GND")
	)
	(via
		(at 114.579146 -180.7591)
		(size 0.7112)
		(drill 0.4064)
		(layers "F.Cu" "B.Cu")
		(net "GND")
	)
	(via
		(at 217.372946 -421.1955)
		(size 0.7112)
		(drill 0.4064)
		(layers "F.Cu" "B.Cu")
		(net "GND")
	)
	(via
		(at 141.223746 -104.7877)
		(size 0.7112)
		(drill 0.4064)
		(layers "F.Cu" "B.Cu")
		(net "GND")
	)
	(via
		(at 153.745946 -501.8405)
		(size 0.7112)
		(drill 0.4064)
		(layers "F.Cu" "B.Cu")
		(net "GND")
	)
	(via
		(at 62.229746 -146.5707)
		(size 0.7112)
		(drill 0.4064)
		(layers "F.Cu" "B.Cu")
		(net "GND")
	)
	(via
		(at 117.855746 -72.0217)
		(size 0.7112)
		(drill 0.4064)
		(layers "F.Cu" "B.Cu")
		(net "GND")
	)
	(via
		(at 236.270546 -502.8057)
		(size 0.7112)
		(drill 0.4064)
		(layers "F.Cu" "B.Cu")
		(net "GND")
	)
	(via
		(at 154.558746 -1.6637)
		(size 0.7112)
		(drill 0.4064)
		(layers "F.Cu" "B.Cu")
		(net "GND")
	)
	(via
		(at 243.280946 -418.3253)
		(size 0.7112)
		(drill 0.4064)
		(layers "F.Cu" "B.Cu")
		(net "GND")
	)
	(via
		(at 5.003292 -42.164)
		(size 0.7112)
		(drill 0.4064)
		(layers "F.Cu" "B.Cu")
		(net "GND")
	)
	(via
		(at 98.450146 -55.9181)
		(size 0.7112)
		(drill 0.4064)
		(layers "F.Cu" "B.Cu")
		(net "GND")
	)
	(via
		(at 258.317746 -322.9737)
		(size 0.7112)
		(drill 0.4064)
		(layers "F.Cu" "B.Cu")
		(net "GND")
	)
	(via
		(at 70.560946 -86.004146)
		(size 0.7112)
		(drill 0.4064)
		(layers "F.Cu" "B.Cu")
		(net "GND")
	)
	(via
		(at 175.488346 -471.3859)
		(size 0.7112)
		(drill 0.4064)
		(layers "F.Cu" "B.Cu")
		(net "GND")
	)
	(via
		(at 73.177146 -246.6975)
		(size 0.7112)
		(drill 0.4064)
		(layers "F.Cu" "B.Cu")
		(net "GND")
	)
	(via
		(at 45.719746 -420.595298)
		(size 0.5588)
		(drill 0.3048)
		(layers "F.Cu" "B.Cu")
		(net "GND")
	)
	(via
		(at 88.315546 -68.3387)
		(size 0.7112)
		(drill 0.4064)
		(layers "F.Cu" "B.Cu")
		(net "GND")
	)
	(via
		(at 106.044746 -23.7617)
		(size 0.7112)
		(drill 0.4064)
		(layers "F.Cu" "B.Cu")
		(net "GND")
	)
	(via
		(at 62.611 -168.4782)
		(size 0.7112)
		(drill 0.4064)
		(layers "F.Cu" "B.Cu")
		(net "GND")
	)
	(via
		(at 110.870746 -7.9629)
		(size 0.7112)
		(drill 0.4064)
		(layers "F.Cu" "B.Cu")
		(net "GND")
	)
	(via
		(at 6.178042 -396.2273)
		(size 0.5588)
		(drill 0.3048)
		(layers "F.Cu" "B.Cu")
		(net "GND")
	)
	(via
		(at 53.49367 -17.955768)
		(size 0.5588)
		(drill 0.3048)
		(layers "F.Cu" "B.Cu")
		(net "GND")
	)
	(via
		(at 3.936746 -83.3247)
		(size 0.7112)
		(drill 0.4064)
		(layers "F.Cu" "B.Cu")
		(net "GND")
	)
	(via
		(at 111.632746 -283.3497)
		(size 0.7112)
		(drill 0.4064)
		(layers "F.Cu" "B.Cu")
		(net "GND")
	)
	(via
		(at 123.342146 -430.4919)
		(size 0.7112)
		(drill 0.4064)
		(layers "F.Cu" "B.Cu")
		(net "GND")
	)
	(via
		(at 125.983746 -72.0217)
		(size 0.7112)
		(drill 0.4064)
		(layers "F.Cu" "B.Cu")
		(net "GND")
	)
	(via
		(at 81.787746 -135.4201)
		(size 0.7112)
		(drill 0.4064)
		(layers "F.Cu" "B.Cu")
		(net "GND")
	)
	(via
		(at 90.093546 -108.3691)
		(size 0.7112)
		(drill 0.4064)
		(layers "F.Cu" "B.Cu")
		(net "GND")
	)
	(via
		(at 53.949346 -479.0059)
		(size 0.7112)
		(drill 0.4064)
		(layers "F.Cu" "B.Cu")
		(net "GND")
	)
	(via
		(at 57.149492 -90.690446)
		(size 0.5588)
		(drill 0.3048)
		(layers "F.Cu" "B.Cu")
		(net "GND")
	)
	(via
		(at 141.071346 -429.0949)
		(size 0.7112)
		(drill 0.4064)
		(layers "F.Cu" "B.Cu")
		(net "GND")
	)
	(via
		(at 53.527452 -19.928586)
		(size 0.5588)
		(drill 0.3048)
		(layers "F.Cu" "B.Cu")
		(net "GND")
	)
	(via
		(at 8.4074 -418.719)
		(size 0.5588)
		(drill 0.3048)
		(layers "F.Cu" "B.Cu")
		(net "GND")
	)
	(via
		(at 49.3268 -370.3066)
		(size 0.7112)
		(drill 0.4064)
		(layers "F.Cu" "B.Cu")
		(net "GND")
	)
	(via
		(at 195.681346 -431.7111)
		(size 0.7112)
		(drill 0.4064)
		(layers "F.Cu" "B.Cu")
		(net "GND")
	)
	(via
		(at 166.903146 -323.3039)
		(size 0.7112)
		(drill 0.4064)
		(layers "F.Cu" "B.Cu")
		(net "GND")
	)
	(via
		(at 39.750746 -214.8967)
		(size 0.7112)
		(drill 0.4064)
		(layers "F.Cu" "B.Cu")
		(net "GND")
	)
	(via
		(at 160.527746 -162.4711)
		(size 0.7112)
		(drill 0.4064)
		(layers "F.Cu" "B.Cu")
		(net "GND")
	)
	(via
		(at 158.190946 -501.9675)
		(size 0.7112)
		(drill 0.4064)
		(layers "F.Cu" "B.Cu")
		(net "GND")
	)
	(via
		(at 131.190746 -243.0907)
		(size 0.7112)
		(drill 0.4064)
		(layers "F.Cu" "B.Cu")
		(net "GND")
	)
	(via
		(at 148.005546 -313.2455)
		(size 0.7112)
		(drill 0.4064)
		(layers "F.Cu" "B.Cu")
		(net "GND")
	)
	(via
		(at 251.206 -422.605708)
		(size 0.5588)
		(drill 0.3048)
		(layers "F.Cu" "B.Cu")
		(net "GND")
	)
	(via
		(at 165.201346 -449.8975)
		(size 0.7112)
		(drill 0.4064)
		(layers "F.Cu" "B.Cu")
		(net "GND")
	)
	(via
		(at 246.760746 -271.0307)
		(size 0.7112)
		(drill 0.4064)
		(layers "F.Cu" "B.Cu")
		(net "GND")
	)
	(via
		(at 141.858746 -142.8877)
		(size 0.7112)
		(drill 0.4064)
		(layers "F.Cu" "B.Cu")
		(net "GND")
	)
	(via
		(at 206.120746 -203.0857)
		(size 0.7112)
		(drill 0.4064)
		(layers "F.Cu" "B.Cu")
		(net "GND")
	)
	(via
		(at 63.880746 -113.2967)
		(size 0.7112)
		(drill 0.4064)
		(layers "F.Cu" "B.Cu")
		(net "GND")
	)
	(via
		(at 194.690746 -186.141868)
		(size 0.5588)
		(drill 0.3048)
		(layers "F.Cu" "B.Cu")
		(net "GND")
	)
	(via
		(at 250.705366 -415.05505)
		(size 0.5588)
		(drill 0.3048)
		(layers "F.Cu" "B.Cu")
		(net "GND")
	)
	(via
		(at 36.104576 -457.617576)
		(size 0.7112)
		(drill 0.4064)
		(layers "F.Cu" "B.Cu")
		(net "GND")
	)
	(via
		(at 129.209546 -126.7333)
		(size 0.7112)
		(drill 0.4064)
		(layers "F.Cu" "B.Cu")
		(net "GND")
	)
	(via
		(at 186.486546 -348.9579)
		(size 0.7112)
		(drill 0.4064)
		(layers "F.Cu" "B.Cu")
		(net "GND")
	)
	(via
		(at 54.9402 -323.7992)
		(size 0.7112)
		(drill 0.4064)
		(layers "F.Cu" "B.Cu")
		(net "GND")
	)
	(via
		(at 45.3898 -32.9946)
		(size 0.7112)
		(drill 0.4064)
		(layers "F.Cu" "B.Cu")
		(net "GND")
	)
	(via
		(at 204.088746 -128.6637)
		(size 0.7112)
		(drill 0.4064)
		(layers "F.Cu" "B.Cu")
		(net "GND")
	)
	(via
		(at 205.790546 -312.2549)
		(size 0.7112)
		(drill 0.4064)
		(layers "F.Cu" "B.Cu")
		(net "GND")
	)
	(via
		(at 259.841746 -462.6737)
		(size 0.7112)
		(drill 0.4064)
		(layers "F.Cu" "B.Cu")
		(net "GND")
	)
	(via
		(at 252.348746 -217.8177)
		(size 0.7112)
		(drill 0.4064)
		(layers "F.Cu" "B.Cu")
		(net "GND")
	)
	(via
		(at 119.379746 -64.6557)
		(size 0.7112)
		(drill 0.4064)
		(layers "F.Cu" "B.Cu")
		(net "GND")
	)
	(via
		(at 175.894746 -274.8407)
		(size 0.7112)
		(drill 0.4064)
		(layers "F.Cu" "B.Cu")
		(net "GND")
	)
	(via
		(at 84.149946 -258.3561)
		(size 0.7112)
		(drill 0.4064)
		(layers "F.Cu" "B.Cu")
		(net "GND")
	)
	(via
		(at 222.2754 -163.6776)
		(size 0.5588)
		(drill 0.3048)
		(layers "F.Cu" "B.Cu")
		(net "GND")
	)
	(via
		(at 55.879746 -160.6677)
		(size 0.7112)
		(drill 0.4064)
		(layers "F.Cu" "B.Cu")
		(net "GND")
	)
	(via
		(at 129.158746 -64.7827)
		(size 0.7112)
		(drill 0.4064)
		(layers "F.Cu" "B.Cu")
		(net "GND")
	)
	(via
		(at 125.095 -504.825)
		(size 0.7112)
		(drill 0.4064)
		(layers "F.Cu" "B.Cu")
		(net "GND")
	)
	(via
		(at 259.333746 -172.0977)
		(size 0.7112)
		(drill 0.4064)
		(layers "F.Cu" "B.Cu")
		(net "GND")
	)
	(via
		(at 73.583546 -259.5245)
		(size 0.7112)
		(drill 0.4064)
		(layers "F.Cu" "B.Cu")
		(net "GND")
	)
	(via
		(at 29.845 -41.2242)
		(size 0.7112)
		(drill 0.4064)
		(layers "F.Cu" "B.Cu")
		(net "GND")
	)
	(via
		(at 166.750746 -82.4357)
		(size 0.7112)
		(drill 0.4064)
		(layers "F.Cu" "B.Cu")
		(net "GND")
	)
	(via
		(at 145.414746 -77.8637)
		(size 0.7112)
		(drill 0.4064)
		(layers "F.Cu" "B.Cu")
		(net "GND")
	)
	(via
		(at 82.905346 -476.5675)
		(size 0.7112)
		(drill 0.4064)
		(layers "F.Cu" "B.Cu")
		(net "GND")
	)
	(via
		(at 166.750746 -266.2047)
		(size 0.7112)
		(drill 0.4064)
		(layers "F.Cu" "B.Cu")
		(net "GND")
	)
	(via
		(at 52.399946 -251.5235)
		(size 0.7112)
		(drill 0.4064)
		(layers "F.Cu" "B.Cu")
		(net "GND")
	)
	(via
		(at 34.391346 -70.3707)
		(size 0.7112)
		(drill 0.4064)
		(layers "F.Cu" "B.Cu")
		(net "GND")
	)
	(via
		(at 14.6812 -161.1122)
		(size 0.5588)
		(drill 0.3048)
		(layers "F.Cu" "B.Cu")
		(net "GND")
	)
	(via
		(at 68.732146 -457.5683)
		(size 0.7112)
		(drill 0.4064)
		(layers "F.Cu" "B.Cu")
		(net "GND")
	)
	(via
		(at 167.715946 -491.8837)
		(size 0.7112)
		(drill 0.4064)
		(layers "F.Cu" "B.Cu")
		(net "GND")
	)
	(via
		(at 247.015 -391.4648)
		(size 0.7112)
		(drill 0.4064)
		(layers "F.Cu" "B.Cu")
		(net "GND")
	)
	(via
		(at 123.342146 -347.3577)
		(size 0.7112)
		(drill 0.4064)
		(layers "F.Cu" "B.Cu")
		(net "GND")
	)
	(via
		(at 42.291 -108.839)
		(size 0.5588)
		(drill 0.3048)
		(layers "F.Cu" "B.Cu")
		(net "GND")
	)
	(via
		(at 249.935746 -80.2767)
		(size 0.7112)
		(drill 0.4064)
		(layers "F.Cu" "B.Cu")
		(net "GND")
	)
	(via
		(at 59.384946 -204.8129)
		(size 0.7112)
		(drill 0.4064)
		(layers "F.Cu" "B.Cu")
		(net "GND")
	)
	(via
		(at 57.759346 -346.2147)
		(size 0.7112)
		(drill 0.4064)
		(layers "F.Cu" "B.Cu")
		(net "GND")
	)
	(via
		(at 104.901746 -69.9897)
		(size 0.7112)
		(drill 0.4064)
		(layers "F.Cu" "B.Cu")
		(net "GND")
	)
	(via
		(at 85.292946 -486.7783)
		(size 0.7112)
		(drill 0.4064)
		(layers "F.Cu" "B.Cu")
		(net "GND")
	)
	(via
		(at 17.5006 -124.6124)
		(size 0.5588)
		(drill 0.3048)
		(layers "F.Cu" "B.Cu")
		(net "GND")
	)
	(via
		(at 152.145746 -283.0957)
		(size 0.7112)
		(drill 0.4064)
		(layers "F.Cu" "B.Cu")
		(net "GND")
	)
	(via
		(at 64.007746 -117.3607)
		(size 0.7112)
		(drill 0.4064)
		(layers "F.Cu" "B.Cu")
		(net "GND")
	)
	(via
		(at 75.336146 -380.2761)
		(size 0.7112)
		(drill 0.4064)
		(layers "F.Cu" "B.Cu")
		(net "GND")
	)
	(via
		(at 91.287346 -152.3111)
		(size 0.7112)
		(drill 0.4064)
		(layers "F.Cu" "B.Cu")
		(net "GND")
	)
	(via
		(at 34.035746 -37.8587)
		(size 0.7112)
		(drill 0.4064)
		(layers "F.Cu" "B.Cu")
		(net "GND")
	)
	(via
		(at 119.963946 -399.3007)
		(size 0.7112)
		(drill 0.4064)
		(layers "F.Cu" "B.Cu")
		(net "GND")
	)
	(via
		(at 71.373746 -150.1267)
		(size 0.7112)
		(drill 0.4064)
		(layers "F.Cu" "B.Cu")
		(net "GND")
	)
	(via
		(at 58.165746 -415.9377)
		(size 0.7112)
		(drill 0.4064)
		(layers "F.Cu" "B.Cu")
		(net "GND")
	)
	(via
		(at 194.817746 -55.6387)
		(size 0.7112)
		(drill 0.4064)
		(layers "F.Cu" "B.Cu")
		(net "GND")
	)
	(via
		(at 192.099946 -426.4787)
		(size 0.7112)
		(drill 0.4064)
		(layers "F.Cu" "B.Cu")
		(net "GND")
	)
	(via
		(at 188.924946 -479.7679)
		(size 0.7112)
		(drill 0.4064)
		(layers "F.Cu" "B.Cu")
		(net "GND")
	)
	(via
		(at 169.468546 -292.8239)
		(size 0.7112)
		(drill 0.4064)
		(layers "F.Cu" "B.Cu")
		(net "GND")
	)
	(via
		(at 233.908346 -240.3729)
		(size 0.7112)
		(drill 0.4064)
		(layers "F.Cu" "B.Cu")
		(net "GND")
	)
	(via
		(at 28.1432 -196.2658)
		(size 0.7112)
		(drill 0.4064)
		(layers "F.Cu" "B.Cu")
		(net "GND")
	)
	(via
		(at 30.5054 -267.5128)
		(size 0.5588)
		(drill 0.3048)
		(layers "F.Cu" "B.Cu")
		(net "GND")
	)
	(via
		(at 5.968746 -96.985074)
		(size 0.5588)
		(drill 0.3048)
		(layers "F.Cu" "B.Cu")
		(net "GND")
	)
	(via
		(at 246.887746 -261.2517)
		(size 0.7112)
		(drill 0.4064)
		(layers "F.Cu" "B.Cu")
		(net "GND")
	)
	(via
		(at 21.843746 -413.6517)
		(size 0.7112)
		(drill 0.4064)
		(layers "F.Cu" "B.Cu")
		(net "GND")
	)
	(via
		(at 77.215746 -105.5497)
		(size 0.7112)
		(drill 0.4064)
		(layers "F.Cu" "B.Cu")
		(net "GND")
	)
	(via
		(at 252.602746 -204.1017)
		(size 0.7112)
		(drill 0.4064)
		(layers "F.Cu" "B.Cu")
		(net "GND")
	)
	(via
		(at 29.527246 -280.0477)
		(size 0.5588)
		(drill 0.3048)
		(layers "F.Cu" "B.Cu")
		(net "GND")
	)
	(via
		(at 195.4022 -377.9774)
		(size 0.7112)
		(drill 0.4064)
		(layers "F.Cu" "B.Cu")
		(net "GND")
	)
	(via
		(at 50.342546 -204.7113)
		(size 0.7112)
		(drill 0.4064)
		(layers "F.Cu" "B.Cu")
		(net "GND")
	)
	(via
		(at 237.616746 -141.3637)
		(size 0.7112)
		(drill 0.4064)
		(layers "F.Cu" "B.Cu")
		(net "GND")
	)
	(via
		(at 203.936346 -424.3197)
		(size 0.7112)
		(drill 0.4064)
		(layers "F.Cu" "B.Cu")
		(net "GND")
	)
	(via
		(at 62.280546 -223.0247)
		(size 0.7112)
		(drill 0.4064)
		(layers "F.Cu" "B.Cu")
		(net "GND")
	)
	(via
		(at 234.060746 -261.8867)
		(size 0.7112)
		(drill 0.4064)
		(layers "F.Cu" "B.Cu")
		(net "GND")
	)
	(via
		(at 165.556946 -10.3251)
		(size 0.7112)
		(drill 0.4064)
		(layers "F.Cu" "B.Cu")
		(net "GND")
	)
	(via
		(at 180.568346 -190.7921)
		(size 0.7112)
		(drill 0.4064)
		(layers "F.Cu" "B.Cu")
		(net "GND")
	)
	(via
		(at 211.6074 -477.139)
		(size 0.7112)
		(drill 0.4064)
		(layers "F.Cu" "B.Cu")
		(net "GND")
	)
	(via
		(at 13.715746 -494.4491)
		(size 0.5588)
		(drill 0.3048)
		(layers "F.Cu" "B.Cu")
		(net "GND")
	)
	(via
		(at 216.281 -462.6356)
		(size 0.5588)
		(drill 0.3048)
		(layers "F.Cu" "B.Cu")
		(net "GND")
	)
	(via
		(at 5.943346 -124.978922)
		(size 0.5588)
		(drill 0.3048)
		(layers "F.Cu" "B.Cu")
		(net "GND")
	)
	(via
		(at 53.720746 -321.8307)
		(size 0.7112)
		(drill 0.4064)
		(layers "F.Cu" "B.Cu")
		(net "GND")
	)
	(via
		(at 110.565946 -197.5231)
		(size 0.7112)
		(drill 0.4064)
		(layers "F.Cu" "B.Cu")
		(net "GND")
	)
	(via
		(at 259.333746 -163.2077)
		(size 0.7112)
		(drill 0.4064)
		(layers "F.Cu" "B.Cu")
		(net "GND")
	)
	(via
		(at 66.674746 -286.8041)
		(size 0.7112)
		(drill 0.4064)
		(layers "F.Cu" "B.Cu")
		(net "GND")
	)
	(via
		(at 166.649146 -375.8057)
		(size 0.7112)
		(drill 0.4064)
		(layers "F.Cu" "B.Cu")
		(net "GND")
	)
	(via
		(at 133.603746 -312.6867)
		(size 0.7112)
		(drill 0.4064)
		(layers "F.Cu" "B.Cu")
		(net "GND")
	)
	(via
		(at 134.492746 -410.6037)
		(size 0.7112)
		(drill 0.4064)
		(layers "F.Cu" "B.Cu")
		(net "GND")
	)
	(via
		(at 6.095746 -66.3067)
		(size 0.7112)
		(drill 0.4064)
		(layers "F.Cu" "B.Cu")
		(net "GND")
	)
	(via
		(at 53.501036 -16.983202)
		(size 0.5588)
		(drill 0.3048)
		(layers "F.Cu" "B.Cu")
		(net "GND")
	)
	(via
		(at 40.06596 -69.576696)
		(size 0.7112)
		(drill 0.4064)
		(layers "F.Cu" "B.Cu")
		(net "GND")
	)
	(via
		(at 255.218946 -63.6143)
		(size 0.7112)
		(drill 0.4064)
		(layers "F.Cu" "B.Cu")
		(net "GND")
	)
	(via
		(at 177.291746 -300.8757)
		(size 0.7112)
		(drill 0.4064)
		(layers "F.Cu" "B.Cu")
		(net "GND")
	)
	(via
		(at 144.297146 -18.4277)
		(size 0.7112)
		(drill 0.4064)
		(layers "F.Cu" "B.Cu")
		(net "GND")
	)
	(via
		(at 227.076 -163.1696)
		(size 0.7112)
		(drill 0.4064)
		(layers "F.Cu" "B.Cu")
		(net "GND")
	)
	(via
		(at 171.170346 -497.2939)
		(size 0.7112)
		(drill 0.4064)
		(layers "F.Cu" "B.Cu")
		(net "GND")
	)
	(via
		(at 82.905346 -481.3935)
		(size 0.7112)
		(drill 0.4064)
		(layers "F.Cu" "B.Cu")
		(net "GND")
	)
	(via
		(at 128.117346 -287.5915)
		(size 0.7112)
		(drill 0.4064)
		(layers "F.Cu" "B.Cu")
		(net "GND")
	)
	(via
		(at 91.185746 -488.9627)
		(size 0.7112)
		(drill 0.4064)
		(layers "F.Cu" "B.Cu")
		(net "GND")
	)
	(via
		(at 37.083746 -343.6747)
		(size 0.7112)
		(drill 0.4064)
		(layers "F.Cu" "B.Cu")
		(net "GND")
	)
	(via
		(at 242.010946 -82.4611)
		(size 0.7112)
		(drill 0.4064)
		(layers "F.Cu" "B.Cu")
		(net "GND")
	)
	(via
		(at 54.355746 -184.1627)
		(size 0.5588)
		(drill 0.3048)
		(layers "F.Cu" "B.Cu")
		(net "GND")
	)
	(via
		(at 19.684746 -119.2657)
		(size 0.5588)
		(drill 0.3048)
		(layers "F.Cu" "B.Cu")
		(net "GND")
	)
	(via
		(at 73.406 -417.0172)
		(size 0.7112)
		(drill 0.4064)
		(layers "F.Cu" "B.Cu")
		(net "GND")
	)
	(via
		(at 171.576746 -30.7467)
		(size 0.7112)
		(drill 0.4064)
		(layers "F.Cu" "B.Cu")
		(net "GND")
	)
	(via
		(at 227.583746 -178.4477)
		(size 0.7112)
		(drill 0.4064)
		(layers "F.Cu" "B.Cu")
		(net "GND")
	)
	(via
		(at 114.299746 -55.1307)
		(size 0.7112)
		(drill 0.4064)
		(layers "F.Cu" "B.Cu")
		(net "GND")
	)
	(via
		(at 175.869346 -144.6149)
		(size 0.7112)
		(drill 0.4064)
		(layers "F.Cu" "B.Cu")
		(net "GND")
	)
	(via
		(at 162.305746 -321.9577)
		(size 0.7112)
		(drill 0.4064)
		(layers "F.Cu" "B.Cu")
		(net "GND")
	)
	(via
		(at 114.198146 -420.8653)
		(size 0.7112)
		(drill 0.4064)
		(layers "F.Cu" "B.Cu")
		(net "GND")
	)
	(via
		(at 138.937746 -497.2939)
		(size 0.7112)
		(drill 0.4064)
		(layers "F.Cu" "B.Cu")
		(net "GND")
	)
	(via
		(at 105.257346 -426.3009)
		(size 0.7112)
		(drill 0.4064)
		(layers "F.Cu" "B.Cu")
		(net "GND")
	)
	(via
		(at 183.006746 -284.1117)
		(size 0.7112)
		(drill 0.4064)
		(layers "F.Cu" "B.Cu")
		(net "GND")
	)
	(via
		(at 202.437746 -6.8707)
		(size 0.7112)
		(drill 0.4064)
		(layers "F.Cu" "B.Cu")
		(net "GND")
	)
	(via
		(at 226.186746 -322.8467)
		(size 0.7112)
		(drill 0.4064)
		(layers "F.Cu" "B.Cu")
		(net "GND")
	)
	(via
		(at 141.223746 -128.1557)
		(size 0.7112)
		(drill 0.4064)
		(layers "F.Cu" "B.Cu")
		(net "GND")
	)
	(via
		(at 106.806746 -339.2297)
		(size 0.7112)
		(drill 0.3556)
		(layers "F.Cu" "B.Cu")
		(net "GND")
	)
	(via
		(at 176.021746 -265.0617)
		(size 0.7112)
		(drill 0.4064)
		(layers "F.Cu" "B.Cu")
		(net "GND")
	)
	(via
		(at 225.297746 -240.6015)
		(size 0.7112)
		(drill 0.4064)
		(layers "F.Cu" "B.Cu")
		(net "GND")
	)
	(via
		(at 49.910746 -303.9237)
		(size 0.7112)
		(drill 0.4064)
		(layers "F.Cu" "B.Cu")
		(net "GND")
	)
	(via
		(at 176.021746 -357.2637)
		(size 0.7112)
		(drill 0.4064)
		(layers "F.Cu" "B.Cu")
		(net "GND")
	)
	(via
		(at 122.300746 -359.9307)
		(size 0.7112)
		(drill 0.4064)
		(layers "F.Cu" "B.Cu")
		(net "GND")
	)
	(via
		(at 82.067146 -224.8027)
		(size 0.7112)
		(drill 0.4064)
		(layers "F.Cu" "B.Cu")
		(net "GND")
	)
	(via
		(at 59.054746 -117.2337)
		(size 0.7112)
		(drill 0.4064)
		(layers "F.Cu" "B.Cu")
		(net "GND")
	)
	(via
		(at 2.184146 -190.9191)
		(size 0.7112)
		(drill 0.4064)
		(layers "F.Cu" "B.Cu")
		(net "GND")
	)
	(via
		(at 141.350746 -123.2027)
		(size 0.7112)
		(drill 0.4064)
		(layers "F.Cu" "B.Cu")
		(net "GND")
	)
	(via
		(at 33.299146 -177.9143)
		(size 0.7112)
		(drill 0.4064)
		(layers "F.Cu" "B.Cu")
		(net "GND")
	)
	(via
		(at 223.4946 -434.1622)
		(size 0.7112)
		(drill 0.4064)
		(layers "F.Cu" "B.Cu")
		(net "GND")
	)
	(via
		(at 42.671746 -287.1597)
		(size 0.7112)
		(drill 0.4064)
		(layers "F.Cu" "B.Cu")
		(net "GND")
	)
	(via
		(at 86.435946 -148.9837)
		(size 0.7112)
		(drill 0.4064)
		(layers "F.Cu" "B.Cu")
		(net "GND")
	)
	(via
		(at 213.181946 -104.1273)
		(size 0.7112)
		(drill 0.4064)
		(layers "F.Cu" "B.Cu")
		(net "GND")
	)
	(via
		(at 93.852746 -471.4113)
		(size 0.7112)
		(drill 0.4064)
		(layers "F.Cu" "B.Cu")
		(net "GND")
	)
	(via
		(at 62.5348 -410.8704)
		(size 0.7112)
		(drill 0.4064)
		(layers "F.Cu" "B.Cu")
		(net "GND")
	)
	(via
		(at 245.3132 -407.5938)
		(size 0.7112)
		(drill 0.4064)
		(layers "F.Cu" "B.Cu")
		(net "GND")
	)
	(via
		(at 247.573546 -5.4483)
		(size 0.7112)
		(drill 0.4064)
		(layers "F.Cu" "B.Cu")
		(net "GND")
	)
	(via
		(at 128.498346 -372.4275)
		(size 0.7112)
		(drill 0.4064)
		(layers "F.Cu" "B.Cu")
		(net "GND")
	)
	(via
		(at 236.600746 -432.3207)
		(size 0.7112)
		(drill 0.4064)
		(layers "F.Cu" "B.Cu")
		(net "GND")
	)
	(via
		(at 248.030746 -309.6387)
		(size 0.7112)
		(drill 0.4064)
		(layers "F.Cu" "B.Cu")
		(net "GND")
	)
	(via
		(at 84.670646 -338.5312)
		(size 0.7112)
		(drill 0.4064)
		(layers "F.Cu" "B.Cu")
		(net "GND")
	)
	(via
		(at 153.110946 -486.4989)
		(size 0.7112)
		(drill 0.4064)
		(layers "F.Cu" "B.Cu")
		(net "GND")
	)
	(via
		(at 204.088746 -132.3467)
		(size 0.7112)
		(drill 0.4064)
		(layers "F.Cu" "B.Cu")
		(net "GND")
	)
	(via
		(at 7.899146 -405.2189)
		(size 0.5588)
		(drill 0.3048)
		(layers "F.Cu" "B.Cu")
		(net "GND")
	)
	(via
		(at 145.795746 -471.2843)
		(size 0.7112)
		(drill 0.4064)
		(layers "F.Cu" "B.Cu")
		(net "GND")
	)
	(via
		(at 187.451746 -141.9987)
		(size 0.7112)
		(drill 0.4064)
		(layers "F.Cu" "B.Cu")
		(net "GND")
	)
	(via
		(at 168.782746 -237.7567)
		(size 0.7112)
		(drill 0.4064)
		(layers "F.Cu" "B.Cu")
		(net "GND")
	)
	(via
		(at 68.198746 -369.2017)
		(size 0.7112)
		(drill 0.4064)
		(layers "F.Cu" "B.Cu")
		(net "GND")
	)
	(via
		(at 129.361946 -502.2215)
		(size 0.7112)
		(drill 0.4064)
		(layers "F.Cu" "B.Cu")
		(net "GND")
	)
	(via
		(at 7.45871 -106.976926)
		(size 0.5588)
		(drill 0.3048)
		(layers "F.Cu" "B.Cu")
		(net "GND")
	)
	(via
		(at 158.622746 -36.3347)
		(size 0.7112)
		(drill 0.4064)
		(layers "F.Cu" "B.Cu")
		(net "GND")
	)
	(via
		(at 126.567946 -336.1309)
		(size 0.7112)
		(drill 0.4064)
		(layers "F.Cu" "B.Cu")
		(net "GND")
	)
	(via
		(at 194.309746 -1.6637)
		(size 0.7112)
		(drill 0.4064)
		(layers "F.Cu" "B.Cu")
		(net "GND")
	)
	(via
		(at 72.516746 -360.3117)
		(size 0.7112)
		(drill 0.4064)
		(layers "F.Cu" "B.Cu")
		(net "GND")
	)
	(via
		(at 154.330146 -435.9783)
		(size 0.7112)
		(drill 0.4064)
		(layers "F.Cu" "B.Cu")
		(net "GND")
	)
	(via
		(at 44.170346 -460.5655)
		(size 0.7112)
		(drill 0.4064)
		(layers "F.Cu" "B.Cu")
		(net "GND")
	)
	(via
		(at 225.373946 -411.4927)
		(size 0.7112)
		(drill 0.4064)
		(layers "F.Cu" "B.Cu")
		(net "GND")
	)
	(via
		(at 75.691746 -62.2427)
		(size 0.7112)
		(drill 0.4064)
		(layers "F.Cu" "B.Cu")
		(net "GND")
	)
	(via
		(at 46.380146 -174.8409)
		(size 0.7112)
		(drill 0.4064)
		(layers "F.Cu" "B.Cu")
		(net "GND")
	)
	(via
		(at 72.796146 -305.7525)
		(size 0.7112)
		(drill 0.4064)
		(layers "F.Cu" "B.Cu")
		(net "GND")
	)
	(via
		(at 235.330746 -329.8317)
		(size 0.7112)
		(drill 0.4064)
		(layers "F.Cu" "B.Cu")
		(net "GND")
	)
	(via
		(at 196.900546 -213.1695)
		(size 0.7112)
		(drill 0.4064)
		(layers "F.Cu" "B.Cu")
		(net "GND")
	)
	(via
		(at 204.698346 -32.0421)
		(size 0.7112)
		(drill 0.4064)
		(layers "F.Cu" "B.Cu")
		(net "GND")
	)
	(via
		(at 113.283746 -489.3437)
		(size 0.7112)
		(drill 0.4064)
		(layers "F.Cu" "B.Cu")
		(net "GND")
	)
	(via
		(at 241.756946 -124.3711)
		(size 0.7112)
		(drill 0.4064)
		(layers "F.Cu" "B.Cu")
		(net "GND")
	)
	(via
		(at 2.920746 -8.6487)
		(size 0.7112)
		(drill 0.4064)
		(layers "F.Cu" "B.Cu")
		(net "GND")
	)
	(via
		(at 153.415746 -38.7985)
		(size 0.7112)
		(drill 0.4064)
		(layers "F.Cu" "B.Cu")
		(net "GND")
	)
	(via
		(at 241.121946 -251.9553)
		(size 0.7112)
		(drill 0.4064)
		(layers "F.Cu" "B.Cu")
		(net "GND")
	)
	(via
		(at 224.662746 -194.8307)
		(size 0.7112)
		(drill 0.4064)
		(layers "F.Cu" "B.Cu")
		(net "GND")
	)
	(via
		(at 79.6544 -366.4458)
		(size 0.7112)
		(drill 0.4064)
		(layers "F.Cu" "B.Cu")
		(net "GND")
	)
	(via
		(at 35.686746 -152.5397)
		(size 0.7112)
		(drill 0.4064)
		(layers "F.Cu" "B.Cu")
		(net "GND")
	)
	(via
		(at 5.836412 -149.497034)
		(size 0.5588)
		(drill 0.3048)
		(layers "F.Cu" "B.Cu")
		(net "GND")
	)
	(via
		(at 250.316746 -150.5077)
		(size 0.7112)
		(drill 0.4064)
		(layers "F.Cu" "B.Cu")
		(net "GND")
	)
	(via
		(at 196.951346 -20.3835)
		(size 0.7112)
		(drill 0.4064)
		(layers "F.Cu" "B.Cu")
		(net "GND")
	)
	(via
		(at 255.345946 -49.3903)
		(size 0.7112)
		(drill 0.4064)
		(layers "F.Cu" "B.Cu")
		(net "GND")
	)
	(via
		(at 244.1702 -404.2664)
		(size 0.7112)
		(drill 0.4064)
		(layers "F.Cu" "B.Cu")
		(net "GND")
	)
	(via
		(at 225.277426 -265.297412)
		(size 0.7112)
		(drill 0.4064)
		(layers "F.Cu" "B.Cu")
		(net "GND")
	)
	(via
		(at 252.475746 -252.2347)
		(size 0.7112)
		(drill 0.4064)
		(layers "F.Cu" "B.Cu")
		(net "GND")
	)
	(via
		(at 83.565746 -304.9397)
		(size 0.7112)
		(drill 0.4064)
		(layers "F.Cu" "B.Cu")
		(net "GND")
	)
	(via
		(at 125.983746 -201.9427)
		(size 0.7112)
		(drill 0.4064)
		(layers "F.Cu" "B.Cu")
		(net "GND")
	)
	(via
		(at 145.668746 -268.1097)
		(size 0.7112)
		(drill 0.4064)
		(layers "F.Cu" "B.Cu")
		(net "GND")
	)
	(via
		(at 95.884746 -307.3527)
		(size 0.7112)
		(drill 0.4064)
		(layers "F.Cu" "B.Cu")
		(net "GND")
	)
	(via
		(at 116.915946 -480.6569)
		(size 0.7112)
		(drill 0.4064)
		(layers "F.Cu" "B.Cu")
		(net "GND")
	)
	(via
		(at 212.50275 -377.7996)
		(size 0.5588)
		(drill 0.3048)
		(layers "F.Cu" "B.Cu")
		(net "GND")
	)
	(via
		(at 167.525446 -461.107536)
		(size 0.7112)
		(drill 0.4064)
		(layers "F.Cu" "B.Cu")
		(net "GND")
	)
	(via
		(at 249.554746 -65.9257)
		(size 0.7112)
		(drill 0.4064)
		(layers "F.Cu" "B.Cu")
		(net "GND")
	)
	(via
		(at 56.844946 -92.7989)
		(size 0.7112)
		(drill 0.4064)
		(layers "F.Cu" "B.Cu")
		(net "GND")
	)
	(via
		(at 113.537746 -477.5327)
		(size 0.7112)
		(drill 0.4064)
		(layers "F.Cu" "B.Cu")
		(net "GND")
	)
	(via
		(at 79.502 -79.7306)
		(size 0.7112)
		(drill 0.4064)
		(layers "F.Cu" "B.Cu")
		(net "GND")
	)
	(via
		(at 254.177546 -122.5169)
		(size 0.7112)
		(drill 0.4064)
		(layers "F.Cu" "B.Cu")
		(net "GND")
	)
	(via
		(at 59.4868 -169.7482)
		(size 0.7112)
		(drill 0.4064)
		(layers "F.Cu" "B.Cu")
		(net "GND")
	)
	(via
		(at 253.771146 -312.9153)
		(size 0.7112)
		(drill 0.4064)
		(layers "F.Cu" "B.Cu")
		(net "GND")
	)
	(via
		(at 124.205746 -64.6557)
		(size 0.7112)
		(drill 0.4064)
		(layers "F.Cu" "B.Cu")
		(net "GND")
	)
	(via
		(at 63.4492 -352.6536)
		(size 0.7112)
		(drill 0.4064)
		(layers "F.Cu" "B.Cu")
		(net "GND")
	)
	(via
		(at 60.680346 -369.2525)
		(size 0.7112)
		(drill 0.4064)
		(layers "F.Cu" "B.Cu")
		(net "GND")
	)
	(via
		(at 43.382946 -175.0441)
		(size 0.7112)
		(drill 0.4064)
		(layers "F.Cu" "B.Cu")
		(net "GND")
	)
	(via
		(at 227.837746 -35.9537)
		(size 0.5588)
		(drill 0.3048)
		(layers "F.Cu" "B.Cu")
		(net "GND")
	)
	(via
		(at 107.644946 -65.9765)
		(size 0.7112)
		(drill 0.4064)
		(layers "F.Cu" "B.Cu")
		(net "GND")
	)
	(via
		(at 253.999746 -450.9135)
		(size 0.7112)
		(drill 0.4064)
		(layers "F.Cu" "B.Cu")
		(net "GND")
	)
	(via
		(at 91.44 -499.745)
		(size 0.5588)
		(drill 0.3048)
		(layers "F.Cu" "B.Cu")
		(net "GND")
	)
	(via
		(at 7.7724 -359.4354)
		(size 0.5588)
		(drill 0.3048)
		(layers "F.Cu" "B.Cu")
		(net "GND")
	)
	(via
		(at 128.828546 -315.8109)
		(size 0.7112)
		(drill 0.4064)
		(layers "F.Cu" "B.Cu")
		(net "GND")
	)
	(via
		(at 50.723546 -447.4083)
		(size 0.7112)
		(drill 0.4064)
		(layers "F.Cu" "B.Cu")
		(net "GND")
	)
	(via
		(at 31.480252 -321.976242)
		(size 0.7112)
		(drill 0.4064)
		(layers "F.Cu" "B.Cu")
		(net "GND")
	)
	(via
		(at 24.892 -504.825)
		(size 0.7112)
		(drill 0.4064)
		(layers "F.Cu" "B.Cu")
		(net "GND")
	)
	(via
		(at 4.445 -277.495)
		(size 0.7112)
		(drill 0.4064)
		(layers "F.Cu" "B.Cu")
		(net "GND")
	)
	(via
		(at 176.783746 -309.2577)
		(size 0.7112)
		(drill 0.4064)
		(layers "F.Cu" "B.Cu")
		(net "GND")
	)
	(via
		(at 176.021746 -360.9467)
		(size 0.7112)
		(drill 0.4064)
		(layers "F.Cu" "B.Cu")
		(net "GND")
	)
	(via
		(at 23.494746 -222.6437)
		(size 0.5588)
		(drill 0.3048)
		(layers "F.Cu" "B.Cu")
		(net "GND")
	)
	(via
		(at 8.382 -353.822)
		(size 0.5588)
		(drill 0.3048)
		(layers "F.Cu" "B.Cu")
		(net "GND")
	)
	(via
		(at 2.285746 -269.3797)
		(size 0.7112)
		(drill 0.4064)
		(layers "F.Cu" "B.Cu")
		(net "GND")
	)
	(via
		(at 36.575746 -153.8097)
		(size 0.7112)
		(drill 0.4064)
		(layers "F.Cu" "B.Cu")
		(net "GND")
	)
	(via
		(at 56.514746 -442.9379)
		(size 0.7112)
		(drill 0.4064)
		(layers "F.Cu" "B.Cu")
		(net "GND")
	)
	(via
		(at 23.596346 -58.7883)
		(size 0.7112)
		(drill 0.4064)
		(layers "F.Cu" "B.Cu")
		(net "GND")
	)
	(via
		(at 242.950746 -504.4567)
		(size 0.7112)
		(drill 0.4064)
		(layers "F.Cu" "B.Cu")
		(net "GND")
	)
	(via
		(at 6.908546 -476.0849)
		(size 0.7112)
		(drill 0.4064)
		(layers "F.Cu" "B.Cu")
		(net "GND")
	)
	(via
		(at 241.350546 -299.2755)
		(size 0.7112)
		(drill 0.4064)
		(layers "F.Cu" "B.Cu")
		(net "GND")
	)
	(via
		(at 142.011146 -341.1855)
		(size 0.7112)
		(drill 0.4064)
		(layers "F.Cu" "B.Cu")
		(net "GND")
	)
	(via
		(at 3.302 -290.957)
		(size 0.7112)
		(drill 0.4064)
		(layers "F.Cu" "B.Cu")
		(net "GND")
	)
	(via
		(at 256.184146 -435.8767)
		(size 0.7112)
		(drill 0.4064)
		(layers "F.Cu" "B.Cu")
		(net "GND")
	)
	(via
		(at 180.060346 -393.5095)
		(size 0.7112)
		(drill 0.4064)
		(layers "F.Cu" "B.Cu")
		(net "GND")
	)
	(via
		(at 206.756 -276.098)
		(size 0.5588)
		(drill 0.3048)
		(layers "F.Cu" "B.Cu")
		(net "GND")
	)
	(via
		(at 146.303746 -190.6397)
		(size 0.7112)
		(drill 0.4064)
		(layers "F.Cu" "B.Cu")
		(net "GND")
	)
	(via
		(at 156.590746 -485.9147)
		(size 0.7112)
		(drill 0.4064)
		(layers "F.Cu" "B.Cu")
		(net "GND")
	)
	(via
		(at 74.675746 -164.6047)
		(size 0.7112)
		(drill 0.4064)
		(layers "F.Cu" "B.Cu")
		(net "GND")
	)
	(via
		(at 226.313746 -339.4837)
		(size 0.7112)
		(drill 0.4064)
		(layers "F.Cu" "B.Cu")
		(net "GND")
	)
	(via
		(at 130.276346 -214.0077)
		(size 0.7112)
		(drill 0.4064)
		(layers "F.Cu" "B.Cu")
		(net "GND")
	)
	(via
		(at 17.8054 -208.0006)
		(size 0.7112)
		(drill 0.4064)
		(layers "F.Cu" "B.Cu")
		(net "GND")
	)
	(via
		(at 242.137946 -102.0191)
		(size 0.7112)
		(drill 0.4064)
		(layers "F.Cu" "B.Cu")
		(net "GND")
	)
	(via
		(at 195.452746 -280.6827)
		(size 0.7112)
		(drill 0.4064)
		(layers "F.Cu" "B.Cu")
		(net "GND")
	)
	(via
		(at 244.2718 -401.0152)
		(size 0.7112)
		(drill 0.4064)
		(layers "F.Cu" "B.Cu")
		(net "GND")
	)
	(via
		(at 42.798746 -471.3097)
		(size 0.7112)
		(drill 0.4064)
		(layers "F.Cu" "B.Cu")
		(net "GND")
	)
	(via
		(at 40.0558 -283.196792)
		(size 0.5588)
		(drill 0.3048)
		(layers "F.Cu" "B.Cu")
		(net "GND")
	)
	(via
		(at 184.403746 -11.4427)
		(size 0.7112)
		(drill 0.4064)
		(layers "F.Cu" "B.Cu")
		(net "GND")
	)
	(via
		(at 156.946346 -345.6559)
		(size 0.7112)
		(drill 0.4064)
		(layers "F.Cu" "B.Cu")
		(net "GND")
	)
	(via
		(at 27.584146 -141.537944)
		(size 0.7112)
		(drill 0.4064)
		(layers "F.Cu" "B.Cu")
		(net "GND")
	)
	(via
		(at 256.869946 -472.6051)
		(size 0.7112)
		(drill 0.4064)
		(layers "F.Cu" "B.Cu")
		(net "GND")
	)
	(via
		(at 221.509844 -491.736888)
		(size 0.5588)
		(drill 0.3048)
		(layers "F.Cu" "B.Cu")
		(net "GND")
	)
	(via
		(at 84.670646 -363.093)
		(size 0.7112)
		(drill 0.4064)
		(layers "F.Cu" "B.Cu")
		(net "GND")
	)
	(via
		(at 148.157946 -325.9455)
		(size 0.7112)
		(drill 0.4064)
		(layers "F.Cu" "B.Cu")
		(net "GND")
	)
	(via
		(at 211.962746 -354.9777)
		(size 0.7112)
		(drill 0.4064)
		(layers "F.Cu" "B.Cu")
		(net "GND")
	)
	(via
		(at 218.642946 -6.1341)
		(size 0.7112)
		(drill 0.4064)
		(layers "F.Cu" "B.Cu")
		(net "GND")
	)
	(via
		(at 153.974546 -339.9155)
		(size 0.7112)
		(drill 0.4064)
		(layers "F.Cu" "B.Cu")
		(net "GND")
	)
	(via
		(at 188.8236 -400.9898)
		(size 0.7112)
		(drill 0.4064)
		(layers "F.Cu" "B.Cu")
		(net "GND")
	)
	(via
		(at 201.116946 -471.3859)
		(size 0.7112)
		(drill 0.4064)
		(layers "F.Cu" "B.Cu")
		(net "GND")
	)
	(via
		(at 4.876292 -38.608)
		(size 0.7112)
		(drill 0.4064)
		(layers "F.Cu" "B.Cu")
		(net "GND")
	)
	(via
		(at 259.206746 -68.4657)
		(size 0.7112)
		(drill 0.4064)
		(layers "F.Cu" "B.Cu")
		(net "GND")
	)
	(via
		(at 95.783146 -430.8729)
		(size 0.7112)
		(drill 0.4064)
		(layers "F.Cu" "B.Cu")
		(net "GND")
	)
	(via
		(at 223.489012 -62.921896)
		(size 0.7112)
		(drill 0.4064)
		(layers "F.Cu" "B.Cu")
		(net "GND")
	)
	(via
		(at 195.833746 -73.6727)
		(size 0.5588)
		(drill 0.3048)
		(layers "F.Cu" "B.Cu")
		(net "GND")
	)
	(via
		(at 226.694746 -315.8617)
		(size 0.7112)
		(drill 0.4064)
		(layers "F.Cu" "B.Cu")
		(net "GND")
	)
	(via
		(at 141.985746 -258.4577)
		(size 0.7112)
		(drill 0.4064)
		(layers "F.Cu" "B.Cu")
		(net "GND")
	)
	(via
		(at 237.489746 -146.3167)
		(size 0.7112)
		(drill 0.4064)
		(layers "F.Cu" "B.Cu")
		(net "GND")
	)
	(via
		(at 69.341746 -280.1239)
		(size 0.7112)
		(drill 0.4064)
		(layers "F.Cu" "B.Cu")
		(net "GND")
	)
	(via
		(at 179.577746 -206.1337)
		(size 0.7112)
		(drill 0.4064)
		(layers "F.Cu" "B.Cu")
		(net "GND")
	)
	(via
		(at 102.489 -504.698)
		(size 0.7112)
		(drill 0.4064)
		(layers "F.Cu" "B.Cu")
		(net "GND")
	)
	(via
		(at 146.227546 -365.4933)
		(size 0.7112)
		(drill 0.4064)
		(layers "F.Cu" "B.Cu")
		(net "GND")
	)
	(via
		(at 87.756746 -504.8377)
		(size 0.7112)
		(drill 0.4064)
		(layers "F.Cu" "B.Cu")
		(net "GND")
	)
	(via
		(at 10.159746 -83.1977)
		(size 0.7112)
		(drill 0.4064)
		(layers "F.Cu" "B.Cu")
		(net "GND")
	)
	(via
		(at 170.230546 -302.9585)
		(size 0.7112)
		(drill 0.4064)
		(layers "F.Cu" "B.Cu")
		(net "GND")
	)
	(via
		(at 196.392546 -244.0051)
		(size 0.7112)
		(drill 0.4064)
		(layers "F.Cu" "B.Cu")
		(net "GND")
	)
	(via
		(at 32.765746 -113.1697)
		(size 0.7112)
		(drill 0.4064)
		(layers "F.Cu" "B.Cu")
		(net "GND")
	)
	(via
		(at 105.841546 -341.0331)
		(size 0.7112)
		(drill 0.4064)
		(layers "F.Cu" "B.Cu")
		(net "GND")
	)
	(via
		(at 152.145746 -328.3077)
		(size 0.7112)
		(drill 0.4064)
		(layers "F.Cu" "B.Cu")
		(net "GND")
	)
	(via
		(at 101.294946 -9.182608)
		(size 0.5588)
		(drill 0.3048)
		(layers "F.Cu" "B.Cu")
		(net "GND")
	)
	(via
		(at 53.527452 -20.868386)
		(size 0.5588)
		(drill 0.3048)
		(layers "F.Cu" "B.Cu")
		(net "GND")
	)
	(via
		(at 2.54 -4.191)
		(size 0.7112)
		(drill 0.4064)
		(layers "F.Cu" "B.Cu")
		(net "GND")
	)
	(via
		(at 172.795946 -346.9259)
		(size 0.7112)
		(drill 0.4064)
		(layers "F.Cu" "B.Cu")
		(net "GND")
	)
	(via
		(at 229.3366 -434.2892)
		(size 0.7112)
		(drill 0.4064)
		(layers "F.Cu" "B.Cu")
		(net "GND")
	)
	(via
		(at 169.011346 -445.0969)
		(size 0.7112)
		(drill 0.4064)
		(layers "F.Cu" "B.Cu")
		(net "GND")
	)
	(via
		(at 68.579746 -105.4227)
		(size 0.7112)
		(drill 0.4064)
		(layers "F.Cu" "B.Cu")
		(net "GND")
	)
	(via
		(at 245.198646 -442.468)
		(size 0.7112)
		(drill 0.4064)
		(layers "F.Cu" "B.Cu")
		(net "GND")
	)
	(via
		(at 76.809346 -422.3893)
		(size 0.7112)
		(drill 0.4064)
		(layers "F.Cu" "B.Cu")
		(net "GND")
	)
	(via
		(at 254.1778 -344.9574)
		(size 0.7112)
		(drill 0.4064)
		(layers "F.Cu" "B.Cu")
		(net "GND")
	)
	(via
		(at 53.339746 -463.5627)
		(size 0.7112)
		(drill 0.4064)
		(layers "F.Cu" "B.Cu")
		(net "GND")
	)
	(via
		(at 160.019746 -267.2207)
		(size 0.7112)
		(drill 0.4064)
		(layers "F.Cu" "B.Cu")
		(net "GND")
	)
	(via
		(at 56.5658 -434.3654)
		(size 0.7112)
		(drill 0.4064)
		(layers "F.Cu" "B.Cu")
		(net "GND")
	)
	(via
		(at 139.2174 -91.9988)
		(size 0.7112)
		(drill 0.4064)
		(layers "F.Cu" "B.Cu")
		(net "GND")
	)
	(via
		(at 62.356746 -25.5397)
		(size 0.5588)
		(drill 0.3048)
		(layers "F.Cu" "B.Cu")
		(net "GND")
	)
	(via
		(at 139.191746 -193.1797)
		(size 0.7112)
		(drill 0.4064)
		(layers "F.Cu" "B.Cu")
		(net "GND")
	)
	(via
		(at 31.724346 -103.8987)
		(size 0.7112)
		(drill 0.4064)
		(layers "F.Cu" "B.Cu")
		(net "GND")
	)
	(via
		(at 162.966146 -219.0115)
		(size 0.7112)
		(drill 0.4064)
		(layers "F.Cu" "B.Cu")
		(net "GND")
	)
	(via
		(at 43.001946 -271.0561)
		(size 0.7112)
		(drill 0.4064)
		(layers "F.Cu" "B.Cu")
		(net "GND")
	)
	(via
		(at 247.015 -396.1638)
		(size 0.7112)
		(drill 0.4064)
		(layers "F.Cu" "B.Cu")
		(net "GND")
	)
	(via
		(at 165.328346 -45.3009)
		(size 0.7112)
		(drill 0.4064)
		(layers "F.Cu" "B.Cu")
		(net "GND")
	)
	(via
		(at 241.756946 -132.4991)
		(size 0.7112)
		(drill 0.4064)
		(layers "F.Cu" "B.Cu")
		(net "GND")
	)
	(via
		(at 2.234946 -330.8477)
		(size 0.7112)
		(drill 0.4064)
		(layers "F.Cu" "B.Cu")
		(net "GND")
	)
	(via
		(at 242.696746 -429.4759)
		(size 0.7112)
		(drill 0.4064)
		(layers "F.Cu" "B.Cu")
		(net "GND")
	)
	(via
		(at 215.848946 -304.7365)
		(size 0.7112)
		(drill 0.4064)
		(layers "F.Cu" "B.Cu")
		(net "GND")
	)
	(via
		(at 111.658146 -394.2461)
		(size 0.7112)
		(drill 0.4064)
		(layers "F.Cu" "B.Cu")
		(net "GND")
	)
	(via
		(at 31.749746 -62.4967)
		(size 0.5588)
		(drill 0.3048)
		(layers "F.Cu" "B.Cu")
		(net "GND")
	)
	(via
		(at 190.601346 -111.5187)
		(size 0.7112)
		(drill 0.4064)
		(layers "F.Cu" "B.Cu")
		(net "GND")
	)
	(via
		(at 228.218746 -210.8327)
		(size 0.7112)
		(drill 0.4064)
		(layers "F.Cu" "B.Cu")
		(net "GND")
	)
	(via
		(at 49.656746 -470.5477)
		(size 0.7112)
		(drill 0.3556)
		(layers "F.Cu" "B.Cu")
		(net "GND")
	)
	(via
		(at 250.443746 -136.2837)
		(size 0.7112)
		(drill 0.4064)
		(layers "F.Cu" "B.Cu")
		(net "GND")
	)
	(via
		(at 55.270146 -100.6983)
		(size 0.7112)
		(drill 0.4064)
		(layers "F.Cu" "B.Cu")
		(net "GND")
	)
	(via
		(at 109.245146 -140.0683)
		(size 0.7112)
		(drill 0.4064)
		(layers "F.Cu" "B.Cu")
		(net "GND")
	)
	(via
		(at 113.232946 -42.0751)
		(size 0.7112)
		(drill 0.4064)
		(layers "F.Cu" "B.Cu")
		(net "GND")
	)
	(via
		(at 53.314854 -429.7299)
		(size 0.7112)
		(drill 0.4064)
		(layers "F.Cu" "B.Cu")
		(net "GND")
	)
	(via
		(at 8.6868 -372.4148)
		(size 0.5588)
		(drill 0.3048)
		(layers "F.Cu" "B.Cu")
		(net "GND")
	)
	(via
		(at 244.0686 -397.6624)
		(size 0.7112)
		(drill 0.4064)
		(layers "F.Cu" "B.Cu")
		(net "GND")
	)
	(via
		(at 237.032546 -400.6977)
		(size 0.7112)
		(drill 0.4064)
		(layers "F.Cu" "B.Cu")
		(net "GND")
	)
	(via
		(at 221.767146 -399.4277)
		(size 0.7112)
		(drill 0.4064)
		(layers "F.Cu" "B.Cu")
		(net "GND")
	)
	(via
		(at 146.786346 -116.9797)
		(size 0.7112)
		(drill 0.4064)
		(layers "F.Cu" "B.Cu")
		(net "GND")
	)
	(via
		(at 151.383746 -162.9537)
		(size 0.7112)
		(drill 0.4064)
		(layers "F.Cu" "B.Cu")
		(net "GND")
	)
	(via
		(at 146.176746 -208.5467)
		(size 0.7112)
		(drill 0.4064)
		(layers "F.Cu" "B.Cu")
		(net "GND")
	)
	(via
		(at 80.517746 -471.4113)
		(size 0.7112)
		(drill 0.4064)
		(layers "F.Cu" "B.Cu")
		(net "GND")
	)
	(via
		(at 50.672746 -277.8379)
		(size 0.7112)
		(drill 0.4064)
		(layers "F.Cu" "B.Cu")
		(net "GND")
	)
	(via
		(at 225.424746 -374.9167)
		(size 0.7112)
		(drill 0.4064)
		(layers "F.Cu" "B.Cu")
		(net "GND")
	)
	(via
		(at 221.446344 -467.606888)
		(size 0.7112)
		(drill 0.4064)
		(layers "F.Cu" "B.Cu")
		(net "GND")
	)
	(via
		(at 152.018746 -277.1267)
		(size 0.7112)
		(drill 0.4064)
		(layers "F.Cu" "B.Cu")
		(net "GND")
	)
	(via
		(at 8.860536 -410.396436)
		(size 0.5588)
		(drill 0.3048)
		(layers "F.Cu" "B.Cu")
		(net "GND")
	)
	(via
		(at 128.676146 -180.7591)
		(size 0.7112)
		(drill 0.4064)
		(layers "F.Cu" "B.Cu")
		(net "GND")
	)
	(via
		(at 156.870146 -316.5475)
		(size 0.7112)
		(drill 0.4064)
		(layers "F.Cu" "B.Cu")
		(net "GND")
	)
	(via
		(at 171.703746 -45.8597)
		(size 0.7112)
		(drill 0.4064)
		(layers "F.Cu" "B.Cu")
		(net "GND")
	)
	(via
		(at 252.729746 -504.5837)
		(size 0.7112)
		(drill 0.4064)
		(layers "F.Cu" "B.Cu")
		(net "GND")
	)
	(via
		(at 235.838746 -336.6389)
		(size 0.7112)
		(drill 0.4064)
		(layers "F.Cu" "B.Cu")
		(net "GND")
	)
	(via
		(at 166.750746 -261.3787)
		(size 0.7112)
		(drill 0.4064)
		(layers "F.Cu" "B.Cu")
		(net "GND")
	)
	(via
		(at 242.341146 -486.5243)
		(size 0.7112)
		(drill 0.4064)
		(layers "F.Cu" "B.Cu")
		(net "GND")
	)
	(via
		(at 163.194746 -434.0987)
		(size 0.7112)
		(drill 0.4064)
		(layers "F.Cu" "B.Cu")
		(net "GND")
	)
	(via
		(at 53.720746 -319.5447)
		(size 0.7112)
		(drill 0.4064)
		(layers "F.Cu" "B.Cu")
		(net "GND")
	)
	(via
		(at 216.864946 -454.8759)
		(size 0.7112)
		(drill 0.4064)
		(layers "F.Cu" "B.Cu")
		(net "GND")
	)
	(via
		(at 187.578746 -128.9177)
		(size 0.7112)
		(drill 0.4064)
		(layers "F.Cu" "B.Cu")
		(net "GND")
	)
	(via
		(at 241.883946 -96.6851)
		(size 0.7112)
		(drill 0.4064)
		(layers "F.Cu" "B.Cu")
		(net "GND")
	)
	(via
		(at 19.8374 -428.800006)
		(size 0.5588)
		(drill 0.3048)
		(layers "F.Cu" "B.Cu")
		(net "GND")
	)
	(via
		(at 206.375 -71.8185)
		(size 0.5588)
		(drill 0.3048)
		(layers "F.Cu" "B.Cu")
		(net "GND")
	)
	(via
		(at 217.2589 -432.613054)
		(size 0.7112)
		(drill 0.4064)
		(layers "F.Cu" "B.Cu")
		(net "GND")
	)
	(via
		(at 85.851746 -55.6387)
		(size 0.7112)
		(drill 0.4064)
		(layers "F.Cu" "B.Cu")
		(net "GND")
	)
	(via
		(at 148.919946 -180.6575)
		(size 0.7112)
		(drill 0.4064)
		(layers "F.Cu" "B.Cu")
		(net "GND")
	)
	(via
		(at 51.054 -357.759)
		(size 0.7112)
		(drill 0.4064)
		(layers "F.Cu" "B.Cu")
		(net "GND")
	)
	(via
		(at 214.375746 -489.8517)
		(size 0.7112)
		(drill 0.4064)
		(layers "F.Cu" "B.Cu")
		(net "GND")
	)
	(via
		(at 139.191746 -480.6569)
		(size 0.7112)
		(drill 0.4064)
		(layers "F.Cu" "B.Cu")
		(net "GND")
	)
	(via
		(at 225.399854 -168.91)
		(size 0.7112)
		(drill 0.4064)
		(layers "F.Cu" "B.Cu")
		(net "GND")
	)
	(via
		(at 2.412746 -71.5137)
		(size 0.7112)
		(drill 0.4064)
		(layers "F.Cu" "B.Cu")
		(net "GND")
	)
	(via
		(at 191.769746 -153.7081)
		(size 0.7112)
		(drill 0.4064)
		(layers "F.Cu" "B.Cu")
		(net "GND")
	)
	(via
		(at 143.865346 -323.5579)
		(size 0.7112)
		(drill 0.4064)
		(layers "F.Cu" "B.Cu")
		(net "GND")
	)
	(via
		(at 187.908946 -483.1461)
		(size 0.7112)
		(drill 0.4064)
		(layers "F.Cu" "B.Cu")
		(net "GND")
	)
	(via
		(at 108.076746 -415.3027)
		(size 0.7112)
		(drill 0.4064)
		(layers "F.Cu" "B.Cu")
		(net "GND")
	)
	(via
		(at 40.35679 -175.116744)
		(size 0.5588)
		(drill 0.3048)
		(layers "F.Cu" "B.Cu")
		(net "GND")
	)
	(via
		(at 224.154746 -37.3507)
		(size 0.5588)
		(drill 0.3048)
		(layers "F.Cu" "B.Cu")
		(net "GND")
	)
	(via
		(at 190.728346 -106.5657)
		(size 0.7112)
		(drill 0.4064)
		(layers "F.Cu" "B.Cu")
		(net "GND")
	)
	(via
		(at 117.474746 -240.4237)
		(size 0.7112)
		(drill 0.4064)
		(layers "F.Cu" "B.Cu")
		(net "GND")
	)
	(via
		(at 80.009746 -387.9977)
		(size 0.5588)
		(drill 0.3048)
		(layers "F.Cu" "B.Cu")
		(net "GND")
	)
	(via
		(at 109.092746 -444.0047)
		(size 0.7112)
		(drill 0.4064)
		(layers "F.Cu" "B.Cu")
		(net "GND")
	)
	(via
		(at 125.348746 -219.7227)
		(size 0.7112)
		(drill 0.4064)
		(layers "F.Cu" "B.Cu")
		(net "GND")
	)
	(via
		(at 95.630746 -318.9097)
		(size 0.7112)
		(drill 0.4064)
		(layers "F.Cu" "B.Cu")
		(net "GND")
	)
	(via
		(at 14.604746 -475.2467)
		(size 0.7112)
		(drill 0.4064)
		(layers "F.Cu" "B.Cu")
		(net "GND")
	)
	(via
		(at 192.404746 -11.1887)
		(size 0.7112)
		(drill 0.4064)
		(layers "F.Cu" "B.Cu")
		(net "GND")
	)
	(via
		(at 78.231746 -246.5451)
		(size 0.7112)
		(drill 0.4064)
		(layers "F.Cu" "B.Cu")
		(net "GND")
	)
	(via
		(at 175.323246 -458.631036)
		(size 0.5588)
		(drill 0.3048)
		(layers "F.Cu" "B.Cu")
		(net "GND")
	)
	(via
		(at 5.841746 -365.0107)
		(size 0.5588)
		(drill 0.3048)
		(layers "F.Cu" "B.Cu")
		(net "GND")
	)
	(via
		(at 159.511746 -63.0047)
		(size 0.7112)
		(drill 0.4064)
		(layers "F.Cu" "B.Cu")
		(net "GND")
	)
	(via
		(at 35.051746 -443.921642)
		(size 0.7112)
		(drill 0.4064)
		(layers "F.Cu" "B.Cu")
		(net "GND")
	)
	(via
		(at 185.216546 -379.1585)
		(size 0.7112)
		(drill 0.4064)
		(layers "F.Cu" "B.Cu")
		(net "GND")
	)
	(via
		(at 126.745746 -1.5367)
		(size 0.7112)
		(drill 0.4064)
		(layers "F.Cu" "B.Cu")
		(net "GND")
	)
	(via
		(at 115.772946 -502.0945)
		(size 0.7112)
		(drill 0.4064)
		(layers "F.Cu" "B.Cu")
		(net "GND")
	)
	(via
		(at 134.6708 -337.1342)
		(size 0.7112)
		(drill 0.3556)
		(layers "F.Cu" "B.Cu")
		(net "GND")
	)
	(via
		(at 54.355746 -243.4971)
		(size 0.7112)
		(drill 0.4064)
		(layers "F.Cu" "B.Cu")
		(net "GND")
	)
	(via
		(at 174.523146 -204.3811)
		(size 0.7112)
		(drill 0.4064)
		(layers "F.Cu" "B.Cu")
		(net "GND")
	)
	(via
		(at 170.027346 -471.2589)
		(size 0.7112)
		(drill 0.4064)
		(layers "F.Cu" "B.Cu")
		(net "GND")
	)
	(via
		(at 238.886746 -420.8653)
		(size 0.7112)
		(drill 0.4064)
		(layers "F.Cu" "B.Cu")
		(net "GND")
	)
	(via
		(at 188.976 -499.11)
		(size 0.7112)
		(drill 0.3556)
		(layers "F.Cu" "B.Cu")
		(net "GND")
	)
	(via
		(at 43.560746 -253.6571)
		(size 0.7112)
		(drill 0.4064)
		(layers "F.Cu" "B.Cu")
		(net "GND")
	)
	(via
		(at 150.723346 -423.8879)
		(size 0.7112)
		(drill 0.4064)
		(layers "F.Cu" "B.Cu")
		(net "GND")
	)
	(via
		(at 81.787746 -440.1947)
		(size 0.7112)
		(drill 0.4064)
		(layers "F.Cu" "B.Cu")
		(net "GND")
	)
	(via
		(at 237.108746 -80.9117)
		(size 0.7112)
		(drill 0.4064)
		(layers "F.Cu" "B.Cu")
		(net "GND")
	)
	(via
		(at 259.460746 -146.3167)
		(size 0.7112)
		(drill 0.4064)
		(layers "F.Cu" "B.Cu")
		(net "GND")
	)
	(via
		(at 8.9916 -386.6388)
		(size 0.5588)
		(drill 0.3048)
		(layers "F.Cu" "B.Cu")
		(net "GND")
	)
	(via
		(at 8.3058 -377.2408)
		(size 0.5588)
		(drill 0.3048)
		(layers "F.Cu" "B.Cu")
		(net "GND")
	)
	(via
		(at 234.949746 -381.7747)
		(size 0.7112)
		(drill 0.4064)
		(layers "F.Cu" "B.Cu")
		(net "GND")
	)
	(via
		(at 81.025746 -206.8449)
		(size 0.7112)
		(drill 0.4064)
		(layers "F.Cu" "B.Cu")
		(net "GND")
	)
	(via
		(at 146.303746 -194.3227)
		(size 0.7112)
		(drill 0.4064)
		(layers "F.Cu" "B.Cu")
		(net "GND")
	)
	(via
		(at 159.689546 -295.7957)
		(size 0.7112)
		(drill 0.4064)
		(layers "F.Cu" "B.Cu")
		(net "GND")
	)
	(via
		(at 159.943546 -487.4895)
		(size 0.7112)
		(drill 0.4064)
		(layers "F.Cu" "B.Cu")
		(net "GND")
	)
	(via
		(at 105.714546 -412.8135)
		(size 0.7112)
		(drill 0.4064)
		(layers "F.Cu" "B.Cu")
		(net "GND")
	)
	(via
		(at 184.683146 -181.6227)
		(size 0.7112)
		(drill 0.4064)
		(layers "F.Cu" "B.Cu")
		(net "GND")
	)
	(via
		(at 227.202746 -386.6007)
		(size 0.7112)
		(drill 0.4064)
		(layers "F.Cu" "B.Cu")
		(net "GND")
	)
	(via
		(at 40.2082 -257.81)
		(size 0.7112)
		(drill 0.4064)
		(layers "F.Cu" "B.Cu")
		(net "GND")
	)
	(via
		(at 233.6292 -13.8684)
		(size 0.5588)
		(drill 0.3048)
		(layers "F.Cu" "B.Cu")
		(net "GND")
	)
	(via
		(at 118.541546 -350.0501)
		(size 0.7112)
		(drill 0.4064)
		(layers "F.Cu" "B.Cu")
		(net "GND")
	)
	(via
		(at 182.752746 -367.4491)
		(size 0.7112)
		(drill 0.4064)
		(layers "F.Cu" "B.Cu")
		(net "GND")
	)
	(via
		(at 124.535946 -186.5757)
		(size 0.7112)
		(drill 0.4064)
		(layers "F.Cu" "B.Cu")
		(net "GND")
	)
	(via
		(at 50.546 -504.825)
		(size 0.7112)
		(drill 0.4064)
		(layers "F.Cu" "B.Cu")
		(net "GND")
	)
	(via
		(at 40.429942 -491.736888)
		(size 0.7112)
		(drill 0.4064)
		(layers "F.Cu" "B.Cu")
		(net "GND")
	)
	(via
		(at 39.141146 -134.425944)
		(size 0.7112)
		(drill 0.4064)
		(layers "F.Cu" "B.Cu")
		(net "GND")
	)
	(via
		(at 71.373746 -210.1977)
		(size 0.7112)
		(drill 0.4064)
		(layers "F.Cu" "B.Cu")
		(net "GND")
	)
	(via
		(at 259.155946 -443.6491)
		(size 0.7112)
		(drill 0.4064)
		(layers "F.Cu" "B.Cu")
		(net "GND")
	)
	(via
		(at 172.541946 -178.5747)
		(size 0.7112)
		(drill 0.4064)
		(layers "F.Cu" "B.Cu")
		(net "GND")
	)
	(via
		(at 50.063146 -201.9427)
		(size 0.7112)
		(drill 0.4064)
		(layers "F.Cu" "B.Cu")
		(net "GND")
	)
	(via
		(at 182.371746 -504.8377)
		(size 0.7112)
		(drill 0.4064)
		(layers "F.Cu" "B.Cu")
		(net "GND")
	)
	(via
		(at 176.021746 -256.9337)
		(size 0.7112)
		(drill 0.4064)
		(layers "F.Cu" "B.Cu")
		(net "GND")
	)
	(via
		(at 163.601146 -114.5413)
		(size 0.7112)
		(drill 0.4064)
		(layers "F.Cu" "B.Cu")
		(net "GND")
	)
	(via
		(at 221.335346 -300.4439)
		(size 0.7112)
		(drill 0.4064)
		(layers "F.Cu" "B.Cu")
		(net "GND")
	)
	(via
		(at 246.379746 -189.0395)
		(size 0.7112)
		(drill 0.4064)
		(layers "F.Cu" "B.Cu")
		(net "GND")
	)
	(via
		(at 168.528746 -232.4227)
		(size 0.7112)
		(drill 0.4064)
		(layers "F.Cu" "B.Cu")
		(net "GND")
	)
	(via
		(at 149.352 -407.416)
		(size 0.7112)
		(drill 0.4064)
		(layers "F.Cu" "B.Cu")
		(net "GND")
	)
	(via
		(at 86.893146 -164.1729)
		(size 0.7112)
		(drill 0.4064)
		(layers "F.Cu" "B.Cu")
		(net "GND")
	)
	(via
		(at 252.856746 -209.4357)
		(size 0.7112)
		(drill 0.4064)
		(layers "F.Cu" "B.Cu")
		(net "GND")
	)
	(via
		(at 98.043746 -19.8247)
		(size 0.5588)
		(drill 0.3048)
		(layers "F.Cu" "B.Cu")
		(net "GND")
	)
	(via
		(at 138.810746 -299.9105)
		(size 0.7112)
		(drill 0.4064)
		(layers "F.Cu" "B.Cu")
		(net "GND")
	)
	(via
		(at 69.341746 -117.1067)
		(size 0.7112)
		(drill 0.4064)
		(layers "F.Cu" "B.Cu")
		(net "GND")
	)
	(via
		(at 179.463446 -455.583036)
		(size 0.7112)
		(drill 0.4064)
		(layers "F.Cu" "B.Cu")
		(net "GND")
	)
	(via
		(at 197.332346 -255.7907)
		(size 0.7112)
		(drill 0.4064)
		(layers "F.Cu" "B.Cu")
		(net "GND")
	)
	(via
		(at 190.372746 -1.6637)
		(size 0.7112)
		(drill 0.4064)
		(layers "F.Cu" "B.Cu")
		(net "GND")
	)
	(via
		(at 222.4786 -434.213)
		(size 0.7112)
		(drill 0.4064)
		(layers "F.Cu" "B.Cu")
		(net "GND")
	)
	(via
		(at 42.036746 -369.2017)
		(size 0.7112)
		(drill 0.4064)
		(layers "F.Cu" "B.Cu")
		(net "GND")
	)
	(via
		(at 123.392946 -233.6927)
		(size 0.7112)
		(drill 0.4064)
		(layers "F.Cu" "B.Cu")
		(net "GND")
	)
	(via
		(at 181.203346 -299.4025)
		(size 0.7112)
		(drill 0.4064)
		(layers "F.Cu" "B.Cu")
		(net "GND")
	)
	(via
		(at 112.216946 -26.0223)
		(size 0.7112)
		(drill 0.4064)
		(layers "F.Cu" "B.Cu")
		(net "GND")
	)
	(via
		(at 199.008746 -431.5587)
		(size 0.7112)
		(drill 0.4064)
		(layers "F.Cu" "B.Cu")
		(net "GND")
	)
	(via
		(at 75.401932 -496.881912)
		(size 0.7112)
		(drill 0.4064)
		(layers "F.Cu" "B.Cu")
		(net "GND")
	)
	(via
		(at 200.481946 -503.8979)
		(size 0.7112)
		(drill 0.4064)
		(layers "F.Cu" "B.Cu")
		(net "GND")
	)
	(via
		(at 128.142746 -143.7767)
		(size 0.7112)
		(drill 0.4064)
		(layers "F.Cu" "B.Cu")
		(net "GND")
	)
	(via
		(at 112.572546 -111.9759)
		(size 0.7112)
		(drill 0.4064)
		(layers "F.Cu" "B.Cu")
		(net "GND")
	)
	(via
		(at 243.534946 -435.8005)
		(size 0.7112)
		(drill 0.4064)
		(layers "F.Cu" "B.Cu")
		(net "GND")
	)
	(via
		(at 62.610746 -20.4597)
		(size 0.5588)
		(drill 0.3048)
		(layers "F.Cu" "B.Cu")
		(net "GND")
	)
	(via
		(at 11.82751 -494.462562)
		(size 0.5588)
		(drill 0.3048)
		(layers "F.Cu" "B.Cu")
		(net "GND")
	)
	(via
		(at 40.893746 -37.9857)
		(size 0.7112)
		(drill 0.4064)
		(layers "F.Cu" "B.Cu")
		(net "GND")
	)
	(via
		(at 117.982746 -89.6747)
		(size 0.7112)
		(drill 0.4064)
		(layers "F.Cu" "B.Cu")
		(net "GND")
	)
	(via
		(at 107.314746 -212.4837)
		(size 0.7112)
		(drill 0.4064)
		(layers "F.Cu" "B.Cu")
		(net "GND")
	)
	(via
		(at 211.200746 -300.1137)
		(size 0.7112)
		(drill 0.4064)
		(layers "F.Cu" "B.Cu")
		(net "GND")
	)
	(via
		(at 205.460346 -431.4063)
		(size 0.7112)
		(drill 0.4064)
		(layers "F.Cu" "B.Cu")
		(net "GND")
	)
	(via
		(at 72.796146 -455.1299)
		(size 0.7112)
		(drill 0.4064)
		(layers "F.Cu" "B.Cu")
		(net "GND")
	)
	(via
		(at 49.656746 -317.7667)
		(size 0.7112)
		(drill 0.4064)
		(layers "F.Cu" "B.Cu")
		(net "GND")
	)
	(via
		(at 130.936746 -451.8787)
		(size 0.7112)
		(drill 0.4064)
		(layers "F.Cu" "B.Cu")
		(net "GND")
	)
	(via
		(at 157.860746 -118.5037)
		(size 0.7112)
		(drill 0.4064)
		(layers "F.Cu" "B.Cu")
		(net "GND")
	)
	(via
		(at 111.073946 -189.1411)
		(size 0.7112)
		(drill 0.4064)
		(layers "F.Cu" "B.Cu")
		(net "GND")
	)
	(via
		(at 52.1462 -129.0574)
		(size 0.7112)
		(drill 0.4064)
		(layers "F.Cu" "B.Cu")
		(net "GND")
	)
	(via
		(at 71.500746 -224.4217)
		(size 0.7112)
		(drill 0.4064)
		(layers "F.Cu" "B.Cu")
		(net "GND")
	)
	(via
		(at 72.008746 -62.2427)
		(size 0.7112)
		(drill 0.4064)
		(layers "F.Cu" "B.Cu")
		(net "GND")
	)
	(via
		(at 172.287946 -248.5009)
		(size 0.7112)
		(drill 0.4064)
		(layers "F.Cu" "B.Cu")
		(net "GND")
	)
	(via
		(at 35.940746 -481.576888)
		(size 0.7112)
		(drill 0.4064)
		(layers "F.Cu" "B.Cu")
		(net "GND")
	)
	(via
		(at 80.695546 -267.8811)
		(size 0.7112)
		(drill 0.4064)
		(layers "F.Cu" "B.Cu")
		(net "GND")
	)
	(via
		(at 71.399146 -239.6617)
		(size 0.7112)
		(drill 0.4064)
		(layers "F.Cu" "B.Cu")
		(net "GND")
	)
	(via
		(at 41.529 -504.825)
		(size 0.7112)
		(drill 0.4064)
		(layers "F.Cu" "B.Cu")
		(net "GND")
	)
	(via
		(at 181.254146 -137.6807)
		(size 0.7112)
		(drill 0.4064)
		(layers "F.Cu" "B.Cu")
		(net "GND")
	)
	(via
		(at 75.564746 -139.9667)
		(size 0.7112)
		(drill 0.4064)
		(layers "F.Cu" "B.Cu")
		(net "GND")
	)
	(via
		(at 80.01 -191.643)
		(size 0.7112)
		(drill 0.4064)
		(layers "F.Cu" "B.Cu")
		(net "GND")
	)
	(via
		(at 149.224746 -468.5157)
		(size 0.7112)
		(drill 0.3556)
		(layers "F.Cu" "B.Cu")
		(net "GND")
	)
	(via
		(at 31.5722 -42.6212)
		(size 0.7112)
		(drill 0.4064)
		(layers "F.Cu" "B.Cu")
		(net "GND")
	)
	(via
		(at 2.311146 -477.9137)
		(size 0.7112)
		(drill 0.4064)
		(layers "F.Cu" "B.Cu")
		(net "GND")
	)
	(via
		(at 153.822146 -336.8929)
		(size 0.7112)
		(drill 0.4064)
		(layers "F.Cu" "B.Cu")
		(net "GND")
	)
	(via
		(at 199.771 -174.2694)
		(size 0.7112)
		(drill 0.4064)
		(layers "F.Cu" "B.Cu")
		(net "GND")
	)
	(via
		(at 225.0948 -79.736696)
		(size 0.5588)
		(drill 0.3048)
		(layers "F.Cu" "B.Cu")
		(net "GND")
	)
	(via
		(at 246.506746 -219.0115)
		(size 0.7112)
		(drill 0.4064)
		(layers "F.Cu" "B.Cu")
		(net "GND")
	)
	(via
		(at 220.827346 -312.2549)
		(size 0.7112)
		(drill 0.4064)
		(layers "F.Cu" "B.Cu")
		(net "GND")
	)
	(via
		(at 135.762746 -170.7007)
		(size 0.7112)
		(drill 0.4064)
		(layers "F.Cu" "B.Cu")
		(net "GND")
	)
	(via
		(at 5.943346 -128.978914)
		(size 0.5588)
		(drill 0.3048)
		(layers "F.Cu" "B.Cu")
		(net "GND")
	)
	(via
		(at 20.32 -276.987)
		(size 0.5588)
		(drill 0.3048)
		(layers "F.Cu" "B.Cu")
		(net "GND")
	)
	(via
		(at 2.107946 -335.2927)
		(size 0.7112)
		(drill 0.4064)
		(layers "F.Cu" "B.Cu")
		(net "GND")
	)
	(via
		(at 83.0834 -499.483888)
		(size 0.5588)
		(drill 0.3048)
		(layers "F.Cu" "B.Cu")
		(net "GND")
	)
	(via
		(at 202.692 -174.3456)
		(size 0.7112)
		(drill 0.4064)
		(layers "F.Cu" "B.Cu")
		(net "GND")
	)
	(via
		(at 165.252146 -300.2407)
		(size 0.7112)
		(drill 0.4064)
		(layers "F.Cu" "B.Cu")
		(net "GND")
	)
	(via
		(at 92.455746 -39.0017)
		(size 0.7112)
		(drill 0.4064)
		(layers "F.Cu" "B.Cu")
		(net "GND")
	)
	(via
		(at 178.460146 -439.5597)
		(size 0.7112)
		(drill 0.4064)
		(layers "F.Cu" "B.Cu")
		(net "GND")
	)
	(via
		(at 57.708546 -201.9427)
		(size 0.7112)
		(drill 0.4064)
		(layers "F.Cu" "B.Cu")
		(net "GND")
	)
	(via
		(at 165.734746 -411.1117)
		(size 0.7112)
		(drill 0.4064)
		(layers "F.Cu" "B.Cu")
		(net "GND")
	)
	(via
		(at 258.952746 -241.6937)
		(size 0.7112)
		(drill 0.4064)
		(layers "F.Cu" "B.Cu")
		(net "GND")
	)
	(via
		(at 224.637346 -112.6363)
		(size 0.7112)
		(drill 0.4064)
		(layers "F.Cu" "B.Cu")
		(net "GND")
	)
	(via
		(at 115.951 -504.825)
		(size 0.7112)
		(drill 0.4064)
		(layers "F.Cu" "B.Cu")
		(net "GND")
	)
	(via
		(at 107.314746 -217.3097)
		(size 0.7112)
		(drill 0.4064)
		(layers "F.Cu" "B.Cu")
		(net "GND")
	)
	(via
		(at 124.713746 -104.7877)
		(size 0.7112)
		(drill 0.4064)
		(layers "F.Cu" "B.Cu")
		(net "GND")
	)
	(via
		(at 128.218946 -497.4717)
		(size 0.7112)
		(drill 0.4064)
		(layers "F.Cu" "B.Cu")
		(net "GND")
	)
	(via
		(at 128.472946 -487.9467)
		(size 0.7112)
		(drill 0.4064)
		(layers "F.Cu" "B.Cu")
		(net "GND")
	)
	(via
		(at 250.443746 -140.7287)
		(size 0.7112)
		(drill 0.4064)
		(layers "F.Cu" "B.Cu")
		(net "GND")
	)
	(via
		(at 64.058546 -455.4347)
		(size 0.7112)
		(drill 0.4064)
		(layers "F.Cu" "B.Cu")
		(net "GND")
	)
	(via
		(at 39.141654 -113.1697)
		(size 0.5588)
		(drill 0.3048)
		(layers "F.Cu" "B.Cu")
		(net "GND")
	)
	(via
		(at 116.763546 -372.8847)
		(size 0.7112)
		(drill 0.4064)
		(layers "F.Cu" "B.Cu")
		(net "GND")
	)
	(via
		(at 132.816346 -16.3449)
		(size 0.7112)
		(drill 0.4064)
		(layers "F.Cu" "B.Cu")
		(net "GND")
	)
	(via
		(at 199.008746 -484.3907)
		(size 0.7112)
		(drill 0.4064)
		(layers "F.Cu" "B.Cu")
		(net "GND")
	)
	(via
		(at 183.108346 -180.9115)
		(size 0.7112)
		(drill 0.4064)
		(layers "F.Cu" "B.Cu")
		(net "GND")
	)
	(via
		(at 122.046746 -471.2843)
		(size 0.7112)
		(drill 0.4064)
		(layers "F.Cu" "B.Cu")
		(net "GND")
	)
	(via
		(at 213.867746 -345.0717)
		(size 0.7112)
		(drill 0.4064)
		(layers "F.Cu" "B.Cu")
		(net "GND")
	)
	(via
		(at 200.659746 -148.4757)
		(size 0.7112)
		(drill 0.4064)
		(layers "F.Cu" "B.Cu")
		(net "GND")
	)
	(via
		(at 218.439746 -194.9577)
		(size 0.7112)
		(drill 0.4064)
		(layers "F.Cu" "B.Cu")
		(net "GND")
	)
	(via
		(at 128.218946 -492.6457)
		(size 0.7112)
		(drill 0.4064)
		(layers "F.Cu" "B.Cu")
		(net "GND")
	)
	(via
		(at 179.323746 -216.1667)
		(size 0.7112)
		(drill 0.4064)
		(layers "F.Cu" "B.Cu")
		(net "GND")
	)
	(via
		(at 129.5146 -439.8518)
		(size 0.7112)
		(drill 0.3556)
		(layers "F.Cu" "B.Cu")
		(net "GND")
	)
	(via
		(at 186.181746 -474.6117)
		(size 0.7112)
		(drill 0.4064)
		(layers "F.Cu" "B.Cu")
		(net "GND")
	)
	(via
		(at 221.995746 -123.0757)
		(size 0.7112)
		(drill 0.3556)
		(layers "F.Cu" "B.Cu")
		(net "GND")
	)
	(via
		(at 155.8798 -128.1684)
		(size 0.7112)
		(drill 0.4064)
		(layers "F.Cu" "B.Cu")
		(net "GND")
	)
	(via
		(at 235.203746 -310.2737)
		(size 0.7112)
		(drill 0.4064)
		(layers "F.Cu" "B.Cu")
		(net "GND")
	)
	(via
		(at 158.749746 -31.3817)
		(size 0.7112)
		(drill 0.4064)
		(layers "F.Cu" "B.Cu")
		(net "GND")
	)
	(via
		(at 79.374746 -325.2089)
		(size 0.7112)
		(drill 0.4064)
		(layers "F.Cu" "B.Cu")
		(net "GND")
	)
	(via
		(at 184.073546 -247.9675)
		(size 0.7112)
		(drill 0.4064)
		(layers "F.Cu" "B.Cu")
		(net "GND")
	)
	(via
		(at 252.602746 -199.2757)
		(size 0.7112)
		(drill 0.4064)
		(layers "F.Cu" "B.Cu")
		(net "GND")
	)
	(via
		(at 82.539586 -194.7545)
		(size 0.5588)
		(drill 0.3048)
		(layers "F.Cu" "B.Cu")
		(net "GND")
	)
	(via
		(at 87.223346 -40.9829)
		(size 0.7112)
		(drill 0.4064)
		(layers "F.Cu" "B.Cu")
		(net "GND")
	)
	(via
		(at 230.530146 -490.2327)
		(size 0.7112)
		(drill 0.4064)
		(layers "F.Cu" "B.Cu")
		(net "GND")
	)
	(via
		(at 160.527746 -254.3937)
		(size 0.7112)
		(drill 0.4064)
		(layers "F.Cu" "B.Cu")
		(net "GND")
	)
	(via
		(at 181.508146 -389.6233)
		(size 0.7112)
		(drill 0.4064)
		(layers "F.Cu" "B.Cu")
		(net "GND")
	)
	(via
		(at 19.558508 -241.828066)
		(size 0.7112)
		(drill 0.4064)
		(layers "F.Cu" "B.Cu")
		(net "GND")
	)
	(via
		(at 259.333746 -108.3437)
		(size 0.7112)
		(drill 0.4064)
		(layers "F.Cu" "B.Cu")
		(net "GND")
	)
	(via
		(at 242.772946 -495.7953)
		(size 0.7112)
		(drill 0.4064)
		(layers "F.Cu" "B.Cu")
		(net "GND")
	)
	(via
		(at 41.275 -158.3436)
		(size 0.7112)
		(drill 0.4064)
		(layers "F.Cu" "B.Cu")
		(net "GND")
	)
	(via
		(at 158.876746 -438.1627)
		(size 0.7112)
		(drill 0.4064)
		(layers "F.Cu" "B.Cu")
		(net "GND")
	)
	(via
		(at 134.873746 -96.9137)
		(size 0.7112)
		(drill 0.4064)
		(layers "F.Cu" "B.Cu")
		(net "GND")
	)
	(via
		(at 98.678746 -490.9693)
		(size 0.7112)
		(drill 0.4064)
		(layers "F.Cu" "B.Cu")
		(net "GND")
	)
	(via
		(at 130.047746 -283.3497)
		(size 0.7112)
		(drill 0.4064)
		(layers "F.Cu" "B.Cu")
		(net "GND")
	)
	(via
		(at 52.907946 -204.5589)
		(size 0.7112)
		(drill 0.4064)
		(layers "F.Cu" "B.Cu")
		(net "GND")
	)
	(via
		(at 61.6966 -320.802)
		(size 0.7112)
		(drill 0.4064)
		(layers "F.Cu" "B.Cu")
		(net "GND")
	)
	(via
		(at 259.333746 -485.7877)
		(size 0.7112)
		(drill 0.4064)
		(layers "F.Cu" "B.Cu")
		(net "GND")
	)
	(via
		(at 108.838746 -336.6389)
		(size 0.7112)
		(drill 0.4064)
		(layers "F.Cu" "B.Cu")
		(net "GND")
	)
	(via
		(at 222.452946 -102.9335)
		(size 0.7112)
		(drill 0.4064)
		(layers "F.Cu" "B.Cu")
		(net "GND")
	)
	(via
		(at 233.781346 -225.2599)
		(size 0.7112)
		(drill 0.4064)
		(layers "F.Cu" "B.Cu")
		(net "GND")
	)
	(via
		(at 235.076746 -288.4297)
		(size 0.7112)
		(drill 0.4064)
		(layers "F.Cu" "B.Cu")
		(net "GND")
	)
	(via
		(at 34.8234 -275.5392)
		(size 0.5588)
		(drill 0.3048)
		(layers "F.Cu" "B.Cu")
		(net "GND")
	)
	(via
		(at 46.227746 -154.8257)
		(size 0.7112)
		(drill 0.4064)
		(layers "F.Cu" "B.Cu")
		(net "GND")
	)
	(via
		(at 220.090746 -409.4607)
		(size 0.7112)
		(drill 0.4064)
		(layers "F.Cu" "B.Cu")
		(net "GND")
	)
	(via
		(at 198.881746 -177.6857)
		(size 0.7112)
		(drill 0.4064)
		(layers "F.Cu" "B.Cu")
		(net "GND")
	)
	(via
		(at 177.291746 -1.7907)
		(size 0.7112)
		(drill 0.4064)
		(layers "F.Cu" "B.Cu")
		(net "GND")
	)
	(via
		(at 94.767146 -369.9637)
		(size 0.7112)
		(drill 0.4064)
		(layers "F.Cu" "B.Cu")
		(net "GND")
	)
	(via
		(at 241.477546 -289.4965)
		(size 0.7112)
		(drill 0.4064)
		(layers "F.Cu" "B.Cu")
		(net "GND")
	)
	(via
		(at 208.597246 -454.9775)
		(size 0.5588)
		(drill 0.3048)
		(layers "F.Cu" "B.Cu")
		(net "GND")
	)
	(via
		(at 234.162346 -197.3199)
		(size 0.7112)
		(drill 0.4064)
		(layers "F.Cu" "B.Cu")
		(net "GND")
	)
	(via
		(at 155.447746 -407.3017)
		(size 0.7112)
		(drill 0.4064)
		(layers "F.Cu" "B.Cu")
		(net "GND")
	)
	(via
		(at 89.941146 -44.5389)
		(size 0.7112)
		(drill 0.4064)
		(layers "F.Cu" "B.Cu")
		(net "GND")
	)
	(via
		(at 164.337746 -148.4757)
		(size 0.7112)
		(drill 0.4064)
		(layers "F.Cu" "B.Cu")
		(net "GND")
	)
	(via
		(at 24.430736 -42.18051)
		(size 0.7112)
		(drill 0.4064)
		(layers "F.Cu" "B.Cu")
		(net "GND")
	)
	(via
		(at 203.5302 -378.206)
		(size 0.7112)
		(drill 0.4064)
		(layers "F.Cu" "B.Cu")
		(net "GND")
	)
	(via
		(at 250.443746 -132.6007)
		(size 0.7112)
		(drill 0.4064)
		(layers "F.Cu" "B.Cu")
		(net "GND")
	)
	(via
		(at 163.1696 -457.2254)
		(size 0.7112)
		(drill 0.4064)
		(layers "F.Cu" "B.Cu")
		(net "GND")
	)
	(via
		(at 84.670646 -322.707)
		(size 0.7112)
		(drill 0.4064)
		(layers "F.Cu" "B.Cu")
		(net "GND")
	)
	(via
		(at 81.533746 -253.3015)
		(size 0.7112)
		(drill 0.4064)
		(layers "F.Cu" "B.Cu")
		(net "GND")
	)
	(via
		(at 78.028546 -52.2097)
		(size 0.7112)
		(drill 0.4064)
		(layers "F.Cu" "B.Cu")
		(net "GND")
	)
	(via
		(at 228.853746 -170.1927)
		(size 0.7112)
		(drill 0.4064)
		(layers "F.Cu" "B.Cu")
		(net "GND")
	)
	(via
		(at 62.229746 -445.7827)
		(size 0.7112)
		(drill 0.4064)
		(layers "F.Cu" "B.Cu")
		(net "GND")
	)
	(via
		(at 88.315546 -500.9515)
		(size 0.7112)
		(drill 0.4064)
		(layers "F.Cu" "B.Cu")
		(net "GND")
	)
	(via
		(at 64.109346 -212.9155)
		(size 0.7112)
		(drill 0.4064)
		(layers "F.Cu" "B.Cu")
		(net "GND")
	)
	(via
		(at 158.876746 -46.4947)
		(size 0.7112)
		(drill 0.4064)
		(layers "F.Cu" "B.Cu")
		(net "GND")
	)
	(via
		(at 155.295346 -265.5951)
		(size 0.7112)
		(drill 0.4064)
		(layers "F.Cu" "B.Cu")
		(net "GND")
	)
	(via
		(at 221.098872 -261.677658)
		(size 0.7112)
		(drill 0.4064)
		(layers "F.Cu" "B.Cu")
		(net "GND")
	)
	(via
		(at 210.819746 -504.8377)
		(size 0.7112)
		(drill 0.4064)
		(layers "F.Cu" "B.Cu")
		(net "GND")
	)
	(via
		(at 259.333746 -167.1447)
		(size 0.7112)
		(drill 0.4064)
		(layers "F.Cu" "B.Cu")
		(net "GND")
	)
	(via
		(at 195.452746 -383.2987)
		(size 0.7112)
		(drill 0.4064)
		(layers "F.Cu" "B.Cu")
		(net "GND")
	)
	(via
		(at 259.588 -3.937)
		(size 0.7112)
		(drill 0.4064)
		(layers "F.Cu" "B.Cu")
		(net "GND")
	)
	(via
		(at 120.954546 -481.6983)
		(size 0.7112)
		(drill 0.4064)
		(layers "F.Cu" "B.Cu")
		(net "GND")
	)
	(via
		(at 31.241746 -479.8187)
		(size 0.7112)
		(drill 0.4064)
		(layers "F.Cu" "B.Cu")
		(net "GND")
	)
	(via
		(at 157.022546 -322.1355)
		(size 0.7112)
		(drill 0.4064)
		(layers "F.Cu" "B.Cu")
		(net "GND")
	)
	(via
		(at 191.642746 -143.4211)
		(size 0.7112)
		(drill 0.4064)
		(layers "F.Cu" "B.Cu")
		(net "GND")
	)
	(via
		(at 39.98976 -386.19684)
		(size 0.5588)
		(drill 0.3048)
		(layers "F.Cu" "B.Cu")
		(net "GND")
	)
	(via
		(at 79.4512 -372.7196)
		(size 0.7112)
		(drill 0.4064)
		(layers "F.Cu" "B.Cu")
		(net "GND")
	)
	(via
		(at 134.111746 -307.9877)
		(size 0.7112)
		(drill 0.4064)
		(layers "F.Cu" "B.Cu")
		(net "GND")
	)
	(via
		(at 189.864746 -440.5249)
		(size 0.7112)
		(drill 0.4064)
		(layers "F.Cu" "B.Cu")
		(net "GND")
	)
	(via
		(at 140.233146 -406.8953)
		(size 0.7112)
		(drill 0.4064)
		(layers "F.Cu" "B.Cu")
		(net "GND")
	)
	(via
		(at 252.348746 -222.2627)
		(size 0.7112)
		(drill 0.4064)
		(layers "F.Cu" "B.Cu")
		(net "GND")
	)
	(via
		(at 17.271746 -200.7616)
		(size 0.7112)
		(drill 0.4064)
		(layers "F.Cu" "B.Cu")
		(net "GND")
	)
	(via
		(at 180.847746 -78.1177)
		(size 0.7112)
		(drill 0.4064)
		(layers "F.Cu" "B.Cu")
		(net "GND")
	)
	(via
		(at 110.997746 -290.2077)
		(size 0.7112)
		(drill 0.4064)
		(layers "F.Cu" "B.Cu")
		(net "GND")
	)
	(via
		(at 11.683746 -500.7483)
		(size 0.5588)
		(drill 0.3048)
		(layers "F.Cu" "B.Cu")
		(net "GND")
	)
	(via
		(at 82.702146 -209.2833)
		(size 0.7112)
		(drill 0.4064)
		(layers "F.Cu" "B.Cu")
		(net "GND")
	)
	(via
		(at 209.168746 -430.0347)
		(size 0.7112)
		(drill 0.4064)
		(layers "F.Cu" "B.Cu")
		(net "GND")
	)
	(via
		(at 220.827346 -315.9379)
		(size 0.7112)
		(drill 0.4064)
		(layers "F.Cu" "B.Cu")
		(net "GND")
	)
	(via
		(at 77.215746 -437.4007)
		(size 0.7112)
		(drill 0.4064)
		(layers "F.Cu" "B.Cu")
		(net "GND")
	)
	(via
		(at 202.564746 -20.5867)
		(size 0.7112)
		(drill 0.4064)
		(layers "F.Cu" "B.Cu")
		(net "GND")
	)
	(via
		(at 144.551146 -28.5877)
		(size 0.7112)
		(drill 0.4064)
		(layers "F.Cu" "B.Cu")
		(net "GND")
	)
	(via
		(at 23.0886 -1.4732)
		(size 0.7112)
		(drill 0.4064)
		(layers "F.Cu" "B.Cu")
		(net "GND")
	)
	(via
		(at 164.286946 -489.3183)
		(size 0.7112)
		(drill 0.4064)
		(layers "F.Cu" "B.Cu")
		(net "GND")
	)
	(via
		(at 193.293746 -278.2697)
		(size 0.7112)
		(drill 0.4064)
		(layers "F.Cu" "B.Cu")
		(net "GND")
	)
	(via
		(at 51.815746 -239.6109)
		(size 0.7112)
		(drill 0.4064)
		(layers "F.Cu" "B.Cu")
		(net "GND")
	)
	(via
		(at 95.198946 -378.7775)
		(size 0.7112)
		(drill 0.4064)
		(layers "F.Cu" "B.Cu")
		(net "GND")
	)
	(via
		(at 62.484 -15.5702)
		(size 0.7112)
		(drill 0.4064)
		(layers "F.Cu" "B.Cu")
		(net "GND")
	)
	(via
		(at 71.373746 -38.6207)
		(size 0.7112)
		(drill 0.4064)
		(layers "F.Cu" "B.Cu")
		(net "GND")
	)
	(via
		(at 192.3796 -174.3202)
		(size 0.7112)
		(drill 0.4064)
		(layers "F.Cu" "B.Cu")
		(net "GND")
	)
	(via
		(at 98.881946 -41.0591)
		(size 0.7112)
		(drill 0.4064)
		(layers "F.Cu" "B.Cu")
		(net "GND")
	)
	(via
		(at 164.947346 -417.8173)
		(size 0.7112)
		(drill 0.4064)
		(layers "F.Cu" "B.Cu")
		(net "GND")
	)
	(via
		(at 110.819946 -502.2215)
		(size 0.7112)
		(drill 0.4064)
		(layers "F.Cu" "B.Cu")
		(net "GND")
	)
	(via
		(at 62.458346 -252.7935)
		(size 0.7112)
		(drill 0.4064)
		(layers "F.Cu" "B.Cu")
		(net "GND")
	)
	(via
		(at 215.2904 -165.5064)
		(size 0.5588)
		(drill 0.3048)
		(layers "F.Cu" "B.Cu")
		(net "GND")
	)
	(via
		(at 82.549746 -105.2957)
		(size 0.7112)
		(drill 0.4064)
		(layers "F.Cu" "B.Cu")
		(net "GND")
	)
	(via
		(at 6.527546 -232.7021)
		(size 0.7112)
		(drill 0.4064)
		(layers "F.Cu" "B.Cu")
		(net "GND")
	)
	(via
		(at 126.720346 -357.7209)
		(size 0.7112)
		(drill 0.4064)
		(layers "F.Cu" "B.Cu")
		(net "GND")
	)
	(via
		(at 54.685946 -460.7433)
		(size 0.7112)
		(drill 0.4064)
		(layers "F.Cu" "B.Cu")
		(net "GND")
	)
	(via
		(at 2.031746 -321.1957)
		(size 0.7112)
		(drill 0.4064)
		(layers "F.Cu" "B.Cu")
		(net "GND")
	)
	(via
		(at 164.032946 -207.4291)
		(size 0.7112)
		(drill 0.4064)
		(layers "F.Cu" "B.Cu")
		(net "GND")
	)
	(via
		(at 63.296546 -442.7601)
		(size 0.7112)
		(drill 0.4064)
		(layers "F.Cu" "B.Cu")
		(net "GND")
	)
	(via
		(at 76.377546 -311.7469)
		(size 0.7112)
		(drill 0.4064)
		(layers "F.Cu" "B.Cu")
		(net "GND")
	)
	(via
		(at 55.117746 -504.8377)
		(size 0.7112)
		(drill 0.4064)
		(layers "F.Cu" "B.Cu")
		(net "GND")
	)
	(via
		(at 128.142746 -151.9047)
		(size 0.7112)
		(drill 0.4064)
		(layers "F.Cu" "B.Cu")
		(net "GND")
	)
	(via
		(at 8.4836 -357.6574)
		(size 0.5588)
		(drill 0.3048)
		(layers "F.Cu" "B.Cu")
		(net "GND")
	)
	(via
		(at 116.661946 -492.4679)
		(size 0.7112)
		(drill 0.4064)
		(layers "F.Cu" "B.Cu")
		(net "GND")
	)
	(via
		(at 195.452746 -279.6667)
		(size 0.7112)
		(drill 0.4064)
		(layers "F.Cu" "B.Cu")
		(net "GND")
	)
	(via
		(at 15.112746 -27.4447)
		(size 0.7112)
		(drill 0.4064)
		(layers "F.Cu" "B.Cu")
		(net "GND")
	)
	(via
		(at 213.613746 -500.5197)
		(size 0.7112)
		(drill 0.4064)
		(layers "F.Cu" "B.Cu")
		(net "GND")
	)
	(via
		(at 174.116746 -497.5987)
		(size 0.7112)
		(drill 0.4064)
		(layers "F.Cu" "B.Cu")
		(net "GND")
	)
	(via
		(at 185.673746 -229.3239)
		(size 0.7112)
		(drill 0.4064)
		(layers "F.Cu" "B.Cu")
		(net "GND")
	)
	(via
		(at 255.523746 -161.6329)
		(size 0.7112)
		(drill 0.4064)
		(layers "F.Cu" "B.Cu")
		(net "GND")
	)
	(via
		(at 121.741946 -75.5015)
		(size 0.7112)
		(drill 0.4064)
		(layers "F.Cu" "B.Cu")
		(net "GND")
	)
	(via
		(at 6.019546 -170.9801)
		(size 0.5588)
		(drill 0.3048)
		(layers "F.Cu" "B.Cu")
		(net "GND")
	)
	(via
		(at 35.36569 -371.087142)
		(size 0.5588)
		(drill 0.3048)
		(layers "F.Cu" "B.Cu")
		(net "GND")
	)
	(via
		(at 145.033746 -1.5367)
		(size 0.7112)
		(drill 0.4064)
		(layers "F.Cu" "B.Cu")
		(net "GND")
	)
	(via
		(at 80.466946 -420.9923)
		(size 0.7112)
		(drill 0.4064)
		(layers "F.Cu" "B.Cu")
		(net "GND")
	)
	(via
		(at 47.243746 -443.4967)
		(size 0.7112)
		(drill 0.4064)
		(layers "F.Cu" "B.Cu")
		(net "GND")
	)
	(via
		(at 211.200746 -336.5373)
		(size 0.7112)
		(drill 0.4064)
		(layers "F.Cu" "B.Cu")
		(net "GND")
	)
	(via
		(at 239.724946 -341.1093)
		(size 0.7112)
		(drill 0.4064)
		(layers "F.Cu" "B.Cu")
		(net "GND")
	)
	(via
		(at 174.523146 -232.4989)
		(size 0.7112)
		(drill 0.4064)
		(layers "F.Cu" "B.Cu")
		(net "GND")
	)
	(via
		(at 68.452746 -164.7317)
		(size 0.7112)
		(drill 0.4064)
		(layers "F.Cu" "B.Cu")
		(net "GND")
	)
	(via
		(at 147.141946 -330.3905)
		(size 0.7112)
		(drill 0.4064)
		(layers "F.Cu" "B.Cu")
		(net "GND")
	)
	(via
		(at 135.5852 -400.177)
		(size 0.7112)
		(drill 0.4064)
		(layers "F.Cu" "B.Cu")
		(net "GND")
	)
	(via
		(at 216.915746 -112.6617)
		(size 0.7112)
		(drill 0.4064)
		(layers "F.Cu" "B.Cu")
		(net "GND")
	)
	(via
		(at 79.781146 -482.9175)
		(size 0.7112)
		(drill 0.4064)
		(layers "F.Cu" "B.Cu")
		(net "GND")
	)
	(via
		(at 220.887036 -464.026504)
		(size 0.7112)
		(drill 0.4064)
		(layers "F.Cu" "B.Cu")
		(net "GND")
	)
	(via
		(at 183.819546 -242.6335)
		(size 0.7112)
		(drill 0.4064)
		(layers "F.Cu" "B.Cu")
		(net "GND")
	)
	(via
		(at 117.855746 -450.1007)
		(size 0.7112)
		(drill 0.4064)
		(layers "F.Cu" "B.Cu")
		(net "GND")
	)
	(via
		(at 153.745946 -168.0845)
		(size 0.7112)
		(drill 0.4064)
		(layers "F.Cu" "B.Cu")
		(net "GND")
	)
	(via
		(at 114.045746 -64.9097)
		(size 0.7112)
		(drill 0.4064)
		(layers "F.Cu" "B.Cu")
		(net "GND")
	)
	(via
		(at 153.390346 -294.0939)
		(size 0.7112)
		(drill 0.4064)
		(layers "F.Cu" "B.Cu")
		(net "GND")
	)
	(via
		(at 75.234546 -144.4117)
		(size 0.7112)
		(drill 0.4064)
		(layers "F.Cu" "B.Cu")
		(net "GND")
	)
	(via
		(at 116.661946 -499.5799)
		(size 0.7112)
		(drill 0.4064)
		(layers "F.Cu" "B.Cu")
		(net "GND")
	)
	(via
		(at 178.561746 -174.7647)
		(size 0.7112)
		(drill 0.4064)
		(layers "F.Cu" "B.Cu")
		(net "GND")
	)
	(via
		(at 56.2102 -275.142452)
		(size 0.5588)
		(drill 0.3048)
		(layers "F.Cu" "B.Cu")
		(net "GND")
	)
	(via
		(at 164.845746 -178.3969)
		(size 0.7112)
		(drill 0.4064)
		(layers "F.Cu" "B.Cu")
		(net "GND")
	)
	(via
		(at 78.231746 -290.0807)
		(size 0.7112)
		(drill 0.4064)
		(layers "F.Cu" "B.Cu")
		(net "GND")
	)
	(via
		(at 84.327746 -164.2237)
		(size 0.7112)
		(drill 0.4064)
		(layers "F.Cu" "B.Cu")
		(net "GND")
	)
	(via
		(at 5.968746 -415.0487)
		(size 0.5588)
		(drill 0.3048)
		(layers "F.Cu" "B.Cu")
		(net "GND")
	)
	(via
		(at 195.833746 -462.4197)
		(size 0.5588)
		(drill 0.3048)
		(layers "F.Cu" "B.Cu")
		(net "GND")
	)
	(via
		(at 241.121946 -248.2723)
		(size 0.7112)
		(drill 0.4064)
		(layers "F.Cu" "B.Cu")
		(net "GND")
	)
	(via
		(at 58.673746 -390.0297)
		(size 0.7112)
		(drill 0.4064)
		(layers "F.Cu" "B.Cu")
		(net "GND")
	)
	(via
		(at 135.762746 -162.5727)
		(size 0.7112)
		(drill 0.4064)
		(layers "F.Cu" "B.Cu")
		(net "GND")
	)
	(via
		(at 227.329746 -464.5787)
		(size 0.7112)
		(drill 0.4064)
		(layers "F.Cu" "B.Cu")
		(net "GND")
	)
	(via
		(at 213.867746 -340.6267)
		(size 0.7112)
		(drill 0.4064)
		(layers "F.Cu" "B.Cu")
		(net "GND")
	)
	(via
		(at 45.186346 -50.6095)
		(size 0.7112)
		(drill 0.4064)
		(layers "F.Cu" "B.Cu")
		(net "GND")
	)
	(via
		(at 208.914746 -461.051656)
		(size 0.5588)
		(drill 0.3048)
		(layers "F.Cu" "B.Cu")
		(net "GND")
	)
	(via
		(at 5.841746 -423.0497)
		(size 0.5588)
		(drill 0.3048)
		(layers "F.Cu" "B.Cu")
		(net "GND")
	)
	(via
		(at 112.140746 -446.5447)
		(size 0.7112)
		(drill 0.4064)
		(layers "F.Cu" "B.Cu")
		(net "GND")
	)
	(via
		(at 43.85564 -207.195674)
		(size 0.5588)
		(drill 0.3048)
		(layers "F.Cu" "B.Cu")
		(net "GND")
	)
	(via
		(at 244.3226 -386.6896)
		(size 0.7112)
		(drill 0.4064)
		(layers "F.Cu" "B.Cu")
		(net "GND")
	)
	(via
		(at 221.995746 -219.0877)
		(size 0.7112)
		(drill 0.4064)
		(layers "F.Cu" "B.Cu")
		(net "GND")
	)
	(via
		(at 173.049946 -401.1041)
		(size 0.7112)
		(drill 0.4064)
		(layers "F.Cu" "B.Cu")
		(net "GND")
	)
	(via
		(at 153.415746 -13.8049)
		(size 0.7112)
		(drill 0.4064)
		(layers "F.Cu" "B.Cu")
		(net "GND")
	)
	(via
		(at 177.723546 -36.0045)
		(size 0.7112)
		(drill 0.4064)
		(layers "F.Cu" "B.Cu")
		(net "GND")
	)
	(via
		(at 97.027746 -64.5287)
		(size 0.7112)
		(drill 0.4064)
		(layers "F.Cu" "B.Cu")
		(net "GND")
	)
	(via
		(at 245.491 -404.368)
		(size 0.7112)
		(drill 0.4064)
		(layers "F.Cu" "B.Cu")
		(net "GND")
	)
	(via
		(at 18.440146 -146.871944)
		(size 0.7112)
		(drill 0.4064)
		(layers "F.Cu" "B.Cu")
		(net "GND")
	)
	(via
		(at 120.954546 -483.9843)
		(size 0.7112)
		(drill 0.4064)
		(layers "F.Cu" "B.Cu")
		(net "GND")
	)
	(via
		(at 255.218946 -86.9823)
		(size 0.7112)
		(drill 0.4064)
		(layers "F.Cu" "B.Cu")
		(net "GND")
	)
	(via
		(at 111.124746 -77.9907)
		(size 0.7112)
		(drill 0.4064)
		(layers "F.Cu" "B.Cu")
		(net "GND")
	)
	(via
		(at 35.3314 -278.6634)
		(size 0.7112)
		(drill 0.4064)
		(layers "F.Cu" "B.Cu")
		(net "GND")
	)
	(via
		(at 212.724746 -35.1917)
		(size 0.7112)
		(drill 0.4064)
		(layers "F.Cu" "B.Cu")
		(net "GND")
	)
	(via
		(at 86.004146 -208.6991)
		(size 0.7112)
		(drill 0.4064)
		(layers "F.Cu" "B.Cu")
		(net "GND")
	)
	(via
		(at 122.249946 -460.0321)
		(size 0.7112)
		(drill 0.4064)
		(layers "F.Cu" "B.Cu")
		(net "GND")
	)
	(via
		(at 107.441746 -203.0857)
		(size 0.7112)
		(drill 0.4064)
		(layers "F.Cu" "B.Cu")
		(net "GND")
	)
	(via
		(at 204.850746 -353.1997)
		(size 0.7112)
		(drill 0.4064)
		(layers "F.Cu" "B.Cu")
		(net "GND")
	)
	(via
		(at 24.891746 -461.0227)
		(size 0.7112)
		(drill 0.4064)
		(layers "F.Cu" "B.Cu")
		(net "GND")
	)
	(via
		(at 236.981746 -90.3097)
		(size 0.7112)
		(drill 0.4064)
		(layers "F.Cu" "B.Cu")
		(net "GND")
	)
	(via
		(at 87.324946 -51.9557)
		(size 0.7112)
		(drill 0.4064)
		(layers "F.Cu" "B.Cu")
		(net "GND")
	)
	(via
		(at 123.1646 -100.2538)
		(size 0.7112)
		(drill 0.4064)
		(layers "F.Cu" "B.Cu")
		(net "GND")
	)
	(via
		(at 169.163746 -209.8167)
		(size 0.7112)
		(drill 0.4064)
		(layers "F.Cu" "B.Cu")
		(net "GND")
	)
	(via
		(at 80.113632 -305.476402)
		(size 0.7112)
		(drill 0.4064)
		(layers "F.Cu" "B.Cu")
		(net "GND")
	)
	(via
		(at 227.583746 -421.9575)
		(size 0.7112)
		(drill 0.4064)
		(layers "F.Cu" "B.Cu")
		(net "GND")
	)
	(via
		(at 159.206946 -363.8169)
		(size 0.7112)
		(drill 0.4064)
		(layers "F.Cu" "B.Cu")
		(net "GND")
	)
	(via
		(at 31.749746 -414.7947)
		(size 0.7112)
		(drill 0.4064)
		(layers "F.Cu" "B.Cu")
		(net "GND")
	)
	(via
		(at 15.76197 -142.6337)
		(size 0.7112)
		(drill 0.4064)
		(layers "F.Cu" "B.Cu")
		(net "GND")
	)
	(via
		(at 86.385146 -231.2289)
		(size 0.7112)
		(drill 0.4064)
		(layers "F.Cu" "B.Cu")
		(net "GND")
	)
	(via
		(at 129.336546 -421.7797)
		(size 0.7112)
		(drill 0.4064)
		(layers "F.Cu" "B.Cu")
		(net "GND")
	)
	(via
		(at 53.136546 -92.7227)
		(size 0.7112)
		(drill 0.4064)
		(layers "F.Cu" "B.Cu")
		(net "GND")
	)
	(via
		(at 6.157976 -427.194472)
		(size 0.5588)
		(drill 0.3048)
		(layers "F.Cu" "B.Cu")
		(net "GND")
	)
	(via
		(at 106.044746 -11.8237)
		(size 0.7112)
		(drill 0.4064)
		(layers "F.Cu" "B.Cu")
		(net "GND")
	)
	(via
		(at 53.3146 -277.7744)
		(size 0.7112)
		(drill 0.4064)
		(layers "F.Cu" "B.Cu")
		(net "GND")
	)
	(via
		(at 213.156546 -427.6217)
		(size 0.7112)
		(drill 0.4064)
		(layers "F.Cu" "B.Cu")
		(net "GND")
	)
	(via
		(at 190.474346 -101.2317)
		(size 0.7112)
		(drill 0.4064)
		(layers "F.Cu" "B.Cu")
		(net "GND")
	)
	(via
		(at 125.221746 -481.8507)
		(size 0.7112)
		(drill 0.4064)
		(layers "F.Cu" "B.Cu")
		(net "GND")
	)
	(via
		(at 59.0931 -379.3363)
		(size 0.5588)
		(drill 0.3048)
		(layers "F.Cu" "B.Cu")
		(net "GND")
	)
	(via
		(at 5.841746 -369.0747)
		(size 0.5588)
		(drill 0.3048)
		(layers "F.Cu" "B.Cu")
		(net "GND")
	)
	(via
		(at 137.261346 -351.0661)
		(size 0.7112)
		(drill 0.4064)
		(layers "F.Cu" "B.Cu")
		(net "GND")
	)
	(via
		(at 112.851946 -389.2931)
		(size 0.7112)
		(drill 0.4064)
		(layers "F.Cu" "B.Cu")
		(net "GND")
	)
	(via
		(at 111.124746 -18.1229)
		(size 0.7112)
		(drill 0.4064)
		(layers "F.Cu" "B.Cu")
		(net "GND")
	)
	(via
		(at 29.1846 -45.1866)
		(size 0.5588)
		(drill 0.3048)
		(layers "F.Cu" "B.Cu")
		(net "GND")
	)
	(via
		(at 247.142 -399.4912)
		(size 0.7112)
		(drill 0.4064)
		(layers "F.Cu" "B.Cu")
		(net "GND")
	)
	(via
		(at 42.4688 -474.472)
		(size 0.7112)
		(drill 0.4064)
		(layers "F.Cu" "B.Cu")
		(net "GND")
	)
	(via
		(at 215.899746 -500.5197)
		(size 0.7112)
		(drill 0.4064)
		(layers "F.Cu" "B.Cu")
		(net "GND")
	)
	(via
		(at 168.147746 -504.5837)
		(size 0.7112)
		(drill 0.4064)
		(layers "F.Cu" "B.Cu")
		(net "GND")
	)
	(via
		(at 86.562946 -130.0607)
		(size 0.7112)
		(drill 0.4064)
		(layers "F.Cu" "B.Cu")
		(net "GND")
	)
	(via
		(at 179.679346 -228.4857)
		(size 0.7112)
		(drill 0.4064)
		(layers "F.Cu" "B.Cu")
		(net "GND")
	)
	(via
		(at 129.539746 -170.8277)
		(size 0.7112)
		(drill 0.4064)
		(layers "F.Cu" "B.Cu")
		(net "GND")
	)
	(via
		(at 8.610346 -255.5113)
		(size 0.7112)
		(drill 0.4064)
		(layers "F.Cu" "B.Cu")
		(net "GND")
	)
	(via
		(at 39.750746 -225.2853)
		(size 0.7112)
		(drill 0.4064)
		(layers "F.Cu" "B.Cu")
		(net "GND")
	)
	(via
		(at 70.612 -361.188)
		(size 0.7112)
		(drill 0.4064)
		(layers "F.Cu" "B.Cu")
		(net "GND")
	)
	(via
		(at 116.915946 -485.4829)
		(size 0.7112)
		(drill 0.4064)
		(layers "F.Cu" "B.Cu")
		(net "GND")
	)
	(via
		(at 238.556546 -36.0807)
		(size 0.7112)
		(drill 0.4064)
		(layers "F.Cu" "B.Cu")
		(net "GND")
	)
	(via
		(at 27.544014 -234.87507)
		(size 0.5588)
		(drill 0.3048)
		(layers "F.Cu" "B.Cu")
		(net "GND")
	)
	(via
		(at 178.561746 -170.3197)
		(size 0.7112)
		(drill 0.4064)
		(layers "F.Cu" "B.Cu")
		(net "GND")
	)
	(via
		(at 126.999746 -41.7957)
		(size 0.7112)
		(drill 0.4064)
		(layers "F.Cu" "B.Cu")
		(net "GND")
	)
	(via
		(at 71.627746 -130.0607)
		(size 0.7112)
		(drill 0.4064)
		(layers "F.Cu" "B.Cu")
		(net "GND")
	)
	(via
		(at 77.825346 -259.2705)
		(size 0.7112)
		(drill 0.4064)
		(layers "F.Cu" "B.Cu")
		(net "GND")
	)
	(via
		(at 113.004346 -349.9993)
		(size 0.7112)
		(drill 0.4064)
		(layers "F.Cu" "B.Cu")
		(net "GND")
	)
	(via
		(at 234.035346 -207.0989)
		(size 0.7112)
		(drill 0.4064)
		(layers "F.Cu" "B.Cu")
		(net "GND")
	)
	(via
		(at 259.206746 -210.3247)
		(size 0.7112)
		(drill 0.4064)
		(layers "F.Cu" "B.Cu")
		(net "GND")
	)
	(via
		(at 215.645746 -294.1447)
		(size 0.7112)
		(drill 0.4064)
		(layers "F.Cu" "B.Cu")
		(net "GND")
	)
	(via
		(at 190.855346 -259.9817)
		(size 0.7112)
		(drill 0.4064)
		(layers "F.Cu" "B.Cu")
		(net "GND")
	)
	(via
		(at 113.715546 -427.4439)
		(size 0.7112)
		(drill 0.4064)
		(layers "F.Cu" "B.Cu")
		(net "GND")
	)
	(via
		(at 123.570746 -307.4797)
		(size 0.7112)
		(drill 0.4064)
		(layers "F.Cu" "B.Cu")
		(net "GND")
	)
	(via
		(at 185.800746 -148.9837)
		(size 0.7112)
		(drill 0.4064)
		(layers "F.Cu" "B.Cu")
		(net "GND")
	)
	(via
		(at 71.627746 -134.5057)
		(size 0.7112)
		(drill 0.4064)
		(layers "F.Cu" "B.Cu")
		(net "GND")
	)
	(via
		(at 52.628546 -480.7839)
		(size 0.7112)
		(drill 0.4064)
		(layers "F.Cu" "B.Cu")
		(net "GND")
	)
	(via
		(at 159.333946 -421.5257)
		(size 0.7112)
		(drill 0.4064)
		(layers "F.Cu" "B.Cu")
		(net "GND")
	)
	(via
		(at 199.771 -378.1044)
		(size 0.7112)
		(drill 0.4064)
		(layers "F.Cu" "B.Cu")
		(net "GND")
	)
	(via
		(at 243.9924 -407.4922)
		(size 0.7112)
		(drill 0.4064)
		(layers "F.Cu" "B.Cu")
		(net "GND")
	)
	(via
		(at 246.379746 -192.7225)
		(size 0.7112)
		(drill 0.4064)
		(layers "F.Cu" "B.Cu")
		(net "GND")
	)
	(via
		(at 144.398746 -279.7937)
		(size 0.7112)
		(drill 0.4064)
		(layers "F.Cu" "B.Cu")
		(net "GND")
	)
	(via
		(at 5.994146 -374.9929)
		(size 0.5588)
		(drill 0.3048)
		(layers "F.Cu" "B.Cu")
		(net "GND")
	)
	(via
		(at 128.752346 -233.6673)
		(size 0.7112)
		(drill 0.4064)
		(layers "F.Cu" "B.Cu")
		(net "GND")
	)
	(via
		(at 196.468746 -280.6827)
		(size 0.7112)
		(drill 0.4064)
		(layers "F.Cu" "B.Cu")
		(net "GND")
	)
	(via
		(at 168.655746 -214.5157)
		(size 0.7112)
		(drill 0.4064)
		(layers "F.Cu" "B.Cu")
		(net "GND")
	)
	(via
		(at 201.421746 -504.8377)
		(size 0.7112)
		(drill 0.4064)
		(layers "F.Cu" "B.Cu")
		(net "GND")
	)
	(via
		(at 59.435746 -253.2507)
		(size 0.7112)
		(drill 0.4064)
		(layers "F.Cu" "B.Cu")
		(net "GND")
	)
	(via
		(at 68.833746 -421.7797)
		(size 0.7112)
		(drill 0.4064)
		(layers "F.Cu" "B.Cu")
		(net "GND")
	)
	(via
		(at 139.547346 -328.6379)
		(size 0.7112)
		(drill 0.4064)
		(layers "F.Cu" "B.Cu")
		(net "GND")
	)
	(via
		(at 46.1518 -309.8546)
		(size 0.7112)
		(drill 0.4064)
		(layers "F.Cu" "B.Cu")
		(net "GND")
	)
	(via
		(at 33.476946 -51.2953)
		(size 0.7112)
		(drill 0.4064)
		(layers "F.Cu" "B.Cu")
		(net "GND")
	)
	(via
		(at 187.324746 -504.7107)
		(size 0.7112)
		(drill 0.4064)
		(layers "F.Cu" "B.Cu")
		(net "GND")
	)
	(via
		(at 166.242746 -348.7547)
		(size 0.7112)
		(drill 0.4064)
		(layers "F.Cu" "B.Cu")
		(net "GND")
	)
	(via
		(at 25.781 -343.408)
		(size 0.5588)
		(drill 0.3048)
		(layers "F.Cu" "B.Cu")
		(net "GND")
	)
	(via
		(at 163.956746 -499.1227)
		(size 0.7112)
		(drill 0.4064)
		(layers "F.Cu" "B.Cu")
		(net "GND")
	)
	(via
		(at 112.140746 -359.1687)
		(size 0.7112)
		(drill 0.4064)
		(layers "F.Cu" "B.Cu")
		(net "GND")
	)
	(via
		(at 259.206746 -117.7417)
		(size 0.7112)
		(drill 0.4064)
		(layers "F.Cu" "B.Cu")
		(net "GND")
	)
	(via
		(at 106.171746 -47.0027)
		(size 0.7112)
		(drill 0.4064)
		(layers "F.Cu" "B.Cu")
		(net "GND")
	)
	(via
		(at 41.516046 -132.4991)
		(size 0.5588)
		(drill 0.3048)
		(layers "F.Cu" "B.Cu")
		(net "GND")
	)
	(via
		(at 167.969946 -484.8987)
		(size 0.7112)
		(drill 0.4064)
		(layers "F.Cu" "B.Cu")
		(net "GND")
	)
	(via
		(at 127.126746 -23.8887)
		(size 0.7112)
		(drill 0.4064)
		(layers "F.Cu" "B.Cu")
		(net "GND")
	)
	(via
		(at 51.866546 -295.6179)
		(size 0.7112)
		(drill 0.4064)
		(layers "F.Cu" "B.Cu")
		(net "GND")
	)
	(via
		(at 170.941746 -331.0763)
		(size 0.7112)
		(drill 0.4064)
		(layers "F.Cu" "B.Cu")
		(net "GND")
	)
	(via
		(at 165.429946 -298.2341)
		(size 0.7112)
		(drill 0.4064)
		(layers "F.Cu" "B.Cu")
		(net "GND")
	)
	(via
		(at 171.449746 -288.2773)
		(size 0.7112)
		(drill 0.4064)
		(layers "F.Cu" "B.Cu")
		(net "GND")
	)
	(via
		(at 40.492934 -489.196888)
		(size 0.5588)
		(drill 0.3048)
		(layers "F.Cu" "B.Cu")
		(net "GND")
	)
	(arc
		(start 39.5224 -77.195934)
		(mid 39.75608 -77.196283)
		(end 39.98976 -77.196696)
		(width 0.508)
		(layer "F.Cu")
		(net "GND")
	)
	(arc
		(start 39.5224 -79.735934)
		(mid 39.75608 -79.736283)
		(end 39.98976 -79.736696)
		(width 0.508)
		(layer "F.Cu")
		(net "GND")
	)
	(arc
		(start 20.472908 -244.391688)
		(mid 20.078825 -244.389453)
		(end 19.684746 -244.386608)
		(width 0.508)
		(layer "F.Cu")
		(net "GND")
	)
	(segment
		(start 6.095746 -359.0417)
		(end 5.554472 -358.500426)
		(width 0.508)
		(layer "B.Cu")
		(net "GND")
	)
	(segment
		(start 5.46481 -112.50041)
		(end 2.81305 -112.50041)
		(width 0.508)
		(layer "B.Cu")
		(net "GND")
	)
	(segment
		(start 64.64427 -479.998532)
		(end 69.000878 -479.998532)
		(width 0.635)
		(layer "B.Cu")
		(net "GND")
	)
	(segment
		(start 5.968746 -410.9847)
		(end 5.453126 -411.50032)
		(width 0.508)
		(layer "B.Cu")
		(net "GND")
	)
	(segment
		(start 5.943346 -132.978906)
		(end 5.46481 -132.50037)
		(width 0.508)
		(layer "B.Cu")
		(net "GND")
	)
	(segment
		(start 225.835718 -251.670058)
		(end 227.499926 -251.670058)
		(width 0.635)
		(layer "B.Cu")
		(net "GND")
	)
	(segment
		(start 2.81305 -361.50042)
		(end 2.811526 -361.498896)
		(width 0.508)
		(layer "B.Cu")
		(net "GND")
	)
	(segment
		(start 40.835834 -45.669962)
		(end 42.500042 -45.669962)
		(width 0.635)
		(layer "B.Cu")
		(net "GND")
	)
	(segment
		(start 6.019546 -170.9801)
		(end 5.53974 -170.500294)
		(width 0.508)
		(layer "B.Cu")
		(net "GND")
	)
	(segment
		(start 5.453888 -173.500288)
		(end 2.81305 -173.500288)
		(width 0.508)
		(layer "B.Cu")
		(net "GND")
	)
	(segment
		(start 69.000878 -479.998532)
		(end 69.000878 -484.35514)
		(width 0.635)
		(layer "B.Cu")
		(net "GND")
	)
	(segment
		(start 5.332984 -404.500334)
		(end 2.81305 -404.500334)
		(width 0.508)
		(layer "B.Cu")
		(net "GND")
	)
	(segment
		(start 2.81305 -348.499938)
		(end 2.811526 -348.498414)
		(width 0.508)
		(layer "B.Cu")
		(net "GND")
	)
	(segment
		(start 227.499926 -354.670106)
		(end 227.499926 -355.788214)
		(width 0.635)
		(layer "B.Cu")
		(net "GND")
	)
	(segment
		(start 69.000878 -269.641828)
		(end 69.000878 -273.998436)
		(width 0.635)
		(layer "B.Cu")
		(net "GND")
	)
	(segment
		(start 2.81305 -120.500394)
		(end 2.811526 -120.49887)
		(width 0.508)
		(layer "B.Cu")
		(net "GND")
	)
	(segment
		(start 2.81305 -169.500296)
		(end 2.811526 -169.498772)
		(width 0.508)
		(layer "B.Cu")
		(net "GND")
	)
	(segment
		(start 5.912358 -376.9487)
		(end 5.36067 -377.500388)
		(width 0.508)
		(layer "B.Cu")
		(net "GND")
	)
	(segment
		(start 5.617464 -362.500418)
		(end 2.81305 -362.500418)
		(width 0.508)
		(layer "B.Cu")
		(net "GND")
	)
	(segment
		(start 2.80924 -60.70473)
		(end 6.06933 -60.70473)
		(width 0.7112)
		(layer "B.Cu")
		(net "GND")
	)
	(segment
		(start 2.81305 -170.500294)
		(end 2.811526 -170.49877)
		(width 0.508)
		(layer "B.Cu")
		(net "GND")
	)
	(segment
		(start 6.044946 -383.0447)
		(end 6.044946 -382.8923)
		(width 0.508)
		(layer "B.Cu")
		(net "GND")
	)
	(segment
		(start 5.968746 -156.985462)
		(end 5.453888 -157.50032)
		(width 0.508)
		(layer "B.Cu")
		(net "GND")
	)
	(segment
		(start 252.500892 -37.998654)
		(end 252.500892 -42.355262)
		(width 0.635)
		(layer "B.Cu")
		(net "GND")
	)
	(segment
		(start 5.453888 -111.500412)
		(end 2.81305 -111.500412)
		(width 0.508)
		(layer "B.Cu")
		(net "GND")
	)
	(segment
		(start 2.81305 -419.500304)
		(end 2.811526 -419.49878)
		(width 0.508)
		(layer "B.Cu")
		(net "GND")
	)
	(segment
		(start 64.64427 -376.998484)
		(end 69.000878 -376.998484)
		(width 0.635)
		(layer "B.Cu")
		(net "GND")
	)
	(segment
		(start 225.835718 -45.669962)
		(end 227.499926 -45.669962)
		(width 0.635)
		(layer "B.Cu")
		(net "GND")
	)
	(segment
		(start 5.46481 -98.49993)
		(end 2.81305 -98.49993)
		(width 0.508)
		(layer "B.Cu")
		(net "GND")
	)
	(segment
		(start 5.46481 -162.50031)
		(end 2.81305 -162.50031)
		(width 0.508)
		(layer "B.Cu")
		(net "GND")
	)
	(segment
		(start 227.499926 -457.670154)
		(end 229.164134 -457.670154)
		(width 0.635)
		(layer "B.Cu")
		(net "GND")
	)
	(segment
		(start 69.000878 -376.998484)
		(end 73.357486 -376.998484)
		(width 0.635)
		(layer "B.Cu")
		(net "GND")
	)
	(segment
		(start 5.621782 -57.704736)
		(end 2.80924 -57.704736)
		(width 0.7112)
		(layer "B.Cu")
		(net "GND")
	)
	(segment
		(start 5.265166 -348.499938)
		(end 2.81305 -348.499938)
		(width 0.508)
		(layer "B.Cu")
		(net "GND")
	)
	(segment
		(start 69.000878 -63.641986)
		(end 69.000878 -67.998594)
		(width 0.635)
		(layer "B.Cu")
		(net "GND")
	)
	(segment
		(start 227.499926 -295.66997)
		(end 229.164134 -295.66997)
		(width 0.635)
		(layer "B.Cu")
		(net "GND")
	)
	(segment
		(start 5.588254 -344.499946)
		(end 2.81305 -344.499946)
		(width 0.508)
		(layer "B.Cu")
		(net "GND")
	)
	(segment
		(start 42.500042 -192.669922)
		(end 42.500042 -193.78803)
		(width 0.635)
		(layer "B.Cu")
		(net "GND")
	)
	(segment
		(start 5.994146 -374.9929)
		(end 5.50164 -374.500394)
		(width 0.508)
		(layer "B.Cu")
		(net "GND")
	)
	(segment
		(start 15.835884 -107.329986)
		(end 17.500092 -107.329986)
		(width 0.635)
		(layer "B.Cu")
		(net "GND")
	)
	(segment
		(start 5.996432 -399.453862)
		(end 5.94995 -399.500344)
		(width 0.508)
		(layer "B.Cu")
		(net "GND")
	)
	(segment
		(start 2.81305 -351.499932)
		(end 2.811526 -351.498408)
		(width 0.508)
		(layer "B.Cu")
		(net "GND")
	)
	(segment
		(start 5.46481 -124.500386)
		(end 2.81305 -124.500386)
		(width 0.508)
		(layer "B.Cu")
		(net "GND")
	)
	(segment
		(start 2.81305 -377.500388)
		(end 2.811526 -377.498864)
		(width 0.508)
		(layer "B.Cu")
		(net "GND")
	)
	(segment
		(start 2.81305 -124.500386)
		(end 2.811526 -124.498862)
		(width 0.508)
		(layer "B.Cu")
		(net "GND")
	)
	(segment
		(start 227.499926 -148.67001)
		(end 229.164134 -148.67001)
		(width 0.635)
		(layer "B.Cu")
		(net "GND")
	)
	(segment
		(start 5.578348 -420.500302)
		(end 2.81305 -420.500302)
		(width 0.508)
		(layer "B.Cu")
		(net "GND")
	)
	(segment
		(start 5.968746 -415.0487)
		(end 5.517134 -415.500312)
		(width 0.508)
		(layer "B.Cu")
		(net "GND")
	)
	(segment
		(start 5.489448 -370.500402)
		(end 2.81305 -370.500402)
		(width 0.508)
		(layer "B.Cu")
		(net "GND")
	)
	(segment
		(start 5.943346 -120.97893)
		(end 5.46481 -120.500394)
		(width 0.508)
		(layer "B.Cu")
		(net "GND")
	)
	(segment
		(start 6.095746 -154.7495)
		(end 5.846572 -154.500326)
		(width 0.508)
		(layer "B.Cu")
		(net "GND")
	)
	(segment
		(start 227.499926 -88.551766)
		(end 227.499926 -89.669874)
		(width 0.635)
		(layer "B.Cu")
		(net "GND")
	)
	(segment
		(start 5.453888 -123.500388)
		(end 2.81305 -123.500388)
		(width 0.508)
		(layer "B.Cu")
		(net "GND")
	)
	(segment
		(start 2.81305 -146.500342)
		(end 2.811526 -146.498818)
		(width 0.508)
		(layer "B.Cu")
		(net "GND")
	)
	(segment
		(start 5.841746 -384.9497)
		(end 5.291074 -385.500372)
		(width 0.508)
		(layer "B.Cu")
		(net "GND")
	)
	(segment
		(start 227.499926 -500.551958)
		(end 227.499926 -501.670066)
		(width 0.635)
		(layer "B.Cu")
		(net "GND")
	)
	(segment
		(start 40.835834 -457.670154)
		(end 42.500042 -457.670154)
		(width 0.635)
		(layer "B.Cu")
		(net "GND")
	)
	(segment
		(start 2.81305 -158.500318)
		(end 2.811526 -158.498794)
		(width 0.508)
		(layer "B.Cu")
		(net "GND")
	)
	(segment
		(start 251.7902 -423.189908)
		(end 251.206 -422.605708)
		(width 0.508)
		(layer "B.Cu")
		(net "GND")
	)
	(segment
		(start 227.499926 -501.670066)
		(end 229.164134 -501.670066)
		(width 0.635)
		(layer "B.Cu")
		(net "GND")
	)
	(segment
		(start 5.542026 -361.50042)
		(end 2.81305 -361.50042)
		(width 0.508)
		(layer "B.Cu")
		(net "GND")
	)
	(segment
		(start 6.1722 -62.8142)
		(end 6.062726 -62.704726)
		(width 0.7112)
		(layer "B.Cu")
		(net "GND")
	)
	(segment
		(start 5.968746 -366.9411)
		(end 5.528056 -366.50041)
		(width 0.508)
		(layer "B.Cu")
		(net "GND")
	)
	(segment
		(start 227.499926 -192.669922)
		(end 227.499926 -193.78803)
		(width 0.635)
		(layer "B.Cu")
		(net "GND")
	)
	(segment
		(start 5.765546 -404.932896)
		(end 5.332984 -404.500334)
		(width 0.508)
		(layer "B.Cu")
		(net "GND")
	)
	(segment
		(start 32.99968 -4.499864)
		(end 32.99968 -8.856472)
		(width 0.635)
		(layer "B.Cu")
		(net "GND")
	)
	(segment
		(start 2.81305 -407.500328)
		(end 2.811526 -407.498804)
		(width 0.508)
		(layer "B.Cu")
		(net "GND")
	)
	(segment
		(start 252.500892 -170.998642)
		(end 256.8575 -170.998642)
		(width 0.635)
		(layer "B.Cu")
		(net "GND")
	)
	(segment
		(start 2.81305 -102.499922)
		(end 2.811526 -102.498398)
		(width 0.508)
		(layer "B.Cu")
		(net "GND")
	)
	(segment
		(start 17.500092 -107.329986)
		(end 17.500092 -108.448094)
		(width 0.635)
		(layer "B.Cu")
		(net "GND")
	)
	(segment
		(start 5.841746 -365.0107)
		(end 5.326888 -365.525558)
		(width 0.508)
		(layer "B.Cu")
		(net "GND")
	)
	(segment
		(start 7.501128 -78.628494)
		(end 7.501128 -82.985102)
		(width 0.635)
		(layer "B.Cu")
		(net "GND")
	)
	(segment
		(start 252.119892 -425.729908)
		(end 251.4346 -426.4152)
		(width 0.508)
		(layer "B.Cu")
		(net "GND")
	)
	(segment
		(start 5.968746 -406.9207)
		(end 5.389118 -407.500328)
		(width 0.508)
		(layer "B.Cu")
		(net "GND")
	)
	(segment
		(start 5.968746 -420.8907)
		(end 5.578348 -420.500302)
		(width 0.508)
		(layer "B.Cu")
		(net "GND")
	)
	(segment
		(start 2.81305 -399.500344)
		(end 2.811526 -399.49882)
		(width 0.508)
		(layer "B.Cu")
		(net "GND")
	)
	(segment
		(start 2.81305 -166.500302)
		(end 2.811526 -166.498778)
		(width 0.508)
		(layer "B.Cu")
		(net "GND")
	)
	(segment
		(start 2.81305 -369.500404)
		(end 2.811526 -369.49888)
		(width 0.508)
		(layer "B.Cu")
		(net "GND")
	)
	(segment
		(start 6.02615 -166.997634)
		(end 5.528818 -166.500302)
		(width 0.508)
		(layer "B.Cu")
		(net "GND")
	)
	(segment
		(start 2.81305 -378.500386)
		(end 2.811526 -378.498862)
		(width 0.508)
		(layer "B.Cu")
		(net "GND")
	)
	(segment
		(start 248.144284 -37.998654)
		(end 252.500892 -37.998654)
		(width 0.635)
		(layer "B.Cu")
		(net "GND")
	)
	(segment
		(start 5.846572 -154.500326)
		(end 2.81305 -154.500326)
		(width 0.508)
		(layer "B.Cu")
		(net "GND")
	)
	(segment
		(start 2.81305 -149.500336)
		(end 2.811526 -149.498812)
		(width 0.508)
		(layer "B.Cu")
		(net "GND")
	)
	(segment
		(start 4.50088 -483.398576)
		(end 4.50088 -487.755184)
		(width 0.635)
		(layer "B.Cu")
		(net "GND")
	)
	(segment
		(start 5.350256 -307.704744)
		(end 5.8928 -307.1622)
		(width 0.7112)
		(layer "B.Cu")
		(net "GND")
	)
	(segment
		(start 5.968746 -126.985522)
		(end 5.453888 -127.50038)
		(width 0.508)
		(layer "B.Cu")
		(net "GND")
	)
	(segment
		(start 248.143014 -479.996754)
		(end 252.499622 -479.996754)
		(width 0.635)
		(layer "B.Cu")
		(net "GND")
	)
	(segment
		(start 42.500042 -457.670154)
		(end 44.16425 -457.670154)
		(width 0.635)
		(layer "B.Cu")
		(net "GND")
	)
	(segment
		(start 4.50088 -479.041968)
		(end 4.50088 -483.398576)
		(width 0.635)
		(layer "B.Cu")
		(net "GND")
	)
	(segment
		(start 5.472684 -416.50031)
		(end 2.81305 -416.50031)
		(width 0.508)
		(layer "B.Cu")
		(net "GND")
	)
	(segment
		(start 5.36575 -369.500404)
		(end 2.81305 -369.500404)
		(width 0.508)
		(layer "B.Cu")
		(net "GND")
	)
	(segment
		(start 2.81305 -352.49993)
		(end 2.811526 -352.498406)
		(width 0.508)
		(layer "B.Cu")
		(net "GND")
	)
	(segment
		(start 2.81305 -127.50038)
		(end 2.811526 -127.498856)
		(width 0.508)
		(layer "B.Cu")
		(net "GND")
	)
	(segment
		(start 2.81305 -98.49993)
		(end 2.811526 -98.498406)
		(width 0.508)
		(layer "B.Cu")
		(net "GND")
	)
	(segment
		(start 42.500042 -501.670066)
		(end 42.500042 -502.788174)
		(width 0.635)
		(layer "B.Cu")
		(net "GND")
	)
	(segment
		(start 227.499926 -456.552046)
		(end 227.499926 -457.670154)
		(width 0.635)
		(layer "B.Cu")
		(net "GND")
	)
	(segment
		(start 227.499926 -191.551814)
		(end 227.499926 -192.669922)
		(width 0.635)
		(layer "B.Cu")
		(net "GND")
	)
	(segment
		(start 5.943346 -124.978922)
		(end 5.46481 -124.500386)
		(width 0.508)
		(layer "B.Cu")
		(net "GND")
	)
	(segment
		(start 2.81305 -374.500394)
		(end 2.811526 -374.49887)
		(width 0.508)
		(layer "B.Cu")
		(net "GND")
	)
	(segment
		(start 2.81305 -412.500318)
		(end 2.811526 -412.498794)
		(width 0.508)
		(layer "B.Cu")
		(net "GND")
	)
	(segment
		(start 5.841746 -381.0127)
		(end 5.354066 -381.50038)
		(width 0.508)
		(layer "B.Cu")
		(net "GND")
	)
	(segment
		(start 252.500892 -170.998642)
		(end 252.500892 -175.35525)
		(width 0.635)
		(layer "B.Cu")
		(net "GND")
	)
	(segment
		(start 5.968746 -351.180654)
		(end 5.649468 -351.499932)
		(width 0.508)
		(layer "B.Cu")
		(net "GND")
	)
	(segment
		(start 225.835718 -398.670018)
		(end 227.499926 -398.670018)
		(width 0.635)
		(layer "B.Cu")
		(net "GND")
	)
	(segment
		(start 6.044946 -382.8923)
		(end 5.653024 -382.500378)
		(width 0.508)
		(layer "B.Cu")
		(net "GND")
	)
	(segment
		(start 5.943346 -94.978474)
		(end 5.46481 -94.499938)
		(width 0.508)
		(layer "B.Cu")
		(net "GND")
	)
	(segment
		(start 252.500892 -166.642034)
		(end 252.500892 -170.998642)
		(width 0.635)
		(layer "B.Cu")
		(net "GND")
	)
	(segment
		(start 5.528056 -366.50041)
		(end 2.81305 -366.50041)
		(width 0.508)
		(layer "B.Cu")
		(net "GND")
	)
	(segment
		(start 2.81305 -162.50031)
		(end 2.811526 -162.498786)
		(width 0.508)
		(layer "B.Cu")
		(net "GND")
	)
	(segment
		(start 2.81305 -423.500296)
		(end 2.811526 -423.498772)
		(width 0.508)
		(layer "B.Cu")
		(net "GND")
	)
	(segment
		(start 40.835834 -192.669922)
		(end 42.500042 -192.669922)
		(width 0.635)
		(layer "B.Cu")
		(net "GND")
	)
	(segment
		(start 2.81305 -344.499946)
		(end 2.811526 -344.498422)
		(width 0.508)
		(layer "B.Cu")
		(net "GND")
	)
	(segment
		(start 7.501128 -78.628494)
		(end 11.857736 -78.628494)
		(width 0.635)
		(layer "B.Cu")
		(net "GND")
	)
	(segment
		(start 42.500042 -501.670066)
		(end 44.16425 -501.670066)
		(width 0.635)
		(layer "B.Cu")
		(net "GND")
	)
	(segment
		(start 252.500892 -37.998654)
		(end 256.8575 -37.998654)
		(width 0.635)
		(layer "B.Cu")
		(net "GND")
	)
	(segment
		(start 5.517134 -415.500312)
		(end 2.81305 -415.500312)
		(width 0.508)
		(layer "B.Cu")
		(net "GND")
	)
	(segment
		(start 5.453888 -131.500372)
		(end 2.81305 -131.500372)
		(width 0.508)
		(layer "B.Cu")
		(net "GND")
	)
	(segment
		(start 6.178042 -396.2273)
		(end 5.904992 -396.50035)
		(width 0.508)
		(layer "B.Cu")
		(net "GND")
	)
	(segment
		(start 248.144284 -170.998642)
		(end 252.500892 -170.998642)
		(width 0.635)
		(layer "B.Cu")
		(net "GND")
	)
	(segment
		(start 6.222746 -378.9807)
		(end 5.742432 -378.500386)
		(width 0.508)
		(layer "B.Cu")
		(net "GND")
	)
	(segment
		(start 42.500042 -88.551766)
		(end 42.500042 -89.669874)
		(width 0.635)
		(layer "B.Cu")
		(net "GND")
	)
	(segment
		(start 2.81305 -123.500388)
		(end 2.811526 -123.498864)
		(width 0.508)
		(layer "B.Cu")
		(net "GND")
	)
	(segment
		(start 69.000878 -67.998594)
		(end 73.357486 -67.998594)
		(width 0.635)
		(layer "B.Cu")
		(net "GND")
	)
	(segment
		(start 42.500042 -89.669874)
		(end 42.500042 -90.787982)
		(width 0.635)
		(layer "B.Cu")
		(net "GND")
	)
	(segment
		(start 2.81305 -111.500412)
		(end 2.811526 -111.498888)
		(width 0.508)
		(layer "B.Cu")
		(net "GND")
	)
	(segment
		(start 2.81305 -165.500304)
		(end 2.811526 -165.49878)
		(width 0.508)
		(layer "B.Cu")
		(net "GND")
	)
	(segment
		(start 5.94995 -399.500344)
		(end 2.81305 -399.500344)
		(width 0.508)
		(layer "B.Cu")
		(net "GND")
	)
	(segment
		(start 5.466588 -146.500342)
		(end 2.81305 -146.500342)
		(width 0.508)
		(layer "B.Cu")
		(net "GND")
	)
	(segment
		(start 64.64427 -170.998642)
		(end 69.000878 -170.998642)
		(width 0.635)
		(layer "B.Cu")
		(net "GND")
	)
	(segment
		(start 42.500042 -148.67001)
		(end 42.500042 -149.788118)
		(width 0.635)
		(layer "B.Cu")
		(net "GND")
	)
	(segment
		(start 2.81305 -135.500364)
		(end 2.811526 -135.49884)
		(width 0.508)
		(layer "B.Cu")
		(net "GND")
	)
	(segment
		(start 42.500042 -397.55191)
		(end 42.500042 -398.670018)
		(width 0.635)
		(layer "B.Cu")
		(net "GND")
	)
	(segment
		(start 227.499926 -192.669922)
		(end 229.164134 -192.669922)
		(width 0.635)
		(layer "B.Cu")
		(net "GND")
	)
	(segment
		(start 5.943346 -98.978466)
		(end 5.46481 -98.49993)
		(width 0.508)
		(layer "B.Cu")
		(net "GND")
	)
	(segment
		(start 2.81305 -116.500402)
		(end 2.811526 -116.498878)
		(width 0.508)
		(layer "B.Cu")
		(net "GND")
	)
	(segment
		(start 5.653024 -382.500378)
		(end 2.81305 -382.500378)
		(width 0.508)
		(layer "B.Cu")
		(net "GND")
	)
	(segment
		(start 17.500092 -48.32985)
		(end 17.500092 -49.447958)
		(width 0.635)
		(layer "B.Cu")
		(net "GND")
	)
	(segment
		(start 5.968746 -114.985546)
		(end 5.453888 -115.500404)
		(width 0.508)
		(layer "B.Cu")
		(net "GND")
	)
	(segment
		(start 64.64427 -67.998594)
		(end 69.000878 -67.998594)
		(width 0.635)
		(layer "B.Cu")
		(net "GND")
	)
	(segment
		(start 5.943346 -128.978914)
		(end 5.46481 -128.500378)
		(width 0.508)
		(layer "B.Cu")
		(net "GND")
	)
	(segment
		(start 17.500092 -107.329986)
		(end 19.1643 -107.329986)
		(width 0.635)
		(layer "B.Cu")
		(net "GND")
	)
	(segment
		(start 225.835718 -192.669922)
		(end 227.499926 -192.669922)
		(width 0.635)
		(layer "B.Cu")
		(net "GND")
	)
	(segment
		(start 5.9944 -103.0478)
		(end 5.446522 -102.499922)
		(width 0.508)
		(layer "B.Cu")
		(net "GND")
	)
	(segment
		(start 5.968746 -110.985554)
		(end 5.453888 -111.500412)
		(width 0.508)
		(layer "B.Cu")
		(net "GND")
	)
	(segment
		(start 3.14452 -78.628494)
		(end 7.501128 -78.628494)
		(width 0.635)
		(layer "B.Cu")
		(net "GND")
	)
	(segment
		(start 5.968746 -118.985538)
		(end 5.453888 -119.500396)
		(width 0.508)
		(layer "B.Cu")
		(net "GND")
	)
	(segment
		(start 5.31749 -373.500396)
		(end 2.81305 -373.500396)
		(width 0.508)
		(layer "B.Cu")
		(net "GND")
	)
	(segment
		(start 69.000878 -273.998436)
		(end 69.000878 -278.355044)
		(width 0.635)
		(layer "B.Cu")
		(net "GND")
	)
	(segment
		(start 5.301742 -365.500412)
		(end 2.81305 -365.500412)
		(width 0.508)
		(layer "B.Cu")
		(net "GND")
	)
	(segment
		(start 2.81305 -347.49994)
		(end 2.811526 -347.498416)
		(width 0.508)
		(layer "B.Cu")
		(net "GND")
	)
	(segment
		(start 5.943346 -116.978938)
		(end 5.46481 -116.500402)
		(width 0.508)
		(layer "B.Cu")
		(net "GND")
	)
	(segment
		(start 2.81305 -132.50037)
		(end 2.811526 -132.498846)
		(width 0.508)
		(layer "B.Cu")
		(net "GND")
	)
	(segment
		(start 2.81305 -385.500372)
		(end 2.811526 -385.498848)
		(width 0.508)
		(layer "B.Cu")
		(net "GND")
	)
	(segment
		(start 42.500042 -456.552046)
		(end 42.500042 -457.670154)
		(width 0.635)
		(layer "B.Cu")
		(net "GND")
	)
	(segment
		(start 17.500092 -4.329938)
		(end 19.1643 -4.329938)
		(width 0.635)
		(layer "B.Cu")
		(net "GND")
	)
	(segment
		(start 5.83311 -149.500336)
		(end 2.81305 -149.500336)
		(width 0.508)
		(layer "B.Cu")
		(net "GND")
	)
	(segment
		(start 5.326888 -365.525558)
		(end 5.301742 -365.500412)
		(width 0.508)
		(layer "B.Cu")
		(net "GND")
	)
	(segment
		(start 252.501146 -271.498568)
		(end 256.857754 -271.498568)
		(width 0.635)
		(layer "B.Cu")
		(net "GND")
	)
	(segment
		(start 2.81305 -420.500302)
		(end 2.811526 -420.498778)
		(width 0.508)
		(layer "B.Cu")
		(net "GND")
	)
	(segment
		(start 2.81305 -161.500312)
		(end 2.811526 -161.498788)
		(width 0.508)
		(layer "B.Cu")
		(net "GND")
	)
	(segment
		(start 5.841746 -369.0747)
		(end 5.390896 -369.52555)
		(width 0.508)
		(layer "B.Cu")
		(net "GND")
	)
	(segment
		(start 227.499926 -398.670018)
		(end 229.164134 -398.670018)
		(width 0.635)
		(layer "B.Cu")
		(net "GND")
	)
	(segment
		(start 2.81305 -173.500288)
		(end 2.811526 -173.498764)
		(width 0.508)
		(layer "B.Cu")
		(net "GND")
	)
	(segment
		(start 5.968746 -130.985514)
		(end 5.453888 -131.500372)
		(width 0.508)
		(layer "B.Cu")
		(net "GND")
	)
	(segment
		(start 5.553964 -158.500318)
		(end 2.81305 -158.500318)
		(width 0.508)
		(layer "B.Cu")
		(net "GND")
	)
	(segment
		(start 5.342636 -373.525542)
		(end 5.31749 -373.500396)
		(width 0.508)
		(layer "B.Cu")
		(net "GND")
	)
	(segment
		(start 17.500092 -48.32985)
		(end 19.1643 -48.32985)
		(width 0.635)
		(layer "B.Cu")
		(net "GND")
	)
	(segment
		(start 2.81305 -128.500378)
		(end 2.811526 -128.498854)
		(width 0.508)
		(layer "B.Cu")
		(net "GND")
	)
	(segment
		(start 5.968746 -168.985438)
		(end 5.453888 -169.500296)
		(width 0.508)
		(layer "B.Cu")
		(net "GND")
	)
	(segment
		(start 5.403596 -165.500304)
		(end 2.81305 -165.500304)
		(width 0.508)
		(layer "B.Cu")
		(net "GND")
	)
	(segment
		(start 5.325364 -412.500318)
		(end 2.81305 -412.500318)
		(width 0.508)
		(layer "B.Cu")
		(net "GND")
	)
	(segment
		(start 5.581142 -419.500304)
		(end 2.81305 -419.500304)
		(width 0.508)
		(layer "B.Cu")
		(net "GND")
	)
	(segment
		(start 2.80924 -307.704744)
		(end 5.350256 -307.704744)
		(width 0.7112)
		(layer "B.Cu")
		(net "GND")
	)
	(segment
		(start 5.53974 -170.500294)
		(end 2.81305 -170.500294)
		(width 0.508)
		(layer "B.Cu")
		(net "GND")
	)
	(segment
		(start 252.499622 -479.996754)
		(end 252.499622 -484.353362)
		(width 0.635)
		(layer "B.Cu")
		(net "GND")
	)
	(segment
		(start 5.516372 -408.500326)
		(end 2.81305 -408.500326)
		(width 0.508)
		(layer "B.Cu")
		(net "GND")
	)
	(segment
		(start 252.500892 -33.642046)
		(end 252.500892 -37.998654)
		(width 0.635)
		(layer "B.Cu")
		(net "GND")
	)
	(segment
		(start 5.453888 -161.500312)
		(end 2.81305 -161.500312)
		(width 0.508)
		(layer "B.Cu")
		(net "GND")
	)
	(segment
		(start 5.968746 -350.901)
		(end 5.968746 -351.180654)
		(width 0.4064)
		(layer "B.Cu")
		(net "GND")
	)
	(segment
		(start 5.943346 -108.978954)
		(end 5.46481 -108.500418)
		(width 0.508)
		(layer "B.Cu")
		(net "GND")
	)
	(segment
		(start 2.81305 -365.500412)
		(end 2.811526 -365.498888)
		(width 0.508)
		(layer "B.Cu")
		(net "GND")
	)
	(segment
		(start 42.500042 -398.670018)
		(end 44.16425 -398.670018)
		(width 0.635)
		(layer "B.Cu")
		(net "GND")
	)
	(segment
		(start 2.81305 -97.499932)
		(end 2.811526 -97.498408)
		(width 0.508)
		(layer "B.Cu")
		(net "GND")
	)
	(segment
		(start 5.446522 -102.499922)
		(end 2.81305 -102.499922)
		(width 0.508)
		(layer "B.Cu")
		(net "GND")
	)
	(segment
		(start 225.835718 -354.670106)
		(end 227.499926 -354.670106)
		(width 0.635)
		(layer "B.Cu")
		(net "GND")
	)
	(segment
		(start 69.000878 -166.642034)
		(end 69.000878 -170.998642)
		(width 0.635)
		(layer "B.Cu")
		(net "GND")
	)
	(segment
		(start 2.80924 -312.704734)
		(end 5.669534 -312.704734)
		(width 0.7112)
		(layer "B.Cu")
		(net "GND")
	)
	(segment
		(start 40.835834 -501.670066)
		(end 42.500042 -501.670066)
		(width 0.635)
		(layer "B.Cu")
		(net "GND")
	)
	(segment
		(start 227.499926 -353.551998)
		(end 227.499926 -354.670106)
		(width 0.635)
		(layer "B.Cu")
		(net "GND")
	)
	(segment
		(start 227.499926 -44.551854)
		(end 227.499926 -45.669962)
		(width 0.635)
		(layer "B.Cu")
		(net "GND")
	)
	(segment
		(start 227.499926 -45.669962)
		(end 229.164134 -45.669962)
		(width 0.635)
		(layer "B.Cu")
		(net "GND")
	)
	(segment
		(start 2.81305 -366.50041)
		(end 2.811526 -366.498886)
		(width 0.508)
		(layer "B.Cu")
		(net "GND")
	)
	(segment
		(start 2.81305 -157.50032)
		(end 2.811526 -157.498796)
		(width 0.508)
		(layer "B.Cu")
		(net "GND")
	)
	(segment
		(start 5.46481 -116.500402)
		(end 2.81305 -116.500402)
		(width 0.508)
		(layer "B.Cu")
		(net "GND")
	)
	(segment
		(start 255.093978 -411.759908)
		(end 250.0122 -411.759908)
		(width 0.508)
		(layer "B.Cu")
		(net "GND")
	)
	(segment
		(start 42.500042 -45.669962)
		(end 42.500042 -46.78807)
		(width 0.635)
		(layer "B.Cu")
		(net "GND")
	)
	(segment
		(start 5.453888 -169.500296)
		(end 2.81305 -169.500296)
		(width 0.508)
		(layer "B.Cu")
		(net "GND")
	)
	(segment
		(start 42.500042 -192.669922)
		(end 44.16425 -192.669922)
		(width 0.635)
		(layer "B.Cu")
		(net "GND")
	)
	(segment
		(start 2.81305 -408.500326)
		(end 2.811526 -408.498802)
		(width 0.508)
		(layer "B.Cu")
		(net "GND")
	)
	(segment
		(start 5.968746 -100.985066)
		(end 5.453888 -101.499924)
		(width 0.508)
		(layer "B.Cu")
		(net "GND")
	)
	(segment
		(start 6.0198 -344.0684)
		(end 5.588254 -344.499946)
		(width 0.508)
		(layer "B.Cu")
		(net "GND")
	)
	(segment
		(start 5.968746 -367.0427)
		(end 5.968746 -366.9411)
		(width 0.508)
		(layer "B.Cu")
		(net "GND")
	)
	(segment
		(start 69.000878 -170.998642)
		(end 69.000878 -175.35525)
		(width 0.635)
		(layer "B.Cu")
		(net "GND")
	)
	(segment
		(start 248.144538 -271.498568)
		(end 252.501146 -271.498568)
		(width 0.635)
		(layer "B.Cu")
		(net "GND")
	)
	(segment
		(start 5.453888 -127.50038)
		(end 2.81305 -127.50038)
		(width 0.508)
		(layer "B.Cu")
		(net "GND")
	)
	(segment
		(start 15.835884 -4.329938)
		(end 17.500092 -4.329938)
		(width 0.635)
		(layer "B.Cu")
		(net "GND")
	)
	(segment
		(start 5.649468 -351.499932)
		(end 2.81305 -351.499932)
		(width 0.508)
		(layer "B.Cu")
		(net "GND")
	)
	(segment
		(start 5.841746 -346.9767)
		(end 5.318506 -347.49994)
		(width 0.508)
		(layer "B.Cu")
		(net "GND")
	)
	(segment
		(start 6.095746 -362.9787)
		(end 5.617464 -362.500418)
		(width 0.508)
		(layer "B.Cu")
		(net "GND")
	)
	(segment
		(start 5.836412 -149.497034)
		(end 5.83311 -149.500336)
		(width 0.508)
		(layer "B.Cu")
		(net "GND")
	)
	(segment
		(start 251.713492 -420.649908)
		(end 251.1552 -421.2082)
		(width 0.508)
		(layer "B.Cu")
		(net "GND")
	)
	(segment
		(start 227.499926 -147.551902)
		(end 227.499926 -148.67001)
		(width 0.635)
		(layer "B.Cu")
		(net "GND")
	)
	(segment
		(start 2.81305 -411.50032)
		(end 2.811526 -411.498796)
		(width 0.508)
		(layer "B.Cu")
		(net "GND")
	)
	(segment
		(start 5.354066 -381.50038)
		(end 2.81305 -381.50038)
		(width 0.508)
		(layer "B.Cu")
		(net "GND")
	)
	(segment
		(start 227.499926 -294.551862)
		(end 227.499926 -295.66997)
		(width 0.635)
		(layer "B.Cu")
		(net "GND")
	)
	(segment
		(start 252.499622 -475.640146)
		(end 252.499622 -479.996754)
		(width 0.635)
		(layer "B.Cu")
		(net "GND")
	)
	(segment
		(start 17.500092 -4.329938)
		(end 17.500092 -5.448046)
		(width 0.635)
		(layer "B.Cu")
		(net "GND")
	)
	(segment
		(start 252.501146 -267.14196)
		(end 252.501146 -271.498568)
		(width 0.635)
		(layer "B.Cu")
		(net "GND")
	)
	(segment
		(start 5.943346 -162.978846)
		(end 5.46481 -162.50031)
		(width 0.508)
		(layer "B.Cu")
		(net "GND")
	)
	(segment
		(start 32.99968 -4.499864)
		(end 37.356288 -4.499864)
		(width 0.635)
		(layer "B.Cu")
		(net "GND")
	)
	(segment
		(start 6.062726 -62.704726)
		(end 2.80924 -62.704726)
		(width 0.7112)
		(layer "B.Cu")
		(net "GND")
	)
	(segment
		(start 5.389118 -407.500328)
		(end 2.81305 -407.500328)
		(width 0.508)
		(layer "B.Cu")
		(net "GND")
	)
	(segment
		(start 5.39115 -423.500296)
		(end 2.81305 -423.500296)
		(width 0.508)
		(layer "B.Cu")
		(net "GND")
	)
	(segment
		(start 2.81305 -94.499938)
		(end 2.811526 -94.498414)
		(width 0.508)
		(layer "B.Cu")
		(net "GND")
	)
	(segment
		(start 42.500042 -45.669962)
		(end 44.16425 -45.669962)
		(width 0.635)
		(layer "B.Cu")
		(net "GND")
	)
	(segment
		(start 2.81305 -358.500426)
		(end 2.811526 -358.498902)
		(width 0.508)
		(layer "B.Cu")
		(net "GND")
	)
	(segment
		(start 2.81305 -101.499924)
		(end 2.811526 -101.4984)
		(width 0.508)
		(layer "B.Cu")
		(net "GND")
	)
	(segment
		(start 5.554472 -358.500426)
		(end 2.81305 -358.500426)
		(width 0.508)
		(layer "B.Cu")
		(net "GND")
	)
	(segment
		(start 5.968746 -361.0737)
		(end 5.542026 -361.50042)
		(width 0.508)
		(layer "B.Cu")
		(net "GND")
	)
	(segment
		(start 227.499926 -251.670058)
		(end 229.164134 -251.670058)
		(width 0.635)
		(layer "B.Cu")
		(net "GND")
	)
	(segment
		(start 5.318506 -347.49994)
		(end 2.81305 -347.49994)
		(width 0.508)
		(layer "B.Cu")
		(net "GND")
	)
	(segment
		(start 2.81305 -115.500404)
		(end 2.811526 -115.49888)
		(width 0.508)
		(layer "B.Cu")
		(net "GND")
	)
	(segment
		(start 2.81305 -396.50035)
		(end 2.811526 -396.498826)
		(width 0.508)
		(layer "B.Cu")
		(net "GND")
	)
	(segment
		(start 69.000878 -67.998594)
		(end 69.000878 -72.355202)
		(width 0.635)
		(layer "B.Cu")
		(net "GND")
	)
	(segment
		(start 227.499926 -250.55195)
		(end 227.499926 -251.670058)
		(width 0.635)
		(layer "B.Cu")
		(net "GND")
	)
	(segment
		(start 227.499926 -457.670154)
		(end 227.499926 -458.788262)
		(width 0.635)
		(layer "B.Cu")
		(net "GND")
	)
	(segment
		(start 227.499926 -89.669874)
		(end 229.164134 -89.669874)
		(width 0.635)
		(layer "B.Cu")
		(net "GND")
	)
	(segment
		(start 2.81305 -154.500326)
		(end 2.811526 -154.498802)
		(width 0.508)
		(layer "B.Cu")
		(net "GND")
	)
	(segment
		(start 17.500092 -3.21183)
		(end 17.500092 -4.329938)
		(width 0.635)
		(layer "B.Cu")
		(net "GND")
	)
	(segment
		(start 5.46481 -108.500418)
		(end 2.81305 -108.500418)
		(width 0.508)
		(layer "B.Cu")
		(net "GND")
	)
	(segment
		(start 5.968746 -164.985446)
		(end 5.428742 -165.52545)
		(width 0.508)
		(layer "B.Cu")
		(net "GND")
	)
	(segment
		(start 227.499926 -295.66997)
		(end 227.499926 -296.788078)
		(width 0.635)
		(layer "B.Cu")
		(net "GND")
	)
	(segment
		(start 255.093978 -425.729908)
		(end 252.119892 -425.729908)
		(width 0.508)
		(layer "B.Cu")
		(net "GND")
	)
	(segment
		(start 42.500042 -457.670154)
		(end 42.500042 -458.788262)
		(width 0.635)
		(layer "B.Cu")
		(net "GND")
	)
	(segment
		(start 5.453888 -101.499924)
		(end 2.81305 -101.499924)
		(width 0.508)
		(layer "B.Cu")
		(net "GND")
	)
	(segment
		(start 227.499926 -148.67001)
		(end 227.499926 -149.788118)
		(width 0.635)
		(layer "B.Cu")
		(net "GND")
	)
	(segment
		(start 5.453888 -135.500364)
		(end 2.81305 -135.500364)
		(width 0.508)
		(layer "B.Cu")
		(net "GND")
	)
	(segment
		(start 5.50164 -374.500394)
		(end 2.81305 -374.500394)
		(width 0.508)
		(layer "B.Cu")
		(net "GND")
	)
	(segment
		(start 5.36067 -377.500388)
		(end 2.81305 -377.500388)
		(width 0.508)
		(layer "B.Cu")
		(net "GND")
	)
	(segment
		(start 225.835718 -295.66997)
		(end 227.499926 -295.66997)
		(width 0.635)
		(layer "B.Cu")
		(net "GND")
	)
	(segment
		(start 17.500092 -106.211878)
		(end 17.500092 -107.329986)
		(width 0.635)
		(layer "B.Cu")
		(net "GND")
	)
	(segment
		(start 17.500092 -415.212022)
		(end 17.500092 -416.33013)
		(width 0.635)
		(layer "B.Cu")
		(net "GND")
	)
	(segment
		(start 40.835834 -89.669874)
		(end 42.500042 -89.669874)
		(width 0.635)
		(layer "B.Cu")
		(net "GND")
	)
	(segment
		(start 5.291074 -385.500372)
		(end 2.81305 -385.500372)
		(width 0.508)
		(layer "B.Cu")
		(net "GND")
	)
	(segment
		(start 2.81305 -362.500418)
		(end 2.811526 -362.498894)
		(width 0.508)
		(layer "B.Cu")
		(net "GND")
	)
	(segment
		(start 225.835718 -501.670066)
		(end 227.499926 -501.670066)
		(width 0.635)
		(layer "B.Cu")
		(net "GND")
	)
	(segment
		(start 69.000878 -170.998642)
		(end 73.357486 -170.998642)
		(width 0.635)
		(layer "B.Cu")
		(net "GND")
	)
	(segment
		(start 6.222746 -352.974402)
		(end 5.748274 -352.49993)
		(width 0.508)
		(layer "B.Cu")
		(net "GND")
	)
	(segment
		(start 5.968746 -160.985454)
		(end 5.453888 -161.500312)
		(width 0.508)
		(layer "B.Cu")
		(net "GND")
	)
	(segment
		(start 5.453126 -411.50032)
		(end 2.81305 -411.50032)
		(width 0.508)
		(layer "B.Cu")
		(net "GND")
	)
	(segment
		(start 2.81305 -404.500334)
		(end 2.811526 -404.49881)
		(width 0.508)
		(layer "B.Cu")
		(net "GND")
	)
	(segment
		(start 5.765546 -146.7993)
		(end 5.466588 -146.500342)
		(width 0.508)
		(layer "B.Cu")
		(net "GND")
	)
	(segment
		(start 69.000878 -273.998436)
		(end 73.357486 -273.998436)
		(width 0.635)
		(layer "B.Cu")
		(net "GND")
	)
	(segment
		(start 2.81305 -373.500396)
		(end 2.811526 -373.498872)
		(width 0.508)
		(layer "B.Cu")
		(net "GND")
	)
	(segment
		(start 225.835718 -457.670154)
		(end 227.499926 -457.670154)
		(width 0.635)
		(layer "B.Cu")
		(net "GND")
	)
	(segment
		(start 5.748274 -352.49993)
		(end 2.81305 -352.49993)
		(width 0.508)
		(layer "B.Cu")
		(net "GND")
	)
	(segment
		(start 5.968746 -370.9797)
		(end 5.489448 -370.500402)
		(width 0.508)
		(layer "B.Cu")
		(net "GND")
	)
	(segment
		(start 225.835718 -89.669874)
		(end 227.499926 -89.669874)
		(width 0.635)
		(layer "B.Cu")
		(net "GND")
	)
	(segment
		(start 2.81305 -112.50041)
		(end 2.811526 -112.498886)
		(width 0.508)
		(layer "B.Cu")
		(net "GND")
	)
	(segment
		(start 6.044946 -158.9913)
		(end 5.553964 -158.500318)
		(width 0.508)
		(layer "B.Cu")
		(net "GND")
	)
	(segment
		(start 17.500092 -416.33013)
		(end 19.1643 -416.33013)
		(width 0.635)
		(layer "B.Cu")
		(net "GND")
	)
	(segment
		(start 2.81305 -381.50038)
		(end 2.811526 -381.498856)
		(width 0.508)
		(layer "B.Cu")
		(net "GND")
	)
	(segment
		(start 42.500042 -44.551854)
		(end 42.500042 -45.669962)
		(width 0.635)
		(layer "B.Cu")
		(net "GND")
	)
	(segment
		(start 42.500042 -398.670018)
		(end 42.500042 -399.788126)
		(width 0.635)
		(layer "B.Cu")
		(net "GND")
	)
	(segment
		(start 225.835718 -148.67001)
		(end 227.499926 -148.67001)
		(width 0.635)
		(layer "B.Cu")
		(net "GND")
	)
	(segment
		(start 5.453888 -119.500396)
		(end 2.81305 -119.500396)
		(width 0.508)
		(layer "B.Cu")
		(net "GND")
	)
	(segment
		(start 5.46481 -128.500378)
		(end 2.81305 -128.500378)
		(width 0.508)
		(layer "B.Cu")
		(net "GND")
	)
	(segment
		(start 17.500092 -47.211742)
		(end 17.500092 -48.32985)
		(width 0.635)
		(layer "B.Cu")
		(net "GND")
	)
	(segment
		(start 5.528818 -166.500302)
		(end 2.81305 -166.500302)
		(width 0.508)
		(layer "B.Cu")
		(net "GND")
	)
	(segment
		(start 5.46481 -120.500394)
		(end 2.81305 -120.500394)
		(width 0.508)
		(layer "B.Cu")
		(net "GND")
	)
	(segment
		(start 5.841746 -413.0167)
		(end 5.325364 -412.500318)
		(width 0.508)
		(layer "B.Cu")
		(net "GND")
	)
	(segment
		(start 255.093978 -420.649908)
		(end 251.713492 -420.649908)
		(width 0.508)
		(layer "B.Cu")
		(net "GND")
	)
	(segment
		(start 252.501146 -271.498568)
		(end 252.501146 -275.855176)
		(width 0.635)
		(layer "B.Cu")
		(net "GND")
	)
	(segment
		(start 17.500092 -416.33013)
		(end 17.500092 -417.448238)
		(width 0.635)
		(layer "B.Cu")
		(net "GND")
	)
	(segment
		(start 64.64427 -273.998436)
		(end 69.000878 -273.998436)
		(width 0.635)
		(layer "B.Cu")
		(net "GND")
	)
	(segment
		(start 5.390896 -369.52555)
		(end 5.36575 -369.500404)
		(width 0.508)
		(layer "B.Cu")
		(net "GND")
	)
	(segment
		(start 227.499926 -251.670058)
		(end 227.499926 -252.788166)
		(width 0.635)
		(layer "B.Cu")
		(net "GND")
	)
	(segment
		(start 252.499622 -479.996754)
		(end 256.85623 -479.996754)
		(width 0.635)
		(layer "B.Cu")
		(net "GND")
	)
	(segment
		(start 40.835834 -148.67001)
		(end 42.500042 -148.67001)
		(width 0.635)
		(layer "B.Cu")
		(net "GND")
	)
	(segment
		(start 5.968746 -408.9527)
		(end 5.516372 -408.500326)
		(width 0.508)
		(layer "B.Cu")
		(net "GND")
	)
	(segment
		(start 2.81305 -415.500312)
		(end 2.811526 -415.498788)
		(width 0.508)
		(layer "B.Cu")
		(net "GND")
	)
	(segment
		(start 42.500042 -148.67001)
		(end 44.16425 -148.67001)
		(width 0.635)
		(layer "B.Cu")
		(net "GND")
	)
	(segment
		(start 250.0122 -411.759908)
		(end 249.2248 -410.972508)
		(width 0.508)
		(layer "B.Cu")
		(net "GND")
	)
	(segment
		(start 5.94741 -416.975036)
		(end 5.472684 -416.50031)
		(width 0.508)
		(layer "B.Cu")
		(net "GND")
	)
	(segment
		(start 5.804154 -349.038926)
		(end 5.265166 -348.499938)
		(width 0.508)
		(layer "B.Cu")
		(net "GND")
	)
	(segment
		(start 2.80924 -310.704738)
		(end 5.701538 -310.704738)
		(width 0.7112)
		(layer "B.Cu")
		(net "GND")
	)
	(segment
		(start 5.841746 -423.0497)
		(end 5.39115 -423.500296)
		(width 0.508)
		(layer "B.Cu")
		(net "GND")
	)
	(segment
		(start 2.81305 -119.500396)
		(end 2.811526 -119.498872)
		(width 0.508)
		(layer "B.Cu")
		(net "GND")
	)
	(segment
		(start 5.46481 -94.499938)
		(end 2.81305 -94.499938)
		(width 0.508)
		(layer "B.Cu")
		(net "GND")
	)
	(segment
		(start 5.46481 -132.50037)
		(end 2.81305 -132.50037)
		(width 0.508)
		(layer "B.Cu")
		(net "GND")
	)
	(segment
		(start 5.904992 -396.50035)
		(end 2.81305 -396.50035)
		(width 0.508)
		(layer "B.Cu")
		(net "GND")
	)
	(segment
		(start 2.81305 -382.500378)
		(end 2.811526 -382.498854)
		(width 0.508)
		(layer "B.Cu")
		(net "GND")
	)
	(segment
		(start 42.500042 -500.551958)
		(end 42.500042 -501.670066)
		(width 0.635)
		(layer "B.Cu")
		(net "GND")
	)
	(segment
		(start 40.835834 -398.670018)
		(end 42.500042 -398.670018)
		(width 0.635)
		(layer "B.Cu")
		(net "GND")
	)
	(segment
		(start 2.81305 -108.500418)
		(end 2.811526 -108.498894)
		(width 0.508)
		(layer "B.Cu")
		(net "GND")
	)
	(segment
		(start 28.643072 -4.499864)
		(end 32.99968 -4.499864)
		(width 0.635)
		(layer "B.Cu")
		(net "GND")
	)
	(segment
		(start 42.500042 -191.551814)
		(end 42.500042 -192.669922)
		(width 0.635)
		(layer "B.Cu")
		(net "GND")
	)
	(segment
		(start 5.428742 -165.52545)
		(end 5.403596 -165.500304)
		(width 0.508)
		(layer "B.Cu")
		(net "GND")
	)
	(segment
		(start 227.499926 -398.670018)
		(end 227.499926 -399.788126)
		(width 0.635)
		(layer "B.Cu")
		(net "GND")
	)
	(segment
		(start 5.742432 -378.500386)
		(end 2.81305 -378.500386)
		(width 0.508)
		(layer "B.Cu")
		(net "GND")
	)
	(segment
		(start 5.968746 -134.985506)
		(end 5.453888 -135.500364)
		(width 0.508)
		(layer "B.Cu")
		(net "GND")
	)
	(segment
		(start 227.499926 -45.669962)
		(end 227.499926 -46.78807)
		(width 0.635)
		(layer "B.Cu")
		(net "GND")
	)
	(segment
		(start 2.81305 -370.500402)
		(end 2.811526 -370.498878)
		(width 0.508)
		(layer "B.Cu")
		(net "GND")
	)
	(segment
		(start 42.500042 -89.669874)
		(end 44.16425 -89.669874)
		(width 0.635)
		(layer "B.Cu")
		(net "GND")
	)
	(segment
		(start 69.000878 -372.641876)
		(end 69.000878 -376.998484)
		(width 0.635)
		(layer "B.Cu")
		(net "GND")
	)
	(segment
		(start 5.968746 -172.98543)
		(end 5.453888 -173.500288)
		(width 0.508)
		(layer "B.Cu")
		(net "GND")
	)
	(segment
		(start 5.453888 -115.500404)
		(end 2.81305 -115.500404)
		(width 0.508)
		(layer "B.Cu")
		(net "GND")
	)
	(segment
		(start 6.095746 -418.9857)
		(end 5.581142 -419.500304)
		(width 0.508)
		(layer "B.Cu")
		(net "GND")
	)
	(segment
		(start 5.849112 -373.019066)
		(end 5.342636 -373.525542)
		(width 0.508)
		(layer "B.Cu")
		(net "GND")
	)
	(segment
		(start 5.968746 -96.985074)
		(end 5.453888 -97.499932)
		(width 0.508)
		(layer "B.Cu")
		(net "GND")
	)
	(segment
		(start 5.453888 -157.50032)
		(end 2.81305 -157.50032)
		(width 0.508)
		(layer "B.Cu")
		(net "GND")
	)
	(segment
		(start 5.943346 -112.978946)
		(end 5.46481 -112.50041)
		(width 0.508)
		(layer "B.Cu")
		(net "GND")
	)
	(segment
		(start 5.968746 -122.98553)
		(end 5.453888 -123.500388)
		(width 0.508)
		(layer "B.Cu")
		(net "GND")
	)
	(segment
		(start 69.000878 -376.998484)
		(end 69.000878 -381.355092)
		(width 0.635)
		(layer "B.Cu")
		(net "GND")
	)
	(segment
		(start 2.81305 -416.50031)
		(end 2.811526 -416.498786)
		(width 0.508)
		(layer "B.Cu")
		(net "GND")
	)
	(segment
		(start 69.000878 -475.641924)
		(end 69.000878 -479.998532)
		(width 0.635)
		(layer "B.Cu")
		(net "GND")
	)
	(segment
		(start 5.453888 -97.499932)
		(end 2.81305 -97.499932)
		(width 0.508)
		(layer "B.Cu")
		(net "GND")
	)
	(segment
		(start 2.81305 -131.500372)
		(end 2.811526 -131.498848)
		(width 0.508)
		(layer "B.Cu")
		(net "GND")
	)
	(segment
		(start 227.499926 -397.55191)
		(end 227.499926 -398.670018)
		(width 0.635)
		(layer "B.Cu")
		(net "GND")
	)
	(segment
		(start 227.499926 -89.669874)
		(end 227.499926 -90.787982)
		(width 0.635)
		(layer "B.Cu")
		(net "GND")
	)
	(segment
		(start 255.093978 -423.189908)
		(end 251.7902 -423.189908)
		(width 0.508)
		(layer "B.Cu")
		(net "GND")
	)
	(segment
		(start 6.095746 -58.1787)
		(end 5.621782 -57.704736)
		(width 0.7112)
		(layer "B.Cu")
		(net "GND")
	)
	(segment
		(start 7.501128 -74.271886)
		(end 7.501128 -78.628494)
		(width 0.635)
		(layer "B.Cu")
		(net "GND")
	)
	(segment
		(start 42.500042 -147.551902)
		(end 42.500042 -148.67001)
		(width 0.635)
		(layer "B.Cu")
		(net "GND")
	)
	(segment
		(start 227.499926 -501.670066)
		(end 227.499926 -502.788174)
		(width 0.635)
		(layer "B.Cu")
		(net "GND")
	)
	(segment
		(start 227.499926 -354.670106)
		(end 229.164134 -354.670106)
		(width 0.635)
		(layer "B.Cu")
		(net "GND")
	)
	(segment
		(start 227.499926 -457.670154)
		(end 227.499926 -458.788262)
		(width 0.635)
		(layer "In2.Cu")
		(net "GND")
	)
	(segment
		(start 40.835834 -251.670058)
		(end 42.500042 -251.670058)
		(width 0.635)
		(layer "In2.Cu")
		(net "GND")
	)
	(segment
		(start 17.500092 -210.330034)
		(end 19.1643 -210.330034)
		(width 0.635)
		(layer "In2.Cu")
		(net "GND")
	)
	(segment
		(start 69.000878 -479.998532)
		(end 69.000878 -482.33584)
		(width 0.635)
		(layer "In2.Cu")
		(net "GND")
	)
	(segment
		(start 42.500042 -45.669962)
		(end 42.500042 -46.78807)
		(width 0.635)
		(layer "In2.Cu")
		(net "GND")
	)
	(segment
		(start 17.500092 -460.330042)
		(end 19.1643 -460.330042)
		(width 0.635)
		(layer "In2.Cu")
		(net "GND")
	)
	(segment
		(start 69.000878 -477.661224)
		(end 69.000878 -479.998532)
		(width 0.635)
		(layer "In2.Cu")
		(net "GND")
	)
	(segment
		(start 30.446472 -4.499864)
		(end 32.99968 -4.499864)
		(width 0.635)
		(layer "In2.Cu")
		(net "GND")
	)
	(segment
		(start 227.499926 -456.552046)
		(end 227.499926 -457.670154)
		(width 0.635)
		(layer "In2.Cu")
		(net "GND")
	)
	(segment
		(start 15.835884 -107.329986)
		(end 17.500092 -107.329986)
		(width 0.635)
		(layer "In2.Cu")
		(net "GND")
	)
	(segment
		(start 7.501128 -78.628494)
		(end 7.501128 -80.965802)
		(width 0.635)
		(layer "In2.Cu")
		(net "GND")
	)
	(segment
		(start 227.499926 -501.670066)
		(end 227.499926 -502.788174)
		(width 0.635)
		(layer "In2.Cu")
		(net "GND")
	)
	(segment
		(start 69.000878 -168.661334)
		(end 69.000878 -170.998642)
		(width 0.635)
		(layer "In2.Cu")
		(net "GND")
	)
	(segment
		(start 227.499926 -457.670154)
		(end 229.164134 -457.670154)
		(width 0.635)
		(layer "In2.Cu")
		(net "GND")
	)
	(segment
		(start 225.835718 -192.669922)
		(end 227.499926 -192.669922)
		(width 0.635)
		(layer "In2.Cu")
		(net "GND")
	)
	(segment
		(start 252.499622 -479.996754)
		(end 255.05283 -479.996754)
		(width 0.635)
		(layer "In2.Cu")
		(net "GND")
	)
	(segment
		(start 227.499926 -501.670066)
		(end 229.164134 -501.670066)
		(width 0.635)
		(layer "In2.Cu")
		(net "GND")
	)
	(segment
		(start 17.500092 -48.32985)
		(end 17.500092 -49.447958)
		(width 0.635)
		(layer "In2.Cu")
		(net "GND")
	)
	(segment
		(start 17.500092 -107.329986)
		(end 19.1643 -107.329986)
		(width 0.635)
		(layer "In2.Cu")
		(net "GND")
	)
	(segment
		(start 17.500092 -107.329986)
		(end 17.500092 -108.448094)
		(width 0.635)
		(layer "In2.Cu")
		(net "GND")
	)
	(segment
		(start 250.163584 -37.998654)
		(end 252.500892 -37.998654)
		(width 0.635)
		(layer "In2.Cu")
		(net "GND")
	)
	(segment
		(start 15.835884 -4.329938)
		(end 17.500092 -4.329938)
		(width 0.635)
		(layer "In2.Cu")
		(net "GND")
	)
	(segment
		(start 225.835718 -398.670018)
		(end 227.499926 -398.670018)
		(width 0.635)
		(layer "In2.Cu")
		(net "GND")
	)
	(segment
		(start 42.500042 -89.669874)
		(end 42.500042 -90.787982)
		(width 0.635)
		(layer "In2.Cu")
		(net "GND")
	)
	(segment
		(start 225.835718 -89.669874)
		(end 227.499926 -89.669874)
		(width 0.635)
		(layer "In2.Cu")
		(net "GND")
	)
	(segment
		(start 40.835834 -457.670154)
		(end 42.500042 -457.670154)
		(width 0.635)
		(layer "In2.Cu")
		(net "GND")
	)
	(segment
		(start 40.835834 -295.66997)
		(end 42.500042 -295.66997)
		(width 0.635)
		(layer "In2.Cu")
		(net "GND")
	)
	(segment
		(start 225.835718 -295.66997)
		(end 227.499926 -295.66997)
		(width 0.635)
		(layer "In2.Cu")
		(net "GND")
	)
	(segment
		(start 250.163838 -271.498568)
		(end 252.501146 -271.498568)
		(width 0.635)
		(layer "In2.Cu")
		(net "GND")
	)
	(segment
		(start 7.501128 -261.498588)
		(end 7.501128 -263.835896)
		(width 0.635)
		(layer "In2.Cu")
		(net "GND")
	)
	(segment
		(start 227.499926 -397.55191)
		(end 227.499926 -398.670018)
		(width 0.635)
		(layer "In2.Cu")
		(net "GND")
	)
	(segment
		(start 227.499926 -148.67001)
		(end 227.499926 -149.788118)
		(width 0.635)
		(layer "In2.Cu")
		(net "GND")
	)
	(segment
		(start 17.500092 -151.329898)
		(end 17.500092 -152.448006)
		(width 0.635)
		(layer "In2.Cu")
		(net "GND")
	)
	(segment
		(start 252.500892 -35.661346)
		(end 252.500892 -37.998654)
		(width 0.635)
		(layer "In2.Cu")
		(net "GND")
	)
	(segment
		(start 42.500042 -354.670106)
		(end 44.16425 -354.670106)
		(width 0.635)
		(layer "In2.Cu")
		(net "GND")
	)
	(segment
		(start 42.500042 -354.670106)
		(end 42.500042 -355.788214)
		(width 0.635)
		(layer "In2.Cu")
		(net "GND")
	)
	(segment
		(start 40.835834 -45.669962)
		(end 42.500042 -45.669962)
		(width 0.635)
		(layer "In2.Cu")
		(net "GND")
	)
	(segment
		(start 17.500092 -48.32985)
		(end 19.1643 -48.32985)
		(width 0.635)
		(layer "In2.Cu")
		(net "GND")
	)
	(segment
		(start 15.835884 -151.329898)
		(end 17.500092 -151.329898)
		(width 0.635)
		(layer "In2.Cu")
		(net "GND")
	)
	(segment
		(start 42.500042 -192.669922)
		(end 42.500042 -193.78803)
		(width 0.635)
		(layer "In2.Cu")
		(net "GND")
	)
	(segment
		(start 17.500092 -313.330082)
		(end 18.332196 -312.211974)
		(width 0.635)
		(layer "In2.Cu")
		(net "GND")
	)
	(segment
		(start 42.500042 -397.55191)
		(end 42.500042 -398.670018)
		(width 0.635)
		(layer "In2.Cu")
		(net "GND")
	)
	(segment
		(start 227.499926 -45.669962)
		(end 227.499926 -46.78807)
		(width 0.635)
		(layer "In2.Cu")
		(net "GND")
	)
	(segment
		(start 227.499926 -500.551958)
		(end 227.499926 -501.670066)
		(width 0.635)
		(layer "In2.Cu")
		(net "GND")
	)
	(segment
		(start 42.500042 -456.552046)
		(end 42.500042 -457.670154)
		(width 0.635)
		(layer "In2.Cu")
		(net "GND")
	)
	(segment
		(start 42.500042 -398.670018)
		(end 44.16425 -398.670018)
		(width 0.635)
		(layer "In2.Cu")
		(net "GND")
	)
	(segment
		(start 66.66357 -376.998484)
		(end 69.000878 -376.998484)
		(width 0.635)
		(layer "In2.Cu")
		(net "GND")
	)
	(segment
		(start 17.500092 -150.21179)
		(end 17.500092 -151.329898)
		(width 0.635)
		(layer "In2.Cu")
		(net "GND")
	)
	(segment
		(start 17.500092 -312.211974)
		(end 17.500092 -313.330082)
		(width 0.635)
		(layer "In2.Cu")
		(net "GND")
	)
	(segment
		(start 227.499926 -44.551854)
		(end 227.499926 -45.669962)
		(width 0.635)
		(layer "In2.Cu")
		(net "GND")
	)
	(segment
		(start 225.835718 -501.670066)
		(end 227.499926 -501.670066)
		(width 0.635)
		(layer "In2.Cu")
		(net "GND")
	)
	(segment
		(start 69.000878 -479.998532)
		(end 71.338186 -479.998532)
		(width 0.635)
		(layer "In2.Cu")
		(net "GND")
	)
	(segment
		(start 225.835718 -457.670154)
		(end 227.499926 -457.670154)
		(width 0.635)
		(layer "In2.Cu")
		(net "GND")
	)
	(segment
		(start 40.835834 -148.67001)
		(end 42.500042 -148.67001)
		(width 0.635)
		(layer "In2.Cu")
		(net "GND")
	)
	(segment
		(start 32.99968 -1.946656)
		(end 32.99968 -4.499864)
		(width 0.635)
		(layer "In2.Cu")
		(net "GND")
	)
	(segment
		(start 227.499926 -192.669922)
		(end 227.499926 -193.78803)
		(width 0.635)
		(layer "In2.Cu")
		(net "GND")
	)
	(segment
		(start 69.000878 -67.998594)
		(end 69.000878 -70.335902)
		(width 0.635)
		(layer "In2.Cu")
		(net "GND")
	)
	(segment
		(start 227.499926 -294.551862)
		(end 227.499926 -295.66997)
		(width 0.635)
		(layer "In2.Cu")
		(net "GND")
	)
	(segment
		(start 42.500042 -148.67001)
		(end 44.16425 -148.67001)
		(width 0.635)
		(layer "In2.Cu")
		(net "GND")
	)
	(segment
		(start 4.50088 -483.398576)
		(end 6.838188 -483.398576)
		(width 0.635)
		(layer "In2.Cu")
		(net "GND")
	)
	(segment
		(start 7.501128 -259.16128)
		(end 7.501128 -261.498588)
		(width 0.635)
		(layer "In2.Cu")
		(net "GND")
	)
	(segment
		(start 4.50088 -483.398576)
		(end 4.50088 -485.735884)
		(width 0.635)
		(layer "In2.Cu")
		(net "GND")
	)
	(segment
		(start 66.66357 -170.998642)
		(end 69.000878 -170.998642)
		(width 0.635)
		(layer "In2.Cu")
		(net "GND")
	)
	(segment
		(start 42.500042 -44.551854)
		(end 42.500042 -45.669962)
		(width 0.635)
		(layer "In2.Cu")
		(net "GND")
	)
	(segment
		(start 42.500042 -398.670018)
		(end 42.500042 -399.788126)
		(width 0.635)
		(layer "In2.Cu")
		(net "GND")
	)
	(segment
		(start 252.500892 -37.998654)
		(end 252.500892 -40.335962)
		(width 0.635)
		(layer "In2.Cu")
		(net "GND")
	)
	(segment
		(start 227.499926 -191.551814)
		(end 227.499926 -192.669922)
		(width 0.635)
		(layer "In2.Cu")
		(net "GND")
	)
	(segment
		(start 66.66357 -67.998594)
		(end 69.000878 -67.998594)
		(width 0.635)
		(layer "In2.Cu")
		(net "GND")
	)
	(segment
		(start 42.500042 -457.670154)
		(end 44.16425 -457.670154)
		(width 0.635)
		(layer "In2.Cu")
		(net "GND")
	)
	(segment
		(start 42.500042 -501.670066)
		(end 44.16425 -501.670066)
		(width 0.635)
		(layer "In2.Cu")
		(net "GND")
	)
	(segment
		(start 69.000878 -65.661286)
		(end 69.000878 -67.998594)
		(width 0.635)
		(layer "In2.Cu")
		(net "GND")
	)
	(segment
		(start 252.500892 -168.661334)
		(end 252.500892 -170.998642)
		(width 0.635)
		(layer "In2.Cu")
		(net "GND")
	)
	(segment
		(start 69.000878 -374.661176)
		(end 69.000878 -376.998484)
		(width 0.635)
		(layer "In2.Cu")
		(net "GND")
	)
	(segment
		(start 227.499926 -89.669874)
		(end 229.164134 -89.669874)
		(width 0.635)
		(layer "In2.Cu")
		(net "GND")
	)
	(segment
		(start 42.500042 -148.67001)
		(end 42.500042 -149.788118)
		(width 0.635)
		(layer "In2.Cu")
		(net "GND")
	)
	(segment
		(start 249.946414 -479.996754)
		(end 252.499622 -479.996754)
		(width 0.635)
		(layer "In2.Cu")
		(net "GND")
	)
	(segment
		(start 42.500042 -295.66997)
		(end 44.16425 -295.66997)
		(width 0.635)
		(layer "In2.Cu")
		(net "GND")
	)
	(segment
		(start 7.501128 -78.628494)
		(end 9.838436 -78.628494)
		(width 0.635)
		(layer "In2.Cu")
		(net "GND")
	)
	(segment
		(start 5.16382 -261.498588)
		(end 7.501128 -261.498588)
		(width 0.635)
		(layer "In2.Cu")
		(net "GND")
	)
	(segment
		(start 227.499926 -295.66997)
		(end 229.164134 -295.66997)
		(width 0.635)
		(layer "In2.Cu")
		(net "GND")
	)
	(segment
		(start 42.500042 -353.551998)
		(end 42.500042 -354.670106)
		(width 0.635)
		(layer "In2.Cu")
		(net "GND")
	)
	(segment
		(start 17.500092 -4.329938)
		(end 19.1643 -4.329938)
		(width 0.635)
		(layer "In2.Cu")
		(net "GND")
	)
	(segment
		(start 227.499926 -147.551902)
		(end 227.499926 -148.67001)
		(width 0.635)
		(layer "In2.Cu")
		(net "GND")
	)
	(segment
		(start 42.500042 -294.551862)
		(end 42.500042 -295.66997)
		(width 0.635)
		(layer "In2.Cu")
		(net "GND")
	)
	(segment
		(start 227.499926 -45.669962)
		(end 229.164134 -45.669962)
		(width 0.635)
		(layer "In2.Cu")
		(net "GND")
	)
	(segment
		(start 227.499926 -353.551998)
		(end 227.499926 -354.670106)
		(width 0.635)
		(layer "In2.Cu")
		(net "GND")
	)
	(segment
		(start 66.66357 -273.998436)
		(end 69.000878 -273.998436)
		(width 0.635)
		(layer "In2.Cu")
		(net "GND")
	)
	(segment
		(start 17.500092 -47.211742)
		(end 17.500092 -48.32985)
		(width 0.635)
		(layer "In2.Cu")
		(net "GND")
	)
	(segment
		(start 227.499926 -354.670106)
		(end 227.499926 -355.788214)
		(width 0.635)
		(layer "In2.Cu")
		(net "GND")
	)
	(segment
		(start 17.500092 -151.329898)
		(end 19.1643 -151.329898)
		(width 0.635)
		(layer "In2.Cu")
		(net "GND")
	)
	(segment
		(start 42.500042 -501.670066)
		(end 42.500042 -502.788174)
		(width 0.635)
		(layer "In2.Cu")
		(net "GND")
	)
	(segment
		(start 5.16382 -78.628494)
		(end 7.501128 -78.628494)
		(width 0.635)
		(layer "In2.Cu")
		(net "GND")
	)
	(segment
		(start 227.499926 -89.669874)
		(end 227.499926 -90.787982)
		(width 0.635)
		(layer "In2.Cu")
		(net "GND")
	)
	(segment
		(start 227.499926 -88.551766)
		(end 227.499926 -89.669874)
		(width 0.635)
		(layer "In2.Cu")
		(net "GND")
	)
	(segment
		(start 42.500042 -88.551766)
		(end 42.500042 -89.669874)
		(width 0.635)
		(layer "In2.Cu")
		(net "GND")
	)
	(segment
		(start 42.500042 -45.669962)
		(end 44.16425 -45.669962)
		(width 0.635)
		(layer "In2.Cu")
		(net "GND")
	)
	(segment
		(start 69.000878 -271.661128)
		(end 69.000878 -273.998436)
		(width 0.635)
		(layer "In2.Cu")
		(net "GND")
	)
	(segment
		(start 227.499926 -354.670106)
		(end 229.164134 -354.670106)
		(width 0.635)
		(layer "In2.Cu")
		(net "GND")
	)
	(segment
		(start 40.835834 -89.669874)
		(end 42.500042 -89.669874)
		(width 0.635)
		(layer "In2.Cu")
		(net "GND")
	)
	(segment
		(start 225.835718 -45.669962)
		(end 227.499926 -45.669962)
		(width 0.635)
		(layer "In2.Cu")
		(net "GND")
	)
	(segment
		(start 17.500092 -356.211886)
		(end 17.500092 -357.329994)
		(width 0.635)
		(layer "In2.Cu")
		(net "GND")
	)
	(segment
		(start 17.500092 -106.211878)
		(end 17.500092 -107.329986)
		(width 0.635)
		(layer "In2.Cu")
		(net "GND")
	)
	(segment
		(start 42.500042 -192.669922)
		(end 44.16425 -192.669922)
		(width 0.635)
		(layer "In2.Cu")
		(net "GND")
	)
	(segment
		(start 252.500892 -37.998654)
		(end 254.8382 -37.998654)
		(width 0.635)
		(layer "In2.Cu")
		(net "GND")
	)
	(segment
		(start 40.835834 -354.670106)
		(end 42.500042 -354.670106)
		(width 0.635)
		(layer "In2.Cu")
		(net "GND")
	)
	(segment
		(start 227.499926 -398.670018)
		(end 229.164134 -398.670018)
		(width 0.635)
		(layer "In2.Cu")
		(net "GND")
	)
	(segment
		(start 227.499926 -192.669922)
		(end 229.164134 -192.669922)
		(width 0.635)
		(layer "In2.Cu")
		(net "GND")
	)
	(segment
		(start 252.500892 -170.998642)
		(end 254.8382 -170.998642)
		(width 0.635)
		(layer "In2.Cu")
		(net "GND")
	)
	(segment
		(start 69.000878 -376.998484)
		(end 69.000878 -379.335792)
		(width 0.635)
		(layer "In2.Cu")
		(net "GND")
	)
	(segment
		(start 66.66357 -479.998532)
		(end 69.000878 -479.998532)
		(width 0.635)
		(layer "In2.Cu")
		(net "GND")
	)
	(segment
		(start 17.500092 -460.330042)
		(end 19.1643 -459.211934)
		(width 0.635)
		(layer "In2.Cu")
		(net "GND")
	)
	(segment
		(start 69.000878 -273.998436)
		(end 71.338186 -273.998436)
		(width 0.635)
		(layer "In2.Cu")
		(net "GND")
	)
	(segment
		(start 42.500042 -500.551958)
		(end 42.500042 -501.670066)
		(width 0.635)
		(layer "In2.Cu")
		(net "GND")
	)
	(segment
		(start 227.499926 -398.670018)
		(end 227.499926 -399.788126)
		(width 0.635)
		(layer "In2.Cu")
		(net "GND")
	)
	(segment
		(start 252.501146 -269.16126)
		(end 252.501146 -271.498568)
		(width 0.635)
		(layer "In2.Cu")
		(net "GND")
	)
	(segment
		(start 15.835884 -48.32985)
		(end 17.500092 -48.32985)
		(width 0.635)
		(layer "In2.Cu")
		(net "GND")
	)
	(segment
		(start 252.499622 -477.443546)
		(end 252.499622 -479.996754)
		(width 0.635)
		(layer "In2.Cu")
		(net "GND")
	)
	(segment
		(start 17.500092 -3.21183)
		(end 17.500092 -4.329938)
		(width 0.635)
		(layer "In2.Cu")
		(net "GND")
	)
	(segment
		(start 2.163572 -483.398576)
		(end 4.50088 -483.398576)
		(width 0.635)
		(layer "In2.Cu")
		(net "GND")
	)
	(segment
		(start 17.500092 -4.329938)
		(end 17.500092 -5.448046)
		(width 0.635)
		(layer "In2.Cu")
		(net "GND")
	)
	(segment
		(start 40.835834 -501.670066)
		(end 42.500042 -501.670066)
		(width 0.635)
		(layer "In2.Cu")
		(net "GND")
	)
	(segment
		(start 42.500042 -295.66997)
		(end 42.500042 -296.788078)
		(width 0.635)
		(layer "In2.Cu")
		(net "GND")
	)
	(segment
		(start 42.500042 -191.551814)
		(end 42.500042 -192.669922)
		(width 0.635)
		(layer "In2.Cu")
		(net "GND")
	)
	(segment
		(start 225.835718 -148.67001)
		(end 227.499926 -148.67001)
		(width 0.635)
		(layer "In2.Cu")
		(net "GND")
	)
	(segment
		(start 69.000878 -170.998642)
		(end 71.338186 -170.998642)
		(width 0.635)
		(layer "In2.Cu")
		(net "GND")
	)
	(segment
		(start 227.499926 -295.66997)
		(end 227.499926 -296.788078)
		(width 0.635)
		(layer "In2.Cu")
		(net "GND")
	)
	(segment
		(start 227.499926 -251.670058)
		(end 229.164134 -251.670058)
		(width 0.635)
		(layer "In2.Cu")
		(net "GND")
	)
	(segment
		(start 42.500042 -89.669874)
		(end 44.16425 -89.669874)
		(width 0.635)
		(layer "In2.Cu")
		(net "GND")
	)
	(segment
		(start 69.000878 -170.998642)
		(end 69.000878 -173.33595)
		(width 0.635)
		(layer "In2.Cu")
		(net "GND")
	)
	(segment
		(start 227.499926 -250.55195)
		(end 227.499926 -251.670058)
		(width 0.635)
		(layer "In2.Cu")
		(net "GND")
	)
	(segment
		(start 69.000878 -376.998484)
		(end 71.338186 -376.998484)
		(width 0.635)
		(layer "In2.Cu")
		(net "GND")
	)
	(segment
		(start 227.499926 -148.67001)
		(end 229.164134 -148.67001)
		(width 0.635)
		(layer "In2.Cu")
		(net "GND")
	)
	(segment
		(start 225.835718 -251.670058)
		(end 227.499926 -251.670058)
		(width 0.635)
		(layer "In2.Cu")
		(net "GND")
	)
	(segment
		(start 250.163584 -170.998642)
		(end 252.500892 -170.998642)
		(width 0.635)
		(layer "In2.Cu")
		(net "GND")
	)
	(segment
		(start 227.499926 -251.670058)
		(end 227.499926 -252.788166)
		(width 0.635)
		(layer "In2.Cu")
		(net "GND")
	)
	(segment
		(start 252.500892 -170.998642)
		(end 252.500892 -173.33595)
		(width 0.635)
		(layer "In2.Cu")
		(net "GND")
	)
	(segment
		(start 252.501146 -271.498568)
		(end 252.501146 -273.835876)
		(width 0.635)
		(layer "In2.Cu")
		(net "GND")
	)
	(segment
		(start 42.500042 -147.551902)
		(end 42.500042 -148.67001)
		(width 0.635)
		(layer "In2.Cu")
		(net "GND")
	)
	(segment
		(start 252.499622 -479.996754)
		(end 252.499622 -482.549962)
		(width 0.635)
		(layer "In2.Cu")
		(net "GND")
	)
	(segment
		(start 7.501128 -76.291186)
		(end 7.501128 -78.628494)
		(width 0.635)
		(layer "In2.Cu")
		(net "GND")
	)
	(segment
		(start 17.500092 -209.211926)
		(end 17.500092 -210.330034)
		(width 0.635)
		(layer "In2.Cu")
		(net "GND")
	)
	(segment
		(start 42.500042 -251.670058)
		(end 42.500042 -252.788166)
		(width 0.635)
		(layer "In2.Cu")
		(net "GND")
	)
	(segment
		(start 17.500092 -357.329994)
		(end 17.500092 -358.448102)
		(width 0.635)
		(layer "In2.Cu")
		(net "GND")
	)
	(segment
		(start 252.501146 -271.498568)
		(end 254.838454 -271.498568)
		(width 0.635)
		(layer "In2.Cu")
		(net "GND")
	)
	(segment
		(start 42.500042 -457.670154)
		(end 42.500042 -458.788262)
		(width 0.635)
		(layer "In2.Cu")
		(net "GND")
	)
	(segment
		(start 4.50088 -481.061268)
		(end 4.50088 -483.398576)
		(width 0.635)
		(layer "In2.Cu")
		(net "GND")
	)
	(segment
		(start 40.835834 -398.670018)
		(end 42.500042 -398.670018)
		(width 0.635)
		(layer "In2.Cu")
		(net "GND")
	)
	(segment
		(start 69.000878 -67.998594)
		(end 71.338186 -67.998594)
		(width 0.635)
		(layer "In2.Cu")
		(net "GND")
	)
	(segment
		(start 225.835718 -354.670106)
		(end 227.499926 -354.670106)
		(width 0.635)
		(layer "In2.Cu")
		(net "GND")
	)
	(segment
		(start 249.946414 -479.996754)
		(end 252.499622 -479.996754)
		(width 0.635)
		(layer "In5.Cu")
		(net "GND")
	)
	(segment
		(start 7.501128 -76.291186)
		(end 7.501128 -78.628494)
		(width 0.635)
		(layer "In5.Cu")
		(net "GND")
	)
	(segment
		(start 66.66357 -273.998436)
		(end 69.000878 -273.998436)
		(width 0.635)
		(layer "In5.Cu")
		(net "GND")
	)
	(segment
		(start 227.499926 -397.55191)
		(end 227.499926 -398.670018)
		(width 0.635)
		(layer "In5.Cu")
		(net "GND")
	)
	(segment
		(start 69.000878 -65.661286)
		(end 69.000878 -67.998594)
		(width 0.635)
		(layer "In5.Cu")
		(net "GND")
	)
	(segment
		(start 227.499926 -192.669922)
		(end 229.164134 -192.669922)
		(width 0.635)
		(layer "In5.Cu")
		(net "GND")
	)
	(segment
		(start 252.499622 -479.996754)
		(end 252.499622 -482.549962)
		(width 0.635)
		(layer "In5.Cu")
		(net "GND")
	)
	(segment
		(start 17.500092 -48.32985)
		(end 17.500092 -49.447958)
		(width 0.635)
		(layer "In5.Cu")
		(net "GND")
	)
	(segment
		(start 227.499926 -148.67001)
		(end 229.164134 -148.67001)
		(width 0.635)
		(layer "In5.Cu")
		(net "GND")
	)
	(segment
		(start 17.500092 -416.33013)
		(end 17.500092 -417.448238)
		(width 0.635)
		(layer "In5.Cu")
		(net "GND")
	)
	(segment
		(start 225.835718 -148.67001)
		(end 227.499926 -148.67001)
		(width 0.635)
		(layer "In5.Cu")
		(net "GND")
	)
	(segment
		(start 42.500042 -501.670066)
		(end 42.500042 -502.788174)
		(width 0.635)
		(layer "In5.Cu")
		(net "GND")
	)
	(segment
		(start 42.500042 -147.551902)
		(end 42.500042 -148.67001)
		(width 0.635)
		(layer "In5.Cu")
		(net "GND")
	)
	(segment
		(start 42.500042 -148.67001)
		(end 44.16425 -148.67001)
		(width 0.635)
		(layer "In5.Cu")
		(net "GND")
	)
	(segment
		(start 42.500042 -398.670018)
		(end 44.16425 -398.670018)
		(width 0.635)
		(layer "In5.Cu")
		(net "GND")
	)
	(segment
		(start 42.500042 -89.669874)
		(end 44.16425 -89.669874)
		(width 0.635)
		(layer "In5.Cu")
		(net "GND")
	)
	(segment
		(start 42.500042 -456.552046)
		(end 42.500042 -457.670154)
		(width 0.635)
		(layer "In5.Cu")
		(net "GND")
	)
	(segment
		(start 42.500042 -192.669922)
		(end 42.500042 -193.78803)
		(width 0.635)
		(layer "In5.Cu")
		(net "GND")
	)
	(segment
		(start 17.500092 -4.329938)
		(end 17.500092 -5.448046)
		(width 0.635)
		(layer "In5.Cu")
		(net "GND")
	)
	(segment
		(start 252.499622 -477.443546)
		(end 252.499622 -479.996754)
		(width 0.635)
		(layer "In5.Cu")
		(net "GND")
	)
	(segment
		(start 17.500092 -150.21179)
		(end 17.500092 -151.329898)
		(width 0.635)
		(layer "In5.Cu")
		(net "GND")
	)
	(segment
		(start 42.500042 -294.551862)
		(end 42.500042 -295.66997)
		(width 0.635)
		(layer "In5.Cu")
		(net "GND")
	)
	(segment
		(start 42.500042 -251.670058)
		(end 44.16425 -251.670058)
		(width 0.635)
		(layer "In5.Cu")
		(net "GND")
	)
	(segment
		(start 225.835718 -89.669874)
		(end 227.499926 -89.669874)
		(width 0.635)
		(layer "In5.Cu")
		(net "GND")
	)
	(segment
		(start 2.163572 -483.398576)
		(end 4.50088 -483.398576)
		(width 0.635)
		(layer "In5.Cu")
		(net "GND")
	)
	(segment
		(start 40.835834 -354.670106)
		(end 42.500042 -354.670106)
		(width 0.635)
		(layer "In5.Cu")
		(net "GND")
	)
	(segment
		(start 227.499926 -354.670106)
		(end 227.499926 -355.788214)
		(width 0.635)
		(layer "In5.Cu")
		(net "GND")
	)
	(segment
		(start 7.501128 -78.628494)
		(end 9.838436 -78.628494)
		(width 0.635)
		(layer "In5.Cu")
		(net "GND")
	)
	(segment
		(start 17.500092 -3.21183)
		(end 17.500092 -4.329938)
		(width 0.635)
		(layer "In5.Cu")
		(net "GND")
	)
	(segment
		(start 252.500892 -37.998654)
		(end 254.8382 -37.998654)
		(width 0.635)
		(layer "In5.Cu")
		(net "GND")
	)
	(segment
		(start 250.163584 -170.998642)
		(end 252.500892 -170.998642)
		(width 0.635)
		(layer "In5.Cu")
		(net "GND")
	)
	(segment
		(start 225.835718 -192.669922)
		(end 227.499926 -192.669922)
		(width 0.635)
		(layer "In5.Cu")
		(net "GND")
	)
	(segment
		(start 7.501128 -78.628494)
		(end 7.501128 -80.965802)
		(width 0.635)
		(layer "In5.Cu")
		(net "GND")
	)
	(segment
		(start 227.499926 -398.670018)
		(end 229.164134 -398.670018)
		(width 0.635)
		(layer "In5.Cu")
		(net "GND")
	)
	(segment
		(start 17.500092 -254.329946)
		(end 17.500092 -255.448054)
		(width 0.635)
		(layer "In5.Cu")
		(net "GND")
	)
	(segment
		(start 4.50088 -481.061268)
		(end 4.50088 -483.398576)
		(width 0.635)
		(layer "In5.Cu")
		(net "GND")
	)
	(segment
		(start 250.163584 -37.998654)
		(end 252.500892 -37.998654)
		(width 0.635)
		(layer "In5.Cu")
		(net "GND")
	)
	(segment
		(start 66.66357 -170.998642)
		(end 69.000878 -170.998642)
		(width 0.635)
		(layer "In5.Cu")
		(net "GND")
	)
	(segment
		(start 252.500892 -170.998642)
		(end 254.8382 -170.998642)
		(width 0.635)
		(layer "In5.Cu")
		(net "GND")
	)
	(segment
		(start 69.000878 -271.661128)
		(end 69.000878 -273.998436)
		(width 0.635)
		(layer "In5.Cu")
		(net "GND")
	)
	(segment
		(start 225.835718 -45.669962)
		(end 227.499926 -45.669962)
		(width 0.635)
		(layer "In5.Cu")
		(net "GND")
	)
	(segment
		(start 252.500892 -35.661346)
		(end 252.500892 -37.998654)
		(width 0.635)
		(layer "In5.Cu")
		(net "GND")
	)
	(segment
		(start 42.500042 -457.670154)
		(end 42.500042 -458.788262)
		(width 0.635)
		(layer "In5.Cu")
		(net "GND")
	)
	(segment
		(start 40.835834 -295.66997)
		(end 42.500042 -295.66997)
		(width 0.635)
		(layer "In5.Cu")
		(net "GND")
	)
	(segment
		(start 227.499926 -294.551862)
		(end 227.499926 -295.66997)
		(width 0.635)
		(layer "In5.Cu")
		(net "GND")
	)
	(segment
		(start 227.499926 -456.552046)
		(end 227.499926 -457.670154)
		(width 0.635)
		(layer "In5.Cu")
		(net "GND")
	)
	(segment
		(start 15.835884 -151.329898)
		(end 17.500092 -151.329898)
		(width 0.635)
		(layer "In5.Cu")
		(net "GND")
	)
	(segment
		(start 252.501146 -269.16126)
		(end 252.501146 -271.498568)
		(width 0.635)
		(layer "In5.Cu")
		(net "GND")
	)
	(segment
		(start 42.500042 -295.66997)
		(end 44.16425 -295.66997)
		(width 0.635)
		(layer "In5.Cu")
		(net "GND")
	)
	(segment
		(start 227.499926 -148.67001)
		(end 227.499926 -149.788118)
		(width 0.635)
		(layer "In5.Cu")
		(net "GND")
	)
	(segment
		(start 227.499926 -353.551998)
		(end 227.499926 -354.670106)
		(width 0.635)
		(layer "In5.Cu")
		(net "GND")
	)
	(segment
		(start 252.500892 -170.998642)
		(end 252.500892 -173.33595)
		(width 0.635)
		(layer "In5.Cu")
		(net "GND")
	)
	(segment
		(start 227.499926 -191.551814)
		(end 227.499926 -192.669922)
		(width 0.635)
		(layer "In5.Cu")
		(net "GND")
	)
	(segment
		(start 42.500042 -397.55191)
		(end 42.500042 -398.670018)
		(width 0.635)
		(layer "In5.Cu")
		(net "GND")
	)
	(segment
		(start 17.500092 -47.211742)
		(end 17.500092 -48.32985)
		(width 0.635)
		(layer "In5.Cu")
		(net "GND")
	)
	(segment
		(start 15.835884 -108.448094)
		(end 17.500092 -107.329986)
		(width 0.635)
		(layer "In5.Cu")
		(net "GND")
	)
	(segment
		(start 227.499926 -500.551958)
		(end 227.499926 -501.670066)
		(width 0.635)
		(layer "In5.Cu")
		(net "GND")
	)
	(segment
		(start 42.500042 -89.669874)
		(end 42.500042 -90.787982)
		(width 0.635)
		(layer "In5.Cu")
		(net "GND")
	)
	(segment
		(start 17.500092 -210.330034)
		(end 17.500092 -211.448142)
		(width 0.635)
		(layer "In5.Cu")
		(net "GND")
	)
	(segment
		(start 17.500092 -356.211886)
		(end 17.500092 -357.329994)
		(width 0.635)
		(layer "In5.Cu")
		(net "GND")
	)
	(segment
		(start 42.500042 -250.55195)
		(end 42.500042 -251.670058)
		(width 0.635)
		(layer "In5.Cu")
		(net "GND")
	)
	(segment
		(start 225.835718 -398.670018)
		(end 227.499926 -398.670018)
		(width 0.635)
		(layer "In5.Cu")
		(net "GND")
	)
	(segment
		(start 40.835834 -398.670018)
		(end 42.500042 -398.670018)
		(width 0.635)
		(layer "In5.Cu")
		(net "GND")
	)
	(segment
		(start 4.50088 -483.398576)
		(end 4.50088 -485.735884)
		(width 0.635)
		(layer "In5.Cu")
		(net "GND")
	)
	(segment
		(start 42.500042 -354.670106)
		(end 44.16425 -354.670106)
		(width 0.635)
		(layer "In5.Cu")
		(net "GND")
	)
	(segment
		(start 42.500042 -457.670154)
		(end 44.16425 -457.670154)
		(width 0.635)
		(layer "In5.Cu")
		(net "GND")
	)
	(segment
		(start 227.499926 -147.551902)
		(end 227.499926 -148.67001)
		(width 0.635)
		(layer "In5.Cu")
		(net "GND")
	)
	(segment
		(start 42.500042 -501.670066)
		(end 44.16425 -501.670066)
		(width 0.635)
		(layer "In5.Cu")
		(net "GND")
	)
	(segment
		(start 42.500042 -191.551814)
		(end 42.500042 -192.669922)
		(width 0.635)
		(layer "In5.Cu")
		(net "GND")
	)
	(segment
		(start 252.499622 -479.996754)
		(end 255.05283 -479.996754)
		(width 0.635)
		(layer "In5.Cu")
		(net "GND")
	)
	(segment
		(start 40.835834 -192.669922)
		(end 42.500042 -192.669922)
		(width 0.635)
		(layer "In5.Cu")
		(net "GND")
	)
	(segment
		(start 40.835834 -457.670154)
		(end 42.500042 -457.670154)
		(width 0.635)
		(layer "In5.Cu")
		(net "GND")
	)
	(segment
		(start 227.499926 -457.670154)
		(end 227.499926 -458.788262)
		(width 0.635)
		(layer "In5.Cu")
		(net "GND")
	)
	(segment
		(start 42.500042 -44.551854)
		(end 42.500042 -45.669962)
		(width 0.635)
		(layer "In5.Cu")
		(net "GND")
	)
	(segment
		(start 40.835834 -45.669962)
		(end 42.500042 -45.669962)
		(width 0.635)
		(layer "In5.Cu")
		(net "GND")
	)
	(segment
		(start 227.499926 -501.670066)
		(end 229.164134 -501.670066)
		(width 0.635)
		(layer "In5.Cu")
		(net "GND")
	)
	(segment
		(start 40.835834 -89.669874)
		(end 42.500042 -89.669874)
		(width 0.635)
		(layer "In5.Cu")
		(net "GND")
	)
	(segment
		(start 225.835718 -354.670106)
		(end 227.499926 -354.670106)
		(width 0.635)
		(layer "In5.Cu")
		(net "GND")
	)
	(segment
		(start 227.499926 -45.669962)
		(end 229.164134 -45.669962)
		(width 0.635)
		(layer "In5.Cu")
		(net "GND")
	)
	(segment
		(start 227.499926 -89.669874)
		(end 227.499926 -90.787982)
		(width 0.635)
		(layer "In5.Cu")
		(net "GND")
	)
	(segment
		(start 69.000878 -376.998484)
		(end 69.000878 -379.335792)
		(width 0.635)
		(layer "In5.Cu")
		(net "GND")
	)
	(segment
		(start 69.000878 -273.998436)
		(end 71.338186 -273.998436)
		(width 0.635)
		(layer "In5.Cu")
		(net "GND")
	)
	(segment
		(start 69.000878 -479.998532)
		(end 71.338186 -479.998532)
		(width 0.635)
		(layer "In5.Cu")
		(net "GND")
	)
	(segment
		(start 42.500042 -354.670106)
		(end 42.500042 -355.788214)
		(width 0.635)
		(layer "In5.Cu")
		(net "GND")
	)
	(segment
		(start 69.000878 -67.998594)
		(end 69.000878 -70.335902)
		(width 0.635)
		(layer "In5.Cu")
		(net "GND")
	)
	(segment
		(start 66.66357 -67.998594)
		(end 69.000878 -67.998594)
		(width 0.635)
		(layer "In5.Cu")
		(net "GND")
	)
	(segment
		(start 15.835884 -460.330042)
		(end 17.500092 -460.330042)
		(width 0.635)
		(layer "In5.Cu")
		(net "GND")
	)
	(segment
		(start 227.499926 -250.55195)
		(end 227.499926 -251.670058)
		(width 0.635)
		(layer "In5.Cu")
		(net "GND")
	)
	(segment
		(start 4.50088 -483.398576)
		(end 6.838188 -483.398576)
		(width 0.635)
		(layer "In5.Cu")
		(net "GND")
	)
	(segment
		(start 17.500092 -151.329898)
		(end 19.1643 -151.329898)
		(width 0.635)
		(layer "In5.Cu")
		(net "GND")
	)
	(segment
		(start 227.499926 -44.551854)
		(end 227.499926 -45.669962)
		(width 0.635)
		(layer "In5.Cu")
		(net "GND")
	)
	(segment
		(start 17.500092 -416.33013)
		(end 19.1643 -416.33013)
		(width 0.635)
		(layer "In5.Cu")
		(net "GND")
	)
	(segment
		(start 15.835884 -4.329938)
		(end 17.500092 -4.329938)
		(width 0.635)
		(layer "In5.Cu")
		(net "GND")
	)
	(segment
		(start 32.99968 -1.946656)
		(end 32.99968 -4.499864)
		(width 0.635)
		(layer "In5.Cu")
		(net "GND")
	)
	(segment
		(start 17.500092 -254.329946)
		(end 19.1643 -254.329946)
		(width 0.635)
		(layer "In5.Cu")
		(net "GND")
	)
	(segment
		(start 40.835834 -251.670058)
		(end 42.500042 -251.670058)
		(width 0.635)
		(layer "In5.Cu")
		(net "GND")
	)
	(segment
		(start 227.499926 -251.670058)
		(end 227.499926 -252.788166)
		(width 0.635)
		(layer "In5.Cu")
		(net "GND")
	)
	(segment
		(start 227.499926 -398.670018)
		(end 227.499926 -399.788126)
		(width 0.635)
		(layer "In5.Cu")
		(net "GND")
	)
	(segment
		(start 227.499926 -88.551766)
		(end 227.499926 -89.669874)
		(width 0.635)
		(layer "In5.Cu")
		(net "GND")
	)
	(segment
		(start 17.500092 -107.329986)
		(end 17.500092 -108.448094)
		(width 0.635)
		(layer "In5.Cu")
		(net "GND")
	)
	(segment
		(start 42.500042 -45.669962)
		(end 44.16425 -45.669962)
		(width 0.635)
		(layer "In5.Cu")
		(net "GND")
	)
	(segment
		(start 17.500092 -313.330082)
		(end 19.1643 -313.330082)
		(width 0.635)
		(layer "In5.Cu")
		(net "GND")
	)
	(segment
		(start 252.501146 -271.498568)
		(end 254.838454 -271.498568)
		(width 0.635)
		(layer "In5.Cu")
		(net "GND")
	)
	(segment
		(start 225.835718 -457.670154)
		(end 227.499926 -457.670154)
		(width 0.635)
		(layer "In5.Cu")
		(net "GND")
	)
	(segment
		(start 17.500092 -459.211934)
		(end 17.500092 -460.330042)
		(width 0.635)
		(layer "In5.Cu")
		(net "GND")
	)
	(segment
		(start 252.501146 -271.498568)
		(end 252.501146 -273.835876)
		(width 0.635)
		(layer "In5.Cu")
		(net "GND")
	)
	(segment
		(start 69.000878 -168.661334)
		(end 69.000878 -170.998642)
		(width 0.635)
		(layer "In5.Cu")
		(net "GND")
	)
	(segment
		(start 69.000878 -376.998484)
		(end 71.338186 -376.998484)
		(width 0.635)
		(layer "In5.Cu")
		(net "GND")
	)
	(segment
		(start 227.499926 -501.670066)
		(end 227.499926 -502.788174)
		(width 0.635)
		(layer "In5.Cu")
		(net "GND")
	)
	(segment
		(start 69.000878 -67.998594)
		(end 71.338186 -67.998594)
		(width 0.635)
		(layer "In5.Cu")
		(net "GND")
	)
	(segment
		(start 66.66357 -479.998532)
		(end 69.000878 -479.998532)
		(width 0.635)
		(layer "In5.Cu")
		(net "GND")
	)
	(segment
		(start 225.835718 -251.670058)
		(end 227.499926 -251.670058)
		(width 0.635)
		(layer "In5.Cu")
		(net "GND")
	)
	(segment
		(start 69.000878 -273.998436)
		(end 69.000878 -276.335744)
		(width 0.635)
		(layer "In5.Cu")
		(net "GND")
	)
	(segment
		(start 69.000878 -170.998642)
		(end 71.338186 -170.998642)
		(width 0.635)
		(layer "In5.Cu")
		(net "GND")
	)
	(segment
		(start 17.500092 -357.329994)
		(end 19.1643 -357.329994)
		(width 0.635)
		(layer "In5.Cu")
		(net "GND")
	)
	(segment
		(start 15.835884 -48.32985)
		(end 17.500092 -48.32985)
		(width 0.635)
		(layer "In5.Cu")
		(net "GND")
	)
	(segment
		(start 42.500042 -88.551766)
		(end 42.500042 -89.669874)
		(width 0.635)
		(layer "In5.Cu")
		(net "GND")
	)
	(segment
		(start 17.500092 -151.329898)
		(end 17.500092 -152.448006)
		(width 0.635)
		(layer "In5.Cu")
		(net "GND")
	)
	(segment
		(start 17.500092 -312.211974)
		(end 17.500092 -313.330082)
		(width 0.635)
		(layer "In5.Cu")
		(net "GND")
	)
	(segment
		(start 42.500042 -192.669922)
		(end 44.16425 -192.669922)
		(width 0.635)
		(layer "In5.Cu")
		(net "GND")
	)
	(segment
		(start 42.500042 -148.67001)
		(end 42.500042 -149.788118)
		(width 0.635)
		(layer "In5.Cu")
		(net "GND")
	)
	(segment
		(start 42.500042 -251.670058)
		(end 42.500042 -252.788166)
		(width 0.635)
		(layer "In5.Cu")
		(net "GND")
	)
	(segment
		(start 225.835718 -295.66997)
		(end 227.499926 -295.66997)
		(width 0.635)
		(layer "In5.Cu")
		(net "GND")
	)
	(segment
		(start 227.499926 -457.670154)
		(end 229.164134 -457.670154)
		(width 0.635)
		(layer "In5.Cu")
		(net "GND")
	)
	(segment
		(start 17.500092 -253.211838)
		(end 17.500092 -254.329946)
		(width 0.635)
		(layer "In5.Cu")
		(net "GND")
	)
	(segment
		(start 69.000878 -170.998642)
		(end 69.000878 -173.33595)
		(width 0.635)
		(layer "In5.Cu")
		(net "GND")
	)
	(segment
		(start 42.500042 -500.551958)
		(end 42.500042 -501.670066)
		(width 0.635)
		(layer "In5.Cu")
		(net "GND")
	)
	(segment
		(start 17.500092 -48.32985)
		(end 19.1643 -48.32985)
		(width 0.635)
		(layer "In5.Cu")
		(net "GND")
	)
	(segment
		(start 15.835884 -313.330082)
		(end 17.500092 -313.330082)
		(width 0.635)
		(layer "In5.Cu")
		(net "GND")
	)
	(segment
		(start 17.500092 -210.330034)
		(end 19.1643 -210.330034)
		(width 0.635)
		(layer "In5.Cu")
		(net "GND")
	)
	(segment
		(start 227.499926 -295.66997)
		(end 227.499926 -296.788078)
		(width 0.635)
		(layer "In5.Cu")
		(net "GND")
	)
	(segment
		(start 17.500092 -4.329938)
		(end 19.1643 -4.329938)
		(width 0.635)
		(layer "In5.Cu")
		(net "GND")
	)
	(segment
		(start 227.499926 -45.669962)
		(end 227.499926 -46.78807)
		(width 0.635)
		(layer "In5.Cu")
		(net "GND")
	)
	(segment
		(start 5.16382 -78.628494)
		(end 7.501128 -78.628494)
		(width 0.635)
		(layer "In5.Cu")
		(net "GND")
	)
	(segment
		(start 66.66357 -376.998484)
		(end 69.000878 -376.998484)
		(width 0.635)
		(layer "In5.Cu")
		(net "GND")
	)
	(segment
		(start 252.500892 -37.998654)
		(end 252.500892 -40.335962)
		(width 0.635)
		(layer "In5.Cu")
		(net "GND")
	)
	(segment
		(start 42.500042 -295.66997)
		(end 42.500042 -296.788078)
		(width 0.635)
		(layer "In5.Cu")
		(net "GND")
	)
	(segment
		(start 40.835834 -501.670066)
		(end 42.500042 -501.670066)
		(width 0.635)
		(layer "In5.Cu")
		(net "GND")
	)
	(segment
		(start 42.500042 -353.551998)
		(end 42.500042 -354.670106)
		(width 0.635)
		(layer "In5.Cu")
		(net "GND")
	)
	(segment
		(start 17.500092 -415.212022)
		(end 17.500092 -416.33013)
		(width 0.635)
		(layer "In5.Cu")
		(net "GND")
	)
	(segment
		(start 42.500042 -398.670018)
		(end 42.500042 -399.788126)
		(width 0.635)
		(layer "In5.Cu")
		(net "GND")
	)
	(segment
		(start 227.499926 -192.669922)
		(end 227.499926 -193.78803)
		(width 0.635)
		(layer "In5.Cu")
		(net "GND")
	)
	(segment
		(start 17.500092 -209.211926)
		(end 17.500092 -210.330034)
		(width 0.635)
		(layer "In5.Cu")
		(net "GND")
	)
	(segment
		(start 225.835718 -501.670066)
		(end 227.499926 -501.670066)
		(width 0.635)
		(layer "In5.Cu")
		(net "GND")
	)
	(segment
		(start 69.000878 -374.661176)
		(end 69.000878 -376.998484)
		(width 0.635)
		(layer "In5.Cu")
		(net "GND")
	)
	(segment
		(start 69.000878 -479.998532)
		(end 69.000878 -482.33584)
		(width 0.635)
		(layer "In5.Cu")
		(net "GND")
	)
	(segment
		(start 42.500042 -45.669962)
		(end 42.500042 -46.78807)
		(width 0.635)
		(layer "In5.Cu")
		(net "GND")
	)
	(segment
		(start 17.500092 -357.329994)
		(end 17.500092 -358.448102)
		(width 0.635)
		(layer "In5.Cu")
		(net "GND")
	)
	(segment
		(start 252.500892 -168.661334)
		(end 252.500892 -170.998642)
		(width 0.635)
		(layer "In5.Cu")
		(net "GND")
	)
	(segment
		(start 69.000878 -477.661224)
		(end 69.000878 -479.998532)
		(width 0.635)
		(layer "In5.Cu")
		(net "GND")
	)
	(segment
		(start 227.499926 -89.669874)
		(end 229.164134 -89.669874)
		(width 0.635)
		(layer "In5.Cu")
		(net "GND")
	)
	(segment
		(start 17.500092 -313.330082)
		(end 17.500092 -314.44819)
		(width 0.635)
		(layer "In5.Cu")
		(net "GND")
	)
	(segment
		(start 30.446472 -4.499864)
		(end 32.99968 -4.499864)
		(width 0.635)
		(layer "In5.Cu")
		(net "GND")
	)
	(segment
		(start 250.163838 -271.498568)
		(end 252.501146 -271.498568)
		(width 0.635)
		(layer "In5.Cu")
		(net "GND")
	)
	(segment
		(start 27.812746 -433.987702)
		(end 27.812746 -434.902102)
		(width 0.111252)
		(layer "F.Cu")
		(net "HDD_PRSNT10")
	)
	(via
		(at 27.812746 -434.902102)
		(size 0.5588)
		(drill 0.3048)
		(layers "F.Cu" "B.Cu")
		(net "HDD_PRSNT10")
	)
	(via
		(at 13.918946 -212.8647)
		(size 0.7112)
		(drill 0.3556)
		(layers "F.Cu" "B.Cu")
		(net "HDD_PRSNT10")
	)
	(via
		(at 8.661146 -463.0039)
		(size 0.5588)
		(drill 0.3048)
		(layers "F.Cu" "B.Cu")
		(net "HDD_PRSNT10")
	)
	(via
		(at 12.204446 -455.0283)
		(size 0.5588)
		(drill 0.3048)
		(layers "F.Cu" "B.Cu")
		(net "HDD_PRSNT10")
	)
	(via
		(at 14.909546 -212.6615)
		(size 0.5588)
		(drill 0.3048)
		(layers "F.Cu" "B.Cu")
		(net "HDD_PRSNT10")
	)
	(segment
		(start 6.736334 -462.501488)
		(end 2.812542 -462.501488)
		(width 0.111252)
		(layer "B.Cu")
		(net "HDD_PRSNT10")
	)
	(segment
		(start 14.706346 -212.8647)
		(end 13.918946 -212.8647)
		(width 0.111252)
		(layer "B.Cu")
		(net "HDD_PRSNT10")
	)
	(segment
		(start 13.918946 -212.8647)
		(end 13.83792 -212.945726)
		(width 0.111252)
		(layer "B.Cu")
		(net "HDD_PRSNT10")
	)
	(segment
		(start 28.575 -451.739)
		(end 28.575 -441.337954)
		(width 0.111252)
		(layer "B.Cu")
		(net "HDD_PRSNT10")
	)
	(segment
		(start 7.243572 -463.008726)
		(end 6.736334 -462.501488)
		(width 0.111252)
		(layer "B.Cu")
		(net "HDD_PRSNT10")
	)
	(segment
		(start 12.217146 -455.0283)
		(end 12.547346 -455.3585)
		(width 0.111252)
		(layer "B.Cu")
		(net "HDD_PRSNT10")
	)
	(segment
		(start 7.85241 -213.636352)
		(end 6.638798 -213.636352)
		(width 0.111252)
		(layer "B.Cu")
		(net "HDD_PRSNT10")
	)
	(segment
		(start 8.661146 -463.0039)
		(end 8.65632 -463.008726)
		(width 0.111252)
		(layer "B.Cu")
		(net "HDD_PRSNT10")
	)
	(segment
		(start 2.812542 -462.501488)
		(end 2.80924 -462.50479)
		(width 0.111252)
		(layer "B.Cu")
		(net "HDD_PRSNT10")
	)
	(segment
		(start 24.9555 -455.3585)
		(end 28.575 -451.739)
		(width 0.111252)
		(layer "B.Cu")
		(net "HDD_PRSNT10")
	)
	(segment
		(start 28.575 -441.337954)
		(end 27.812746 -440.5757)
		(width 0.111252)
		(layer "B.Cu")
		(net "HDD_PRSNT10")
	)
	(segment
		(start 5.503926 -212.50148)
		(end 2.812542 -212.50148)
		(width 0.111252)
		(layer "B.Cu")
		(net "HDD_PRSNT10")
	)
	(segment
		(start 27.812746 -440.5757)
		(end 27.812746 -434.902102)
		(width 0.111252)
		(layer "B.Cu")
		(net "HDD_PRSNT10")
	)
	(segment
		(start 12.547346 -455.3585)
		(end 24.9555 -455.3585)
		(width 0.111252)
		(layer "B.Cu")
		(net "HDD_PRSNT10")
	)
	(segment
		(start 8.543036 -212.945726)
		(end 7.85241 -213.636352)
		(width 0.111252)
		(layer "B.Cu")
		(net "HDD_PRSNT10")
	)
	(segment
		(start 12.204446 -455.0283)
		(end 12.217146 -455.0283)
		(width 0.111252)
		(layer "B.Cu")
		(net "HDD_PRSNT10")
	)
	(segment
		(start 13.83792 -212.945726)
		(end 8.543036 -212.945726)
		(width 0.111252)
		(layer "B.Cu")
		(net "HDD_PRSNT10")
	)
	(segment
		(start 2.812542 -212.50148)
		(end 2.80924 -212.504782)
		(width 0.111252)
		(layer "B.Cu")
		(net "HDD_PRSNT10")
	)
	(segment
		(start 14.909546 -212.6615)
		(end 14.706346 -212.8647)
		(width 0.111252)
		(layer "B.Cu")
		(net "HDD_PRSNT10")
	)
	(segment
		(start 6.638798 -213.636352)
		(end 5.503926 -212.50148)
		(width 0.111252)
		(layer "B.Cu")
		(net "HDD_PRSNT10")
	)
	(segment
		(start 8.65632 -463.008726)
		(end 7.243572 -463.008726)
		(width 0.111252)
		(layer "B.Cu")
		(net "HDD_PRSNT10")
	)
	(segment
		(start 14.362938 -396.799054)
		(end 14.465554 -396.696692)
		(width 0.14605)
		(layer "In2.Cu")
		(net "HDD_PRSNT10")
	)
	(segment
		(start 17.516856 -259.681218)
		(end 15.4051 -257.569462)
		(width 0.14605)
		(layer "In2.Cu")
		(net "HDD_PRSNT10")
	)
	(segment
		(start 15.55115 -375.915428)
		(end 15.55115 -365.138208)
		(width 0.14605)
		(layer "In2.Cu")
		(net "HDD_PRSNT10")
	)
	(segment
		(start 15.4051 -257.569462)
		(end 15.4051 -256.359406)
		(width 0.14605)
		(layer "In2.Cu")
		(net "HDD_PRSNT10")
	)
	(segment
		(start 14.465554 -394.86332)
		(end 15.033498 -394.295376)
		(width 0.14605)
		(layer "In2.Cu")
		(net "HDD_PRSNT10")
	)
	(segment
		(start 14.18844 -415.183828)
		(end 14.362938 -415.00933)
		(width 0.14605)
		(layer "In2.Cu")
		(net "HDD_PRSNT10")
	)
	(segment
		(start 14.465554 -396.696692)
		(end 14.465554 -394.86332)
		(width 0.14605)
		(layer "In2.Cu")
		(net "HDD_PRSNT10")
	)
	(segment
		(start 14.782038 -216.96045)
		(end 14.747494 -216.925906)
		(width 0.14605)
		(layer "In2.Cu")
		(net "HDD_PRSNT10")
	)
	(segment
		(start 10.467848 -452.079614)
		(end 10.133584 -451.74535)
		(width 0.14605)
		(layer "In2.Cu")
		(net "HDD_PRSNT10")
	)
	(segment
		(start 17.516856 -266.21994)
		(end 17.516856 -259.681218)
		(width 0.14605)
		(layer "In2.Cu")
		(net "HDD_PRSNT10")
	)
	(segment
		(start 10.467848 -453.291702)
		(end 10.467848 -452.079614)
		(width 0.14605)
		(layer "In2.Cu")
		(net "HDD_PRSNT10")
	)
	(segment
		(start 14.747494 -216.925906)
		(end 14.747494 -212.823552)
		(width 0.14605)
		(layer "In2.Cu")
		(net "HDD_PRSNT10")
	)
	(segment
		(start 14.747494 -212.823552)
		(end 14.909546 -212.6615)
		(width 0.14605)
		(layer "In2.Cu")
		(net "HDD_PRSNT10")
	)
	(segment
		(start 15.09014 -268.646656)
		(end 17.516856 -266.21994)
		(width 0.14605)
		(layer "In2.Cu")
		(net "HDD_PRSNT10")
	)
	(segment
		(start 14.18844 -441.38723)
		(end 14.18844 -415.183828)
		(width 0.14605)
		(layer "In2.Cu")
		(net "HDD_PRSNT10")
	)
	(segment
		(start 14.362938 -415.00933)
		(end 14.362938 -396.799054)
		(width 0.14605)
		(layer "In2.Cu")
		(net "HDD_PRSNT10")
	)
	(segment
		(start 15.033498 -394.295376)
		(end 15.033498 -376.43308)
		(width 0.14605)
		(layer "In2.Cu")
		(net "HDD_PRSNT10")
	)
	(segment
		(start 10.781792 -460.083408)
		(end 10.781792 -460.883)
		(width 0.14605)
		(layer "In2.Cu")
		(net "HDD_PRSNT10")
	)
	(segment
		(start 15.09014 -364.677198)
		(end 15.09014 -268.646656)
		(width 0.14605)
		(layer "In2.Cu")
		(net "HDD_PRSNT10")
	)
	(segment
		(start 12.645898 -455.469752)
		(end 12.645898 -458.219302)
		(width 0.14605)
		(layer "In2.Cu")
		(net "HDD_PRSNT10")
	)
	(segment
		(start 15.4051 -256.359406)
		(end 14.782038 -255.736344)
		(width 0.14605)
		(layer "In2.Cu")
		(net "HDD_PRSNT10")
	)
	(segment
		(start 14.782038 -255.736344)
		(end 14.782038 -216.96045)
		(width 0.14605)
		(layer "In2.Cu")
		(net "HDD_PRSNT10")
	)
	(segment
		(start 12.204446 -455.0283)
		(end 10.467848 -453.291702)
		(width 0.14605)
		(layer "In2.Cu")
		(net "HDD_PRSNT10")
	)
	(segment
		(start 15.55115 -365.138208)
		(end 15.09014 -364.677198)
		(width 0.14605)
		(layer "In2.Cu")
		(net "HDD_PRSNT10")
	)
	(segment
		(start 10.133584 -445.442086)
		(end 14.18844 -441.38723)
		(width 0.14605)
		(layer "In2.Cu")
		(net "HDD_PRSNT10")
	)
	(segment
		(start 12.645898 -458.219302)
		(end 10.781792 -460.083408)
		(width 0.14605)
		(layer "In2.Cu")
		(net "HDD_PRSNT10")
	)
	(segment
		(start 10.781792 -460.883)
		(end 10.673334 -460.991712)
		(width 0.14605)
		(layer "In2.Cu")
		(net "HDD_PRSNT10")
	)
	(segment
		(start 15.033498 -376.43308)
		(end 15.55115 -375.915428)
		(width 0.14605)
		(layer "In2.Cu")
		(net "HDD_PRSNT10")
	)
	(segment
		(start 12.204446 -455.0283)
		(end 12.645898 -455.469752)
		(width 0.14605)
		(layer "In2.Cu")
		(net "HDD_PRSNT10")
	)
	(segment
		(start 10.673334 -460.991712)
		(end 8.661146 -463.0039)
		(width 0.14605)
		(layer "In2.Cu")
		(net "HDD_PRSNT10")
	)
	(segment
		(start 10.133584 -451.74535)
		(end 10.133584 -445.442086)
		(width 0.14605)
		(layer "In2.Cu")
		(net "HDD_PRSNT10")
	)
	(segment
		(start 57.864756 -481.866702)
		(end 58.944256 -481.866702)
		(width 0.111252)
		(layer "F.Cu")
		(net "HDD_PRSNT_NET5")
	)
	(segment
		(start 53.737256 -482.85019)
		(end 54.736746 -481.8507)
		(width 0.111252)
		(layer "F.Cu")
		(net "HDD_PRSNT_NET5")
	)
	(segment
		(start 58.944256 -481.866702)
		(end 59.007756 -481.930202)
		(width 0.111252)
		(layer "F.Cu")
		(net "HDD_PRSNT_NET5")
	)
	(segment
		(start 56.736234 -481.8507)
		(end 56.752744 -481.86721)
		(width 0.111252)
		(layer "F.Cu")
		(net "HDD_PRSNT_NET5")
	)
	(segment
		(start 57.864248 -481.86721)
		(end 57.864756 -481.866702)
		(width 0.111252)
		(layer "F.Cu")
		(net "HDD_PRSNT_NET5")
	)
	(segment
		(start 38.250114 -482.85019)
		(end 53.737256 -482.85019)
		(width 0.111252)
		(layer "F.Cu")
		(net "HDD_PRSNT_NET5")
	)
	(segment
		(start 54.736746 -481.8507)
		(end 55.498746 -481.8507)
		(width 0.111252)
		(layer "F.Cu")
		(net "HDD_PRSNT_NET5")
	)
	(segment
		(start 59.011058 -481.9269)
		(end 59.9694 -481.9269)
		(width 0.111252)
		(layer "F.Cu")
		(net "HDD_PRSNT_NET5")
	)
	(segment
		(start 55.498746 -481.8507)
		(end 56.736234 -481.8507)
		(width 0.111252)
		(layer "F.Cu")
		(net "HDD_PRSNT_NET5")
	)
	(segment
		(start 56.752744 -481.86721)
		(end 57.864248 -481.86721)
		(width 0.111252)
		(layer "F.Cu")
		(net "HDD_PRSNT_NET5")
	)
	(segment
		(start 59.007756 -481.930202)
		(end 59.011058 -481.9269)
		(width 0.111252)
		(layer "F.Cu")
		(net "HDD_PRSNT_NET5")
	)
	(via
		(at 55.498746 -481.8507)
		(size 0.7112)
		(drill 0.3556)
		(layers "F.Cu" "B.Cu")
		(net "HDD_PRSNT_NET5")
	)
	(segment
		(start 24.840946 -452.8312)
		(end 24.840946 -453.60463)
		(width 0.09525)
		(layer "F.Cu")
		(net "SAS2X28_A_HDD10_TX_-")
	)
	(segment
		(start 4.666234 -412.498794)
		(end 3.192526 -412.498794)
		(width 0.09525)
		(layer "F.Cu")
		(net "SAS2X28_A_HDD10_TX_-")
	)
	(segment
		(start 22.124924 -455.8919)
		(end 20.700746 -455.8919)
		(width 0.09525)
		(layer "F.Cu")
		(net "SAS2X28_A_HDD10_TX_-")
	)
	(segment
		(start 24.514556 -452.268844)
		(end 24.514556 -452.26859)
		(width 0.09525)
		(layer "F.Cu")
		(net "SAS2X28_A_HDD10_TX_-")
	)
	(segment
		(start 24.617934 -454.14311)
		(end 24.490172 -454.271126)
		(width 0.09525)
		(layer "F.Cu")
		(net "SAS2X28_A_HDD10_TX_-")
	)
	(segment
		(start 23.504144 -452.1835)
		(end 24.188674 -452.1835)
		(width 0.09525)
		(layer "F.Cu")
		(net "SAS2X28_A_HDD10_TX_-")
	)
	(segment
		(start 20.700746 -455.8919)
		(end 20.700746 -455.891646)
		(width 0.09525)
		(layer "F.Cu")
		(net "SAS2X28_A_HDD10_TX_-")
	)
	(segment
		(start 18.5166 -418.086032)
		(end 19.50847 -417.094162)
		(width 0.09525)
		(layer "F.Cu")
		(net "SAS2X28_A_HDD10_TX_-")
	)
	(segment
		(start 21.75002 -451.660006)
		(end 22.973538 -451.660006)
		(width 0.09525)
		(layer "F.Cu")
		(net "SAS2X28_A_HDD10_TX_-")
	)
	(segment
		(start 4.667758 -412.500318)
		(end 4.666234 -412.498794)
		(width 0.09525)
		(layer "F.Cu")
		(net "SAS2X28_A_HDD10_TX_-")
	)
	(segment
		(start 18.470372 -412.16072)
		(end 5.48767 -412.16072)
		(width 0.09525)
		(layer "F.Cu")
		(net "SAS2X28_A_HDD10_TX_-")
	)
	(segment
		(start 24.490172 -454.271126)
		(end 23.396194 -455.365358)
		(width 0.09525)
		(layer "F.Cu")
		(net "SAS2X28_A_HDD10_TX_-")
	)
	(segment
		(start 17.360646 -452.320914)
		(end 17.360646 -420.87673)
		(width 0.09525)
		(layer "F.Cu")
		(net "SAS2X28_A_HDD10_TX_-")
	)
	(segment
		(start 19.166078 -455.256392)
		(end 18.159222 -454.249536)
		(width 0.09525)
		(layer "F.Cu")
		(net "SAS2X28_A_HDD10_TX_-")
	)
	(segment
		(start 19.882612 -416.191954)
		(end 19.882612 -413.25292)
		(width 0.09525)
		(layer "F.Cu")
		(net "SAS2X28_A_HDD10_TX_-")
	)
	(arc
		(start 24.514556 -452.26859)
		(mid 24.753483 -452.505956)
		(end 24.840946 -452.8312)
		(width 0.09525)
		(layer "F.Cu")
		(net "SAS2X28_A_HDD10_TX_-")
	)
	(arc
		(start 23.240746 -451.920102)
		(mid 23.317893 -452.106353)
		(end 23.504144 -452.1835)
		(width 0.09525)
		(layer "F.Cu")
		(net "SAS2X28_A_HDD10_TX_-")
	)
	(arc
		(start 22.973538 -451.660006)
		(mid 23.068115 -451.678819)
		(end 23.14829 -451.732396)
		(width 0.09525)
		(layer "F.Cu")
		(net "SAS2X28_A_HDD10_TX_-")
	)
	(arc
		(start 24.188674 -452.1835)
		(mid 24.357268 -452.204596)
		(end 24.514556 -452.268844)
		(width 0.09525)
		(layer "F.Cu")
		(net "SAS2X28_A_HDD10_TX_-")
	)
	(arc
		(start 18.159222 -454.249536)
		(mid 17.568115 -453.364647)
		(end 17.360646 -452.320914)
		(width 0.09525)
		(layer "F.Cu")
		(net "SAS2X28_A_HDD10_TX_-")
	)
	(arc
		(start 24.840946 -453.60463)
		(mid 24.782981 -453.89604)
		(end 24.617934 -454.14311)
		(width 0.09525)
		(layer "F.Cu")
		(net "SAS2X28_A_HDD10_TX_-")
	)
	(arc
		(start 19.628866 -412.64078)
		(mid 19.097373 -412.285521)
		(end 18.470372 -412.16072)
		(width 0.09525)
		(layer "F.Cu")
		(net "SAS2X28_A_HDD10_TX_-")
	)
	(arc
		(start 5.48767 -412.16072)
		(mid 5.373847 -412.183361)
		(end 5.277358 -412.247842)
		(width 0.09525)
		(layer "F.Cu")
		(net "SAS2X28_A_HDD10_TX_-")
	)
	(arc
		(start 19.882612 -413.25292)
		(mid 19.81667 -412.921588)
		(end 19.628866 -412.64078)
		(width 0.09525)
		(layer "F.Cu")
		(net "SAS2X28_A_HDD10_TX_-")
	)
	(arc
		(start 17.360646 -420.87673)
		(mid 17.619248 -419.471614)
		(end 18.361152 -418.250624)
		(width 0.09525)
		(layer "F.Cu")
		(net "SAS2X28_A_HDD10_TX_-")
	)
	(arc
		(start 18.361152 -418.250624)
		(mid 18.437693 -418.167211)
		(end 18.5166 -418.086032)
		(width 0.09525)
		(layer "F.Cu")
		(net "SAS2X28_A_HDD10_TX_-")
	)
	(arc
		(start 20.700746 -455.891646)
		(mid 19.870245 -455.726636)
		(end 19.166078 -455.256392)
		(width 0.09525)
		(layer "F.Cu")
		(net "SAS2X28_A_HDD10_TX_-")
	)
	(arc
		(start 23.396194 -455.365358)
		(mid 22.812944 -455.755107)
		(end 22.124924 -455.8919)
		(width 0.09525)
		(layer "F.Cu")
		(net "SAS2X28_A_HDD10_TX_-")
	)
	(arc
		(start 23.14829 -451.732396)
		(mid 23.213274 -451.817013)
		(end 23.240746 -451.920102)
		(width 0.09525)
		(layer "F.Cu")
		(net "SAS2X28_A_HDD10_TX_-")
	)
	(arc
		(start 19.50847 -417.094162)
		(mid 19.785273 -416.68027)
		(end 19.882612 -416.191954)
		(width 0.09525)
		(layer "F.Cu")
		(net "SAS2X28_A_HDD10_TX_-")
	)
	(arc
		(start 5.277358 -412.247842)
		(mid 4.997671 -412.434723)
		(end 4.667758 -412.500318)
		(width 0.09525)
		(layer "F.Cu")
		(net "SAS2X28_A_HDD10_TX_-")
	)
	(segment
		(start 17.690846 -431.369724)
		(end 17.690846 -429.127666)
		(width 0.09525)
		(layer "F.Cu")
		(net "SAS2X28_A_HDD10_TX_+")
	)
	(segment
		(start 17.923256 -427.161706)
		(end 17.923256 -426.875956)
		(width 0.09525)
		(layer "F.Cu")
		(net "SAS2X28_A_HDD10_TX_+")
	)
	(segment
		(start 17.690846 -434.372004)
		(end 17.690846 -434.086254)
		(width 0.09525)
		(layer "F.Cu")
		(net "SAS2X28_A_HDD10_TX_+")
	)
	(segment
		(start 17.690846 -426.411136)
		(end 17.690846 -426.125386)
		(width 0.09525)
		(layer "F.Cu")
		(net "SAS2X28_A_HDD10_TX_+")
	)
	(segment
		(start 17.923256 -432.120294)
		(end 17.923256 -431.834544)
		(width 0.09525)
		(layer "F.Cu")
		(net "SAS2X28_A_HDD10_TX_+")
	)
	(segment
		(start 24.510746 -452.830946)
		(end 24.510746 -453.604884)
		(width 0.09525)
		(layer "F.Cu")
		(net "SAS2X28_A_HDD10_TX_+")
	)
	(segment
		(start 24.510492 -452.8312)
		(end 24.510746 -452.830946)
		(width 0.09525)
		(layer "F.Cu")
		(net "SAS2X28_A_HDD10_TX_+")
	)
	(segment
		(start 24.384254 -453.90943)
		(end 24.384254 -453.909684)
		(width 0.09525)
		(layer "F.Cu")
		(net "SAS2X28_A_HDD10_TX_+")
	)
	(segment
		(start 24.510746 -453.604884)
		(end 24.510492 -453.60463)
		(width 0.09525)
		(layer "F.Cu")
		(net "SAS2X28_A_HDD10_TX_+")
	)
	(segment
		(start 18.75028 -418.319712)
		(end 19.74215 -417.327842)
		(width 0.09525)
		(layer "F.Cu")
		(net "SAS2X28_A_HDD10_TX_+")
	)
	(segment
		(start 24.256492 -454.0377)
		(end 23.162514 -455.131678)
		(width 0.09525)
		(layer "F.Cu")
		(net "SAS2X28_A_HDD10_TX_+")
	)
	(segment
		(start 4.705096 -411.498796)
		(end 3.192526 -411.498796)
		(width 0.09525)
		(layer "F.Cu")
		(net "SAS2X28_A_HDD10_TX_+")
	)
	(segment
		(start 20.212812 -416.191954)
		(end 20.212812 -413.252666)
		(width 0.09525)
		(layer "F.Cu")
		(net "SAS2X28_A_HDD10_TX_+")
	)
	(segment
		(start 17.690846 -427.912276)
		(end 17.690846 -427.626526)
		(width 0.09525)
		(layer "F.Cu")
		(net "SAS2X28_A_HDD10_TX_+")
	)
	(segment
		(start 17.690846 -443.20079)
		(end 17.690846 -442.91504)
		(width 0.09525)
		(layer "F.Cu")
		(net "SAS2X28_A_HDD10_TX_+")
	)
	(segment
		(start 19.399758 -455.022966)
		(end 19.303746 -454.9267)
		(width 0.09525)
		(layer "F.Cu")
		(net "SAS2X28_A_HDD10_TX_+")
	)
	(segment
		(start 17.923256 -433.621434)
		(end 17.923256 -433.335684)
		(width 0.09525)
		(layer "F.Cu")
		(net "SAS2X28_A_HDD10_TX_+")
	)
	(segment
		(start 18.607786 -418.470588)
		(end 18.608548 -418.469826)
		(width 0.09525)
		(layer "F.Cu")
		(net "SAS2X28_A_HDD10_TX_+")
	)
	(segment
		(start 24.384254 -453.909684)
		(end 24.256492 -454.0377)
		(width 0.09525)
		(layer "F.Cu")
		(net "SAS2X28_A_HDD10_TX_+")
	)
	(segment
		(start 18.470626 -411.83052)
		(end 5.503672 -411.83052)
		(width 0.09525)
		(layer "F.Cu")
		(net "SAS2X28_A_HDD10_TX_+")
	)
	(segment
		(start 17.690846 -424.909996)
		(end 17.690846 -420.876984)
		(width 0.09525)
		(layer "F.Cu")
		(net "SAS2X28_A_HDD10_TX_+")
	)
	(segment
		(start 23.052532 -452.930006)
		(end 23.055834 -452.926704)
		(width 0.09525)
		(layer "F.Cu")
		(net "SAS2X28_A_HDD10_TX_+")
	)
	(segment
		(start 4.70662 -411.50032)
		(end 4.705096 -411.498796)
		(width 0.09525)
		(layer "F.Cu")
		(net "SAS2X28_A_HDD10_TX_+")
	)
	(segment
		(start 17.923256 -435.122574)
		(end 17.923256 -434.836824)
		(width 0.09525)
		(layer "F.Cu")
		(net "SAS2X28_A_HDD10_TX_+")
	)
	(segment
		(start 17.690846 -441.69965)
		(end 17.690846 -435.587394)
		(width 0.09525)
		(layer "F.Cu")
		(net "SAS2X28_A_HDD10_TX_+")
	)
	(segment
		(start 19.303746 -454.9267)
		(end 18.392902 -454.015856)
		(width 0.09525)
		(layer "F.Cu")
		(net "SAS2X28_A_HDD10_TX_+")
	)
	(segment
		(start 17.923256 -428.662846)
		(end 17.923256 -428.377096)
		(width 0.09525)
		(layer "F.Cu")
		(net "SAS2X28_A_HDD10_TX_+")
	)
	(segment
		(start 22.124924 -455.5617)
		(end 20.700746 -455.5617)
		(width 0.09525)
		(layer "F.Cu")
		(net "SAS2X28_A_HDD10_TX_+")
	)
	(segment
		(start 17.923256 -425.660566)
		(end 17.923256 -425.374816)
		(width 0.09525)
		(layer "F.Cu")
		(net "SAS2X28_A_HDD10_TX_+")
	)
	(segment
		(start 23.684992 -452.5137)
		(end 24.19096 -452.5137)
		(width 0.09525)
		(layer "F.Cu")
		(net "SAS2X28_A_HDD10_TX_+")
	)
	(segment
		(start 21.75002 -452.930006)
		(end 23.052532 -452.930006)
		(width 0.09525)
		(layer "F.Cu")
		(net "SAS2X28_A_HDD10_TX_+")
	)
	(segment
		(start 17.923256 -443.95136)
		(end 17.923256 -443.66561)
		(width 0.09525)
		(layer "F.Cu")
		(net "SAS2X28_A_HDD10_TX_+")
	)
	(segment
		(start 24.350726 -452.55561)
		(end 24.360886 -452.561452)
		(width 0.09525)
		(layer "F.Cu")
		(net "SAS2X28_A_HDD10_TX_+")
	)
	(segment
		(start 17.690846 -452.320914)
		(end 17.690846 -444.41618)
		(width 0.09525)
		(layer "F.Cu")
		(net "SAS2X28_A_HDD10_TX_+")
	)
	(segment
		(start 17.923256 -442.45022)
		(end 17.923256 -442.16447)
		(width 0.09525)
		(layer "F.Cu")
		(net "SAS2X28_A_HDD10_TX_+")
	)
	(segment
		(start 23.316946 -452.8185)
		(end 23.577042 -452.558404)
		(width 0.09525)
		(layer "F.Cu")
		(net "SAS2X28_A_HDD10_TX_+")
	)
	(segment
		(start 17.690846 -432.870864)
		(end 17.690846 -432.585114)
		(width 0.09525)
		(layer "F.Cu")
		(net "SAS2X28_A_HDD10_TX_+")
	)
	(arc
		(start 17.806924 -433.853844)
		(mid 17.893323 -433.75177)
		(end 17.923256 -433.621434)
		(width 0.09525)
		(layer "F.Cu")
		(net "SAS2X28_A_HDD10_TX_+")
	)
	(arc
		(start 20.212812 -413.252666)
		(mid 20.121785 -412.795041)
		(end 19.862546 -412.4071)
		(width 0.09525)
		(layer "F.Cu")
		(net "SAS2X28_A_HDD10_TX_+")
	)
	(arc
		(start 17.690846 -426.125386)
		(mid 17.720643 -425.995068)
		(end 17.806924 -425.892976)
		(width 0.09525)
		(layer "F.Cu")
		(net "SAS2X28_A_HDD10_TX_+")
	)
	(arc
		(start 24.360886 -452.561452)
		(mid 24.470654 -452.676936)
		(end 24.510492 -452.8312)
		(width 0.09525)
		(layer "F.Cu")
		(net "SAS2X28_A_HDD10_TX_+")
	)
	(arc
		(start 23.597616 -452.540878)
		(mid 23.639223 -452.520609)
		(end 23.684992 -452.5137)
		(width 0.09525)
		(layer "F.Cu")
		(net "SAS2X28_A_HDD10_TX_+")
	)
	(arc
		(start 17.923256 -433.335684)
		(mid 17.89332 -433.205349)
		(end 17.806924 -433.103274)
		(width 0.09525)
		(layer "F.Cu")
		(net "SAS2X28_A_HDD10_TX_+")
	)
	(arc
		(start 19.862546 -412.4071)
		(mid 19.223928 -411.980389)
		(end 18.470626 -411.83052)
		(width 0.09525)
		(layer "F.Cu")
		(net "SAS2X28_A_HDD10_TX_+")
	)
	(arc
		(start 17.923256 -431.834544)
		(mid 17.89332 -431.704209)
		(end 17.806924 -431.602134)
		(width 0.09525)
		(layer "F.Cu")
		(net "SAS2X28_A_HDD10_TX_+")
	)
	(arc
		(start 17.690846 -427.626526)
		(mid 17.720643 -427.496208)
		(end 17.806924 -427.394116)
		(width 0.09525)
		(layer "F.Cu")
		(net "SAS2X28_A_HDD10_TX_+")
	)
	(arc
		(start 23.596092 -452.542148)
		(mid 23.596852 -452.54151)
		(end 23.597616 -452.540878)
		(width 0.09525)
		(layer "F.Cu")
		(net "SAS2X28_A_HDD10_TX_+")
	)
	(arc
		(start 17.806924 -426.643546)
		(mid 17.720693 -426.541429)
		(end 17.690846 -426.411136)
		(width 0.09525)
		(layer "F.Cu")
		(net "SAS2X28_A_HDD10_TX_+")
	)
	(arc
		(start 17.690846 -420.876984)
		(mid 17.927857 -419.589405)
		(end 18.607786 -418.470588)
		(width 0.09525)
		(layer "F.Cu")
		(net "SAS2X28_A_HDD10_TX_+")
	)
	(arc
		(start 17.806924 -425.142406)
		(mid 17.720693 -425.040289)
		(end 17.690846 -424.909996)
		(width 0.09525)
		(layer "F.Cu")
		(net "SAS2X28_A_HDD10_TX_+")
	)
	(arc
		(start 17.806924 -433.103274)
		(mid 17.720693 -433.001157)
		(end 17.690846 -432.870864)
		(width 0.09525)
		(layer "F.Cu")
		(net "SAS2X28_A_HDD10_TX_+")
	)
	(arc
		(start 17.690846 -442.91504)
		(mid 17.720643 -442.784722)
		(end 17.806924 -442.68263)
		(width 0.09525)
		(layer "F.Cu")
		(net "SAS2X28_A_HDD10_TX_+")
	)
	(arc
		(start 17.690846 -444.41618)
		(mid 17.720643 -444.285862)
		(end 17.806924 -444.18377)
		(width 0.09525)
		(layer "F.Cu")
		(net "SAS2X28_A_HDD10_TX_+")
	)
	(arc
		(start 5.253482 -411.726888)
		(mid 5.00258 -411.55924)
		(end 4.70662 -411.50032)
		(width 0.09525)
		(layer "F.Cu")
		(net "SAS2X28_A_HDD10_TX_+")
	)
	(arc
		(start 17.923256 -426.875956)
		(mid 17.89332 -426.745621)
		(end 17.806924 -426.643546)
		(width 0.09525)
		(layer "F.Cu")
		(net "SAS2X28_A_HDD10_TX_+")
	)
	(arc
		(start 17.806924 -435.354984)
		(mid 17.893323 -435.25291)
		(end 17.923256 -435.122574)
		(width 0.09525)
		(layer "F.Cu")
		(net "SAS2X28_A_HDD10_TX_+")
	)
	(arc
		(start 17.806924 -442.68263)
		(mid 17.893323 -442.580556)
		(end 17.923256 -442.45022)
		(width 0.09525)
		(layer "F.Cu")
		(net "SAS2X28_A_HDD10_TX_+")
	)
	(arc
		(start 17.806924 -443.4332)
		(mid 17.720693 -443.331083)
		(end 17.690846 -443.20079)
		(width 0.09525)
		(layer "F.Cu")
		(net "SAS2X28_A_HDD10_TX_+")
	)
	(arc
		(start 18.392902 -454.015856)
		(mid 17.873296 -453.23821)
		(end 17.690846 -452.320914)
		(width 0.09525)
		(layer "F.Cu")
		(net "SAS2X28_A_HDD10_TX_+")
	)
	(arc
		(start 23.055834 -452.926704)
		(mid 23.197165 -452.898591)
		(end 23.316946 -452.8185)
		(width 0.09525)
		(layer "F.Cu")
		(net "SAS2X28_A_HDD10_TX_+")
	)
	(arc
		(start 17.690846 -434.086254)
		(mid 17.720643 -433.955936)
		(end 17.806924 -433.853844)
		(width 0.09525)
		(layer "F.Cu")
		(net "SAS2X28_A_HDD10_TX_+")
	)
	(arc
		(start 17.923256 -428.377096)
		(mid 17.89332 -428.246761)
		(end 17.806924 -428.144686)
		(width 0.09525)
		(layer "F.Cu")
		(net "SAS2X28_A_HDD10_TX_+")
	)
	(arc
		(start 23.162514 -455.131678)
		(mid 23.078545 -455.209363)
		(end 22.988778 -455.280268)
		(width 0.09525)
		(layer "F.Cu")
		(net "SAS2X28_A_HDD10_TX_+")
	)
	(arc
		(start 17.690846 -429.127666)
		(mid 17.720643 -428.997348)
		(end 17.806924 -428.895256)
		(width 0.09525)
		(layer "F.Cu")
		(net "SAS2X28_A_HDD10_TX_+")
	)
	(arc
		(start 17.806924 -425.892976)
		(mid 17.893323 -425.790902)
		(end 17.923256 -425.660566)
		(width 0.09525)
		(layer "F.Cu")
		(net "SAS2X28_A_HDD10_TX_+")
	)
	(arc
		(start 17.923256 -442.16447)
		(mid 17.89332 -442.034135)
		(end 17.806924 -441.93206)
		(width 0.09525)
		(layer "F.Cu")
		(net "SAS2X28_A_HDD10_TX_+")
	)
	(arc
		(start 23.577042 -452.558404)
		(mid 23.586239 -452.549892)
		(end 23.596092 -452.542148)
		(width 0.09525)
		(layer "F.Cu")
		(net "SAS2X28_A_HDD10_TX_+")
	)
	(arc
		(start 17.806924 -428.144686)
		(mid 17.720693 -428.042569)
		(end 17.690846 -427.912276)
		(width 0.09525)
		(layer "F.Cu")
		(net "SAS2X28_A_HDD10_TX_+")
	)
	(arc
		(start 18.608548 -418.469826)
		(mid 18.678344 -418.393759)
		(end 18.75028 -418.319712)
		(width 0.09525)
		(layer "F.Cu")
		(net "SAS2X28_A_HDD10_TX_+")
	)
	(arc
		(start 17.806924 -441.93206)
		(mid 17.720693 -441.829943)
		(end 17.690846 -441.69965)
		(width 0.09525)
		(layer "F.Cu")
		(net "SAS2X28_A_HDD10_TX_+")
	)
	(arc
		(start 17.806924 -431.602134)
		(mid 17.720693 -431.500017)
		(end 17.690846 -431.369724)
		(width 0.09525)
		(layer "F.Cu")
		(net "SAS2X28_A_HDD10_TX_+")
	)
	(arc
		(start 17.923256 -434.836824)
		(mid 17.89332 -434.706489)
		(end 17.806924 -434.604414)
		(width 0.09525)
		(layer "F.Cu")
		(net "SAS2X28_A_HDD10_TX_+")
	)
	(arc
		(start 24.19096 -452.5137)
		(mid 24.27361 -452.524099)
		(end 24.350726 -452.55561)
		(width 0.09525)
		(layer "F.Cu")
		(net "SAS2X28_A_HDD10_TX_+")
	)
	(arc
		(start 20.700746 -455.5617)
		(mid 19.996661 -455.421742)
		(end 19.399758 -455.022966)
		(width 0.09525)
		(layer "F.Cu")
		(net "SAS2X28_A_HDD10_TX_+")
	)
	(arc
		(start 17.806924 -444.18377)
		(mid 17.893323 -444.081696)
		(end 17.923256 -443.95136)
		(width 0.09525)
		(layer "F.Cu")
		(net "SAS2X28_A_HDD10_TX_+")
	)
	(arc
		(start 24.510492 -453.60463)
		(mid 24.477681 -453.769581)
		(end 24.384254 -453.90943)
		(width 0.09525)
		(layer "F.Cu")
		(net "SAS2X28_A_HDD10_TX_+")
	)
	(arc
		(start 17.690846 -432.585114)
		(mid 17.720643 -432.454796)
		(end 17.806924 -432.352704)
		(width 0.09525)
		(layer "F.Cu")
		(net "SAS2X28_A_HDD10_TX_+")
	)
	(arc
		(start 17.806924 -428.895256)
		(mid 17.893323 -428.793182)
		(end 17.923256 -428.662846)
		(width 0.09525)
		(layer "F.Cu")
		(net "SAS2X28_A_HDD10_TX_+")
	)
	(arc
		(start 19.74215 -417.327842)
		(mid 20.090454 -416.806707)
		(end 20.212812 -416.191954)
		(width 0.09525)
		(layer "F.Cu")
		(net "SAS2X28_A_HDD10_TX_+")
	)
	(arc
		(start 17.806924 -427.394116)
		(mid 17.893323 -427.292042)
		(end 17.923256 -427.161706)
		(width 0.09525)
		(layer "F.Cu")
		(net "SAS2X28_A_HDD10_TX_+")
	)
	(arc
		(start 5.503672 -411.83052)
		(mid 5.36827 -411.803587)
		(end 5.253482 -411.726888)
		(width 0.09525)
		(layer "F.Cu")
		(net "SAS2X28_A_HDD10_TX_+")
	)
	(arc
		(start 17.690846 -435.587394)
		(mid 17.720643 -435.457076)
		(end 17.806924 -435.354984)
		(width 0.09525)
		(layer "F.Cu")
		(net "SAS2X28_A_HDD10_TX_+")
	)
	(arc
		(start 17.806924 -434.604414)
		(mid 17.720693 -434.502297)
		(end 17.690846 -434.372004)
		(width 0.09525)
		(layer "F.Cu")
		(net "SAS2X28_A_HDD10_TX_+")
	)
	(arc
		(start 17.806924 -432.352704)
		(mid 17.893323 -432.25063)
		(end 17.923256 -432.120294)
		(width 0.09525)
		(layer "F.Cu")
		(net "SAS2X28_A_HDD10_TX_+")
	)
	(arc
		(start 22.988778 -455.280268)
		(mid 22.579173 -455.489485)
		(end 22.124924 -455.5617)
		(width 0.09525)
		(layer "F.Cu")
		(net "SAS2X28_A_HDD10_TX_+")
	)
	(arc
		(start 17.923256 -425.374816)
		(mid 17.89332 -425.244481)
		(end 17.806924 -425.142406)
		(width 0.09525)
		(layer "F.Cu")
		(net "SAS2X28_A_HDD10_TX_+")
	)
	(arc
		(start 17.923256 -443.66561)
		(mid 17.89332 -443.535275)
		(end 17.806924 -443.4332)
		(width 0.09525)
		(layer "F.Cu")
		(net "SAS2X28_A_HDD10_TX_+")
	)
	(segment
		(start 215.3666 -171.9834)
		(end 215.3793 -172.1358)
		(width 0.111252)
		(layer "F.Cu")
		(net "HDD_PRSNT_NET3")
	)
	(segment
		(start 216.584784 -173.198028)
		(end 217.664284 -173.198028)
		(width 0.111252)
		(layer "F.Cu")
		(net "HDD_PRSNT_NET3")
	)
	(segment
		(start 217.664284 -173.198028)
		(end 217.727784 -173.261528)
		(width 0.111252)
		(layer "F.Cu")
		(net "HDD_PRSNT_NET3")
	)
	(segment
		(start 219.095574 -173.261528)
		(end 217.727784 -173.261528)
		(width 0.111252)
		(layer "F.Cu")
		(net "HDD_PRSNT_NET3")
	)
	(segment
		(start 215.378284 -172.136816)
		(end 215.378284 -173.198028)
		(width 0.111252)
		(layer "F.Cu")
		(net "HDD_PRSNT_NET3")
	)
	(segment
		(start 219.684092 -173.850046)
		(end 219.095574 -173.261528)
		(width 0.111252)
		(layer "F.Cu")
		(net "HDD_PRSNT_NET3")
	)
	(segment
		(start 223.249998 -173.850046)
		(end 219.684092 -173.850046)
		(width 0.111252)
		(layer "F.Cu")
		(net "HDD_PRSNT_NET3")
	)
	(segment
		(start 215.1888 -170.688)
		(end 215.3666 -170.8658)
		(width 0.111252)
		(layer "F.Cu")
		(net "HDD_PRSNT_NET3")
	)
	(segment
		(start 215.3666 -170.8658)
		(end 215.3666 -171.9834)
		(width 0.111252)
		(layer "F.Cu")
		(net "HDD_PRSNT_NET3")
	)
	(segment
		(start 215.3793 -172.1358)
		(end 215.378284 -172.136816)
		(width 0.111252)
		(layer "F.Cu")
		(net "HDD_PRSNT_NET3")
	)
	(segment
		(start 215.378284 -173.198028)
		(end 216.584784 -173.198028)
		(width 0.111252)
		(layer "F.Cu")
		(net "HDD_PRSNT_NET3")
	)
	(via
		(at 215.1888 -170.688)
		(size 0.7112)
		(drill 0.3556)
		(layers "F.Cu" "B.Cu")
		(net "HDD_PRSNT_NET3")
	)
	(segment
		(start 27.442414 -442.491114)
		(end 27.812746 -442.8617)
		(width 0.09525)
		(layer "F.Cu")
		(net "SAS2X28_B_HDD10_RX_-")
	)
	(segment
		(start 26.733246 -442.7347)
		(end 26.77033 -442.69787)
		(width 0.09525)
		(layer "F.Cu")
		(net "SAS2X28_B_HDD10_RX_-")
	)
	(via
		(at 27.812746 -442.8617)
		(size 0.5588)
		(drill 0.3048)
		(layers "F.Cu" "B.Cu")
		(net "SAS2X28_B_HDD10_RX_-")
	)
	(arc
		(start 27.355546 -442.4553)
		(mid 27.402548 -442.464556)
		(end 27.442414 -442.491114)
		(width 0.09525)
		(layer "F.Cu")
		(net "SAS2X28_B_HDD10_RX_-")
	)
	(arc
		(start 26.77033 -442.69787)
		(mid 27.038814 -442.518381)
		(end 27.355546 -442.4553)
		(width 0.09525)
		(layer "F.Cu")
		(net "SAS2X28_B_HDD10_RX_-")
	)
	(segment
		(start 4.988052 -160.500314)
		(end 4.986528 -160.49879)
		(width 0.09525)
		(layer "B.Cu")
		(net "SAS2X28_B_HDD10_RX_-")
	)
	(segment
		(start 32.28848 -356.401116)
		(end 39.588694 -349.100902)
		(width 0.09525)
		(layer "B.Cu")
		(net "SAS2X28_B_HDD10_RX_-")
	)
	(segment
		(start 13.905992 -160.160716)
		(end 5.808218 -160.160716)
		(width 0.09525)
		(layer "B.Cu")
		(net "SAS2X28_B_HDD10_RX_-")
	)
	(segment
		(start 25.641046 -441.313062)
		(end 25.641046 -430.753012)
		(width 0.09525)
		(layer "B.Cu")
		(net "SAS2X28_B_HDD10_RX_-")
	)
	(segment
		(start 34.183574 -189.018418)
		(end 16.378174 -171.213018)
		(width 0.09525)
		(layer "B.Cu")
		(net "SAS2X28_B_HDD10_RX_-")
	)
	(segment
		(start 27.812746 -442.8617)
		(end 27.725116 -442.77407)
		(width 0.09525)
		(layer "B.Cu")
		(net "SAS2X28_B_HDD10_RX_-")
	)
	(segment
		(start 45.643292 -297.65879)
		(end 45.643546 -297.659044)
		(width 0.09525)
		(layer "B.Cu")
		(net "SAS2X28_B_HDD10_RX_-")
	)
	(segment
		(start 39.725346 -348.77121)
		(end 39.725346 -304.564542)
		(width 0.09525)
		(layer "B.Cu")
		(net "SAS2X28_B_HDD10_RX_-")
	)
	(segment
		(start 45.2628 -206.590646)
		(end 34.861246 -196.189092)
		(width 0.09525)
		(layer "B.Cu")
		(net "SAS2X28_B_HDD10_RX_-")
	)
	(segment
		(start 28.09621 -371.517672)
		(end 31.423864 -368.190018)
		(width 0.09525)
		(layer "B.Cu")
		(net "SAS2X28_B_HDD10_RX_-")
	)
	(segment
		(start 26.070814 -429.715422)
		(end 27.315414 -428.470822)
		(width 0.09525)
		(layer "B.Cu")
		(net "SAS2X28_B_HDD10_RX_-")
	)
	(segment
		(start 31.762446 -367.372646)
		(end 31.762446 -357.671116)
		(width 0.09525)
		(layer "B.Cu")
		(net "SAS2X28_B_HDD10_RX_-")
	)
	(segment
		(start 4.986528 -160.49879)
		(end 2.811526 -160.49879)
		(width 0.09525)
		(layer "B.Cu")
		(net "SAS2X28_B_HDD10_RX_-")
	)
	(segment
		(start 16.378174 -171.213018)
		(end 16.378428 -171.212764)
		(width 0.09525)
		(layer "B.Cu")
		(net "SAS2X28_B_HDD10_RX_-")
	)
	(segment
		(start 40.188134 -303.447196)
		(end 45.408088 -298.227242)
		(width 0.09525)
		(layer "B.Cu")
		(net "SAS2X28_B_HDD10_RX_-")
	)
	(segment
		(start 34.183828 -189.018418)
		(end 34.183574 -189.018418)
		(width 0.09525)
		(layer "B.Cu")
		(net "SAS2X28_B_HDD10_RX_-")
	)
	(segment
		(start 34.471356 -195.247768)
		(end 34.471356 -189.7126)
		(width 0.09525)
		(layer "B.Cu")
		(net "SAS2X28_B_HDD10_RX_-")
	)
	(segment
		(start 27.558746 -427.88332)
		(end 27.558746 -372.815358)
		(width 0.09525)
		(layer "B.Cu")
		(net "SAS2X28_B_HDD10_RX_-")
	)
	(segment
		(start 15.798546 -169.812716)
		(end 15.798546 -161.767266)
		(width 0.09525)
		(layer "B.Cu")
		(net "SAS2X28_B_HDD10_RX_-")
	)
	(segment
		(start 45.643546 -297.659044)
		(end 45.643546 -207.509872)
		(width 0.09525)
		(layer "B.Cu")
		(net "SAS2X28_B_HDD10_RX_-")
	)
	(arc
		(start 39.725346 -304.564542)
		(mid 39.845679 -303.959876)
		(end 40.188134 -303.447196)
		(width 0.09525)
		(layer "B.Cu")
		(net "SAS2X28_B_HDD10_RX_-")
	)
	(arc
		(start 25.641046 -430.753012)
		(mid 25.752795 -430.191504)
		(end 26.070814 -429.715422)
		(width 0.09525)
		(layer "B.Cu")
		(net "SAS2X28_B_HDD10_RX_-")
	)
	(arc
		(start 39.588694 -349.100902)
		(mid 39.689873 -348.949667)
		(end 39.725346 -348.77121)
		(width 0.09525)
		(layer "B.Cu")
		(net "SAS2X28_B_HDD10_RX_-")
	)
	(arc
		(start 45.643546 -207.509872)
		(mid 45.544592 -207.012394)
		(end 45.2628 -206.590646)
		(width 0.09525)
		(layer "B.Cu")
		(net "SAS2X28_B_HDD10_RX_-")
	)
	(arc
		(start 27.315414 -428.470822)
		(mid 27.49552 -428.201274)
		(end 27.558746 -427.88332)
		(width 0.09525)
		(layer "B.Cu")
		(net "SAS2X28_B_HDD10_RX_-")
	)
	(arc
		(start 26.917142 -442.4299)
		(mid 26.905712 -442.429844)
		(end 26.894282 -442.4299)
		(width 0.09525)
		(layer "B.Cu")
		(net "SAS2X28_B_HDD10_RX_-")
	)
	(arc
		(start 27.558746 -372.815358)
		(mid 27.698491 -372.113102)
		(end 28.09621 -371.517672)
		(width 0.09525)
		(layer "B.Cu")
		(net "SAS2X28_B_HDD10_RX_-")
	)
	(arc
		(start 34.861246 -196.189092)
		(mid 34.572695 -195.757195)
		(end 34.471356 -195.247768)
		(width 0.09525)
		(layer "B.Cu")
		(net "SAS2X28_B_HDD10_RX_-")
	)
	(arc
		(start 27.725116 -442.77407)
		(mid 27.354493 -442.523659)
		(end 26.917142 -442.4299)
		(width 0.09525)
		(layer "B.Cu")
		(net "SAS2X28_B_HDD10_RX_-")
	)
	(arc
		(start 15.798546 -161.767266)
		(mid 15.691532 -161.229921)
		(end 15.387066 -160.77438)
		(width 0.09525)
		(layer "B.Cu")
		(net "SAS2X28_B_HDD10_RX_-")
	)
	(arc
		(start 25.964134 -442.093096)
		(mid 25.725004 -441.735213)
		(end 25.641046 -441.313062)
		(width 0.09525)
		(layer "B.Cu")
		(net "SAS2X28_B_HDD10_RX_-")
	)
	(arc
		(start 26.894282 -442.4299)
		(mid 26.399677 -442.343059)
		(end 25.964134 -442.093096)
		(width 0.09525)
		(layer "B.Cu")
		(net "SAS2X28_B_HDD10_RX_-")
	)
	(arc
		(start 5.808218 -160.160716)
		(mid 5.49605 -160.222716)
		(end 5.231384 -160.399476)
		(width 0.09525)
		(layer "B.Cu")
		(net "SAS2X28_B_HDD10_RX_-")
	)
	(arc
		(start 15.387066 -160.77438)
		(mid 14.707572 -160.32023)
		(end 13.905992 -160.160716)
		(width 0.09525)
		(layer "B.Cu")
		(net "SAS2X28_B_HDD10_RX_-")
	)
	(arc
		(start 16.378428 -171.212764)
		(mid 15.949254 -170.570416)
		(end 15.798546 -169.812716)
		(width 0.09525)
		(layer "B.Cu")
		(net "SAS2X28_B_HDD10_RX_-")
	)
	(arc
		(start 34.471356 -189.7126)
		(mid 34.396628 -189.336916)
		(end 34.183828 -189.018418)
		(width 0.09525)
		(layer "B.Cu")
		(net "SAS2X28_B_HDD10_RX_-")
	)
	(arc
		(start 31.423864 -368.190018)
		(mid 31.674386 -367.81499)
		(end 31.762446 -367.372646)
		(width 0.09525)
		(layer "B.Cu")
		(net "SAS2X28_B_HDD10_RX_-")
	)
	(arc
		(start 31.762446 -357.671116)
		(mid 31.899214 -356.983829)
		(end 32.28848 -356.401116)
		(width 0.09525)
		(layer "B.Cu")
		(net "SAS2X28_B_HDD10_RX_-")
	)
	(arc
		(start 45.408088 -298.227242)
		(mid 45.582164 -297.966391)
		(end 45.643292 -297.65879)
		(width 0.09525)
		(layer "B.Cu")
		(net "SAS2X28_B_HDD10_RX_-")
	)
	(arc
		(start 5.231384 -160.399476)
		(mid 5.119742 -160.474073)
		(end 4.988052 -160.500314)
		(width 0.09525)
		(layer "B.Cu")
		(net "SAS2X28_B_HDD10_RX_-")
	)
	(segment
		(start 223.244918 -276.845014)
		(end 223.249998 -276.850094)
		(width 0.111252)
		(layer "F.Cu")
		(net "HDD_PRSNT_NET2")
	)
	(segment
		(start 216.492582 -276.197568)
		(end 217.572082 -276.197568)
		(width 0.111252)
		(layer "F.Cu")
		(net "HDD_PRSNT_NET2")
	)
	(segment
		(start 219.582746 -276.3647)
		(end 220.06306 -276.845014)
		(width 0.111252)
		(layer "F.Cu")
		(net "HDD_PRSNT_NET2")
	)
	(segment
		(start 215.286082 -276.197568)
		(end 216.492582 -276.197568)
		(width 0.111252)
		(layer "F.Cu")
		(net "HDD_PRSNT_NET2")
	)
	(segment
		(start 215.2777 -274.2819)
		(end 215.2777 -275.1328)
		(width 0.111252)
		(layer "F.Cu")
		(net "HDD_PRSNT_NET2")
	)
	(segment
		(start 217.572082 -276.197568)
		(end 217.635582 -276.261068)
		(width 0.111252)
		(layer "F.Cu")
		(net "HDD_PRSNT_NET2")
	)
	(segment
		(start 217.739214 -276.3647)
		(end 219.582746 -276.3647)
		(width 0.111252)
		(layer "F.Cu")
		(net "HDD_PRSNT_NET2")
	)
	(segment
		(start 214.9856 -273.9898)
		(end 215.2777 -274.2819)
		(width 0.111252)
		(layer "F.Cu")
		(net "HDD_PRSNT_NET2")
	)
	(segment
		(start 217.635582 -276.261068)
		(end 217.739214 -276.3647)
		(width 0.111252)
		(layer "F.Cu")
		(net "HDD_PRSNT_NET2")
	)
	(segment
		(start 215.2777 -276.189186)
		(end 215.286082 -276.197568)
		(width 0.111252)
		(layer "F.Cu")
		(net "HDD_PRSNT_NET2")
	)
	(segment
		(start 215.2777 -275.1328)
		(end 215.2777 -276.189186)
		(width 0.111252)
		(layer "F.Cu")
		(net "HDD_PRSNT_NET2")
	)
	(segment
		(start 220.06306 -276.845014)
		(end 223.244918 -276.845014)
		(width 0.111252)
		(layer "F.Cu")
		(net "HDD_PRSNT_NET2")
	)
	(via
		(at 214.9856 -273.9898)
		(size 0.7112)
		(drill 0.3556)
		(layers "F.Cu" "B.Cu")
		(net "HDD_PRSNT_NET2")
	)
	(segment
		(start 215.7857 -379.036326)
		(end 215.792558 -379.043184)
		(width 0.111252)
		(layer "F.Cu")
		(net "HDD_PRSNT_NET1")
	)
	(segment
		(start 218.142058 -379.106684)
		(end 220.34373 -379.106684)
		(width 0.111252)
		(layer "F.Cu")
		(net "HDD_PRSNT_NET1")
	)
	(segment
		(start 216.999058 -379.043184)
		(end 218.078558 -379.043184)
		(width 0.111252)
		(layer "F.Cu")
		(net "HDD_PRSNT_NET1")
	)
	(segment
		(start 215.792558 -379.043184)
		(end 216.999058 -379.043184)
		(width 0.111252)
		(layer "F.Cu")
		(net "HDD_PRSNT_NET1")
	)
	(segment
		(start 215.4682 -377.5202)
		(end 215.7857 -377.8377)
		(width 0.111252)
		(layer "F.Cu")
		(net "HDD_PRSNT_NET1")
	)
	(segment
		(start 215.7857 -377.8377)
		(end 215.7857 -377.9774)
		(width 0.111252)
		(layer "F.Cu")
		(net "HDD_PRSNT_NET1")
	)
	(segment
		(start 221.087188 -379.850142)
		(end 223.249998 -379.850142)
		(width 0.111252)
		(layer "F.Cu")
		(net "HDD_PRSNT_NET1")
	)
	(segment
		(start 220.34373 -379.106684)
		(end 221.087188 -379.850142)
		(width 0.111252)
		(layer "F.Cu")
		(net "HDD_PRSNT_NET1")
	)
	(segment
		(start 215.7857 -377.9774)
		(end 215.7857 -379.036326)
		(width 0.111252)
		(layer "F.Cu")
		(net "HDD_PRSNT_NET1")
	)
	(segment
		(start 215.4682 -376.682)
		(end 215.4682 -377.5202)
		(width 0.111252)
		(layer "F.Cu")
		(net "HDD_PRSNT_NET1")
	)
	(segment
		(start 218.078558 -379.043184)
		(end 218.142058 -379.106684)
		(width 0.111252)
		(layer "F.Cu")
		(net "HDD_PRSNT_NET1")
	)
	(via
		(at 215.4682 -376.682)
		(size 0.7112)
		(drill 0.3556)
		(layers "F.Cu" "B.Cu")
		(net "HDD_PRSNT_NET1")
	)
	(segment
		(start 218.202256 -482.120702)
		(end 218.265756 -482.184202)
		(width 0.111252)
		(layer "F.Cu")
		(net "HDD_PRSNT_NET0")
	)
	(segment
		(start 217.122756 -482.120702)
		(end 218.202256 -482.120702)
		(width 0.111252)
		(layer "F.Cu")
		(net "HDD_PRSNT_NET0")
	)
	(segment
		(start 215.912446 -481.0379)
		(end 215.8492 -480.9236)
		(width 0.111252)
		(layer "F.Cu")
		(net "HDD_PRSNT_NET0")
	)
	(segment
		(start 215.912446 -481.0379)
		(end 216.039954 -481.0379)
		(width 0.111252)
		(layer "F.Cu")
		(net "HDD_PRSNT_NET0")
	)
	(segment
		(start 220.27896 -482.527102)
		(end 218.608656 -482.527102)
		(width 0.111252)
		(layer "F.Cu")
		(net "HDD_PRSNT_NET0")
	)
	(segment
		(start 218.608656 -482.527102)
		(end 218.265756 -482.184202)
		(width 0.111252)
		(layer "F.Cu")
		(net "HDD_PRSNT_NET0")
	)
	(segment
		(start 216.039954 -481.0379)
		(end 217.122756 -482.120702)
		(width 0.111252)
		(layer "F.Cu")
		(net "HDD_PRSNT_NET0")
	)
	(segment
		(start 215.916256 -482.120702)
		(end 215.916256 -481.04171)
		(width 0.111252)
		(layer "F.Cu")
		(net "HDD_PRSNT_NET0")
	)
	(segment
		(start 215.8492 -480.9236)
		(end 215.8492 -479.6282)
		(width 0.111252)
		(layer "F.Cu")
		(net "HDD_PRSNT_NET0")
	)
	(segment
		(start 223.249998 -482.85019)
		(end 220.602048 -482.85019)
		(width 0.111252)
		(layer "F.Cu")
		(net "HDD_PRSNT_NET0")
	)
	(segment
		(start 215.916256 -481.04171)
		(end 215.912446 -481.0379)
		(width 0.111252)
		(layer "F.Cu")
		(net "HDD_PRSNT_NET0")
	)
	(segment
		(start 220.602048 -482.85019)
		(end 220.27896 -482.527102)
		(width 0.111252)
		(layer "F.Cu")
		(net "HDD_PRSNT_NET0")
	)
	(via
		(at 215.8492 -479.6282)
		(size 0.7112)
		(drill 0.3556)
		(layers "F.Cu" "B.Cu")
		(net "HDD_PRSNT_NET0")
	)
	(segment
		(start 195.635118 -286.088328)
		(end 194.839082 -286.088328)
		(width 0.111252)
		(layer "F.Cu")
		(net "SAS_EXP_B_PWR2")
	)
	(segment
		(start 196.087746 -285.6357)
		(end 195.635118 -286.088328)
		(width 0.111252)
		(layer "F.Cu")
		(net "SAS_EXP_B_PWR2")
	)
	(segment
		(start 196.913246 -285.3817)
		(end 196.341746 -285.3817)
		(width 0.111252)
		(layer "F.Cu")
		(net "SAS_EXP_B_PWR2")
	)
	(segment
		(start 3.231388 -202.4634)
		(end 11.388598 -202.4634)
		(width 0.111252)
		(layer "F.Cu")
		(net "SAS_EXP_B_PWR2")
	)
	(segment
		(start 12.937998 -204.0128)
		(end 27.8638 -204.0128)
		(width 0.111252)
		(layer "F.Cu")
		(net "SAS_EXP_B_PWR2")
	)
	(segment
		(start 196.341746 -285.3817)
		(end 196.087746 -285.6357)
		(width 0.111252)
		(layer "F.Cu")
		(net "SAS_EXP_B_PWR2")
	)
	(segment
		(start 11.388598 -202.4634)
		(end 12.937998 -204.0128)
		(width 0.111252)
		(layer "F.Cu")
		(net "SAS_EXP_B_PWR2")
	)
	(segment
		(start 3.19024 -202.504548)
		(end 3.231388 -202.4634)
		(width 0.111252)
		(layer "F.Cu")
		(net "SAS_EXP_B_PWR2")
	)
	(via
		(at 27.8638 -204.0128)
		(size 0.5588)
		(drill 0.3048)
		(layers "F.Cu" "B.Cu")
		(net "SAS_EXP_B_PWR2")
	)
	(via
		(at 195.149724 -285.577534)
		(size 0.7112)
		(drill 0.3556)
		(layers "F.Cu" "B.Cu")
		(net "SAS_EXP_B_PWR2")
	)
	(via
		(at 87.756746 -278.5237)
		(size 0.5588)
		(drill 0.3048)
		(layers "F.Cu" "B.Cu")
		(net "SAS_EXP_B_PWR2")
	)
	(via
		(at 196.087746 -285.6357)
		(size 0.5588)
		(drill 0.3048)
		(layers "F.Cu" "B.Cu")
		(net "SAS_EXP_B_PWR2")
	)
	(segment
		(start 196.02958 -285.577534)
		(end 195.149724 -285.577534)
		(width 0.111252)
		(layer "B.Cu")
		(net "SAS_EXP_B_PWR2")
	)
	(segment
		(start 196.087746 -285.6357)
		(end 196.02958 -285.577534)
		(width 0.111252)
		(layer "B.Cu")
		(net "SAS_EXP_B_PWR2")
	)
	(segment
		(start 188.975746 -278.5237)
		(end 87.756746 -278.5237)
		(width 0.14605)
		(layer "In2.Cu")
		(net "SAS_EXP_B_PWR2")
	)
	(segment
		(start 196.087746 -285.6357)
		(end 188.975746 -278.5237)
		(width 0.14605)
		(layer "In2.Cu")
		(net "SAS_EXP_B_PWR2")
	)
	(segment
		(start 87.756746 -206.933546)
		(end 81.7753 -200.9521)
		(width 0.14605)
		(layer "In5.Cu")
		(net "SAS_EXP_B_PWR2")
	)
	(segment
		(start 87.756746 -278.5237)
		(end 87.756746 -206.933546)
		(width 0.14605)
		(layer "In5.Cu")
		(net "SAS_EXP_B_PWR2")
	)
	(segment
		(start 27.20975 -203.380086)
		(end 27.842464 -204.0128)
		(width 0.14605)
		(layer "In5.Cu")
		(net "SAS_EXP_B_PWR2")
	)
	(segment
		(start 27.941778 -201.628248)
		(end 27.919172 -201.628248)
		(width 0.14605)
		(layer "In5.Cu")
		(net "SAS_EXP_B_PWR2")
	)
	(segment
		(start 81.7753 -200.9521)
		(end 28.617926 -200.9521)
		(width 0.14605)
		(layer "In5.Cu")
		(net "SAS_EXP_B_PWR2")
	)
	(segment
		(start 27.842464 -204.0128)
		(end 27.8638 -204.0128)
		(width 0.14605)
		(layer "In5.Cu")
		(net "SAS_EXP_B_PWR2")
	)
	(segment
		(start 27.638248 -201.909172)
		(end 27.638248 -201.931778)
		(width 0.14605)
		(layer "In5.Cu")
		(net "SAS_EXP_B_PWR2")
	)
	(segment
		(start 27.919172 -201.628248)
		(end 27.638248 -201.909172)
		(width 0.14605)
		(layer "In5.Cu")
		(net "SAS_EXP_B_PWR2")
	)
	(segment
		(start 27.638248 -201.931778)
		(end 27.20975 -202.360276)
		(width 0.14605)
		(layer "In5.Cu")
		(net "SAS_EXP_B_PWR2")
	)
	(segment
		(start 27.20975 -202.360276)
		(end 27.20975 -203.380086)
		(width 0.14605)
		(layer "In5.Cu")
		(net "SAS_EXP_B_PWR2")
	)
	(segment
		(start 28.617926 -200.9521)
		(end 27.941778 -201.628248)
		(width 0.14605)
		(layer "In5.Cu")
		(net "SAS_EXP_B_PWR2")
	)
	(segment
		(start 187.718446 -455.646536)
		(end 188.988446 -456.916536)
		(width 0.111252)
		(layer "F.Cu")
		(net "EEPROM_A2")
	)
	(segment
		(start 189.686946 -456.916536)
		(end 190.004446 -457.234036)
		(width 0.111252)
		(layer "F.Cu")
		(net "EEPROM_A2")
	)
	(segment
		(start 188.988446 -456.916536)
		(end 189.686946 -456.916536)
		(width 0.111252)
		(layer "F.Cu")
		(net "EEPROM_A2")
	)
	(segment
		(start 190.004446 -457.869036)
		(end 190.314326 -458.178916)
		(width 0.111252)
		(layer "F.Cu")
		(net "EEPROM_A2")
	)
	(segment
		(start 187.464446 -456.408536)
		(end 187.464446 -455.646536)
		(width 0.111252)
		(layer "F.Cu")
		(net "EEPROM_A2")
	)
	(segment
		(start 187.464446 -455.646536)
		(end 187.718446 -455.646536)
		(width 0.111252)
		(layer "F.Cu")
		(net "EEPROM_A2")
	)
	(segment
		(start 187.908946 -456.853036)
		(end 187.464446 -456.408536)
		(width 0.111252)
		(layer "F.Cu")
		(net "EEPROM_A2")
	)
	(segment
		(start 190.004446 -457.234036)
		(end 190.004446 -457.869036)
		(width 0.111252)
		(layer "F.Cu")
		(net "EEPROM_A2")
	)
	(segment
		(start 190.314326 -458.178916)
		(end 191.503046 -458.178916)
		(width 0.111252)
		(layer "F.Cu")
		(net "EEPROM_A2")
	)
	(via
		(at 187.464446 -455.646536)
		(size 0.7112)
		(drill 0.3556)
		(layers "F.Cu" "B.Cu")
		(net "EEPROM_A2")
	)
	(segment
		(start 57.225692 -71.402956)
		(end 57.225692 -70.497446)
		(width 0.111252)
		(layer "F.Cu")
		(net "HDD_PRSNT9")
	)
	(segment
		(start 56.260492 -71.402956)
		(end 56.260492 -70.218554)
		(width 0.111252)
		(layer "F.Cu")
		(net "HDD_PRSNT9")
	)
	(segment
		(start 56.260492 -70.218554)
		(end 56.336946 -70.1421)
		(width 0.111252)
		(layer "F.Cu")
		(net "HDD_PRSNT9")
	)
	(segment
		(start 57.225692 -70.497446)
		(end 56.870346 -70.1421)
		(width 0.111252)
		(layer "F.Cu")
		(net "HDD_PRSNT9")
	)
	(segment
		(start 56.870346 -70.1421)
		(end 56.336946 -70.1421)
		(width 0.111252)
		(layer "F.Cu")
		(net "HDD_PRSNT9")
	)
	(via
		(at 8.9662 -200.50125)
		(size 0.5588)
		(drill 0.3048)
		(layers "F.Cu" "B.Cu")
		(net "HDD_PRSNT9")
	)
	(via
		(at 10.73785 -445.516)
		(size 0.5588)
		(drill 0.3048)
		(layers "F.Cu" "B.Cu")
		(net "HDD_PRSNT9")
	)
	(via
		(at 57.225692 -71.402956)
		(size 0.5588)
		(drill 0.3048)
		(layers "F.Cu" "B.Cu")
		(net "HDD_PRSNT9")
	)
	(via
		(at 56.336946 -70.1421)
		(size 0.7112)
		(drill 0.3556)
		(layers "F.Cu" "B.Cu")
		(net "HDD_PRSNT9")
	)
	(via
		(at 11.112754 -452.261986)
		(size 0.5588)
		(drill 0.3048)
		(layers "F.Cu" "B.Cu")
		(net "HDD_PRSNT9")
	)
	(segment
		(start 6.812534 -452.501254)
		(end 2.812542 -452.501254)
		(width 0.111252)
		(layer "B.Cu")
		(net "HDD_PRSNT9")
	)
	(segment
		(start 7.497572 -451.816216)
		(end 6.812534 -452.501254)
		(width 0.111252)
		(layer "B.Cu")
		(net "HDD_PRSNT9")
	)
	(segment
		(start 10.666984 -451.816216)
		(end 7.497572 -451.816216)
		(width 0.111252)
		(layer "B.Cu")
		(net "HDD_PRSNT9")
	)
	(segment
		(start 2.812542 -200.50125)
		(end 2.80924 -200.504552)
		(width 0.111252)
		(layer "B.Cu")
		(net "HDD_PRSNT9")
	)
	(segment
		(start 2.812542 -452.501254)
		(end 2.80924 -452.504556)
		(width 0.111252)
		(layer "B.Cu")
		(net "HDD_PRSNT9")
	)
	(segment
		(start 8.9662 -200.50125)
		(end 2.812542 -200.50125)
		(width 0.111252)
		(layer "B.Cu")
		(net "HDD_PRSNT9")
	)
	(segment
		(start 11.112754 -452.261986)
		(end 10.666984 -451.816216)
		(width 0.111252)
		(layer "B.Cu")
		(net "HDD_PRSNT9")
	)
	(segment
		(start 15.54099 -268.8336)
		(end 17.967706 -266.406884)
		(width 0.14605)
		(layer "In2.Cu")
		(net "HDD_PRSNT9")
	)
	(segment
		(start 14.267942 -206.762858)
		(end 14.774926 -206.255874)
		(width 0.14605)
		(layer "In2.Cu")
		(net "HDD_PRSNT9")
	)
	(segment
		(start 14.267942 -211.282534)
		(end 14.267942 -206.762858)
		(width 0.14605)
		(layer "In2.Cu")
		(net "HDD_PRSNT9")
	)
	(segment
		(start 14.813788 -415.196274)
		(end 14.813788 -396.986506)
		(width 0.14605)
		(layer "In2.Cu")
		(net "HDD_PRSNT9")
	)
	(segment
		(start 15.54099 -364.490254)
		(end 15.54099 -268.8336)
		(width 0.14605)
		(layer "In2.Cu")
		(net "HDD_PRSNT9")
	)
	(segment
		(start 15.54099 -376.563382)
		(end 16.002 -376.102372)
		(width 0.14605)
		(layer "In2.Cu")
		(net "HDD_PRSNT9")
	)
	(segment
		(start 15.232888 -255.5494)
		(end 15.232888 -216.773506)
		(width 0.14605)
		(layer "In2.Cu")
		(net "HDD_PRSNT9")
	)
	(segment
		(start 14.774926 -203.344272)
		(end 11.931904 -200.50125)
		(width 0.14605)
		(layer "In2.Cu")
		(net "HDD_PRSNT9")
	)
	(segment
		(start 15.198344 -216.738962)
		(end 15.198344 -213.251288)
		(width 0.14605)
		(layer "In2.Cu")
		(net "HDD_PRSNT9")
	)
	(segment
		(start 16.002 -376.102372)
		(end 16.002 -364.951264)
		(width 0.14605)
		(layer "In2.Cu")
		(net "HDD_PRSNT9")
	)
	(segment
		(start 11.931904 -200.50125)
		(end 8.9662 -200.50125)
		(width 0.14605)
		(layer "In2.Cu")
		(net "HDD_PRSNT9")
	)
	(segment
		(start 14.813788 -396.986506)
		(end 14.963648 -396.836646)
		(width 0.14605)
		(layer "In2.Cu")
		(net "HDD_PRSNT9")
	)
	(segment
		(start 16.002 -364.951264)
		(end 15.54099 -364.490254)
		(width 0.14605)
		(layer "In2.Cu")
		(net "HDD_PRSNT9")
	)
	(segment
		(start 10.73785 -445.516)
		(end 14.63929 -441.61456)
		(width 0.14605)
		(layer "In2.Cu")
		(net "HDD_PRSNT9")
	)
	(segment
		(start 14.963648 -396.836646)
		(end 14.963648 -395.00302)
		(width 0.14605)
		(layer "In2.Cu")
		(net "HDD_PRSNT9")
	)
	(segment
		(start 10.73785 -445.516)
		(end 10.584434 -445.669416)
		(width 0.14605)
		(layer "In2.Cu")
		(net "HDD_PRSNT9")
	)
	(segment
		(start 11.112754 -452.086726)
		(end 11.112754 -452.261986)
		(width 0.14605)
		(layer "In2.Cu")
		(net "HDD_PRSNT9")
	)
	(segment
		(start 14.63929 -415.370772)
		(end 14.813788 -415.196274)
		(width 0.14605)
		(layer "In2.Cu")
		(net "HDD_PRSNT9")
	)
	(segment
		(start 10.584434 -445.669416)
		(end 10.584434 -451.558406)
		(width 0.14605)
		(layer "In2.Cu")
		(net "HDD_PRSNT9")
	)
	(segment
		(start 17.967706 -259.494274)
		(end 15.85595 -257.382518)
		(width 0.14605)
		(layer "In2.Cu")
		(net "HDD_PRSNT9")
	)
	(segment
		(start 15.232888 -216.773506)
		(end 15.198344 -216.738962)
		(width 0.14605)
		(layer "In2.Cu")
		(net "HDD_PRSNT9")
	)
	(segment
		(start 15.198344 -213.251288)
		(end 15.389098 -213.060534)
		(width 0.14605)
		(layer "In2.Cu")
		(net "HDD_PRSNT9")
	)
	(segment
		(start 10.584434 -451.558406)
		(end 11.112754 -452.086726)
		(width 0.14605)
		(layer "In2.Cu")
		(net "HDD_PRSNT9")
	)
	(segment
		(start 14.774926 -206.255874)
		(end 14.774926 -203.344272)
		(width 0.14605)
		(layer "In2.Cu")
		(net "HDD_PRSNT9")
	)
	(segment
		(start 15.85595 -257.382518)
		(end 15.85595 -256.172462)
		(width 0.14605)
		(layer "In2.Cu")
		(net "HDD_PRSNT9")
	)
	(segment
		(start 15.389098 -212.40369)
		(end 14.267942 -211.282534)
		(width 0.14605)
		(layer "In2.Cu")
		(net "HDD_PRSNT9")
	)
	(segment
		(start 15.54099 -394.425678)
		(end 15.54099 -376.563382)
		(width 0.14605)
		(layer "In2.Cu")
		(net "HDD_PRSNT9")
	)
	(segment
		(start 15.389098 -213.060534)
		(end 15.389098 -212.40369)
		(width 0.14605)
		(layer "In2.Cu")
		(net "HDD_PRSNT9")
	)
	(segment
		(start 17.967706 -266.406884)
		(end 17.967706 -259.494274)
		(width 0.14605)
		(layer "In2.Cu")
		(net "HDD_PRSNT9")
	)
	(segment
		(start 14.63929 -441.61456)
		(end 14.63929 -415.370772)
		(width 0.14605)
		(layer "In2.Cu")
		(net "HDD_PRSNT9")
	)
	(segment
		(start 14.963648 -395.00302)
		(end 15.54099 -394.425678)
		(width 0.14605)
		(layer "In2.Cu")
		(net "HDD_PRSNT9")
	)
	(segment
		(start 15.85595 -256.172462)
		(end 15.232888 -255.5494)
		(width 0.14605)
		(layer "In2.Cu")
		(net "HDD_PRSNT9")
	)
	(segment
		(start 51.379374 -452.866252)
		(end 51.439826 -452.8058)
		(width 0.14605)
		(layer "In5.Cu")
		(net "HDD_PRSNT9")
	)
	(segment
		(start 50.921666 -452.8058)
		(end 50.982118 -452.866252)
		(width 0.14605)
		(layer "In5.Cu")
		(net "HDD_PRSNT9")
	)
	(segment
		(start 11.244072 -445.516)
		(end 11.247374 -445.512698)
		(width 0.14605)
		(layer "In5.Cu")
		(net "HDD_PRSNT9")
	)
	(segment
		(start 100.704396 -159.95777)
		(end 100.704396 -103.717344)
		(width 0.14605)
		(layer "In5.Cu")
		(net "HDD_PRSNT9")
	)
	(segment
		(start 100.704396 -160.38703)
		(end 100.720398 -160.371028)
		(width 0.14605)
		(layer "In5.Cu")
		(net "HDD_PRSNT9")
	)
	(segment
		(start 100.720398 -159.973772)
		(end 100.704396 -159.95777)
		(width 0.14605)
		(layer "In5.Cu")
		(net "HDD_PRSNT9")
	)
	(segment
		(start 100.571046 -98.661728)
		(end 73.312274 -71.402956)
		(width 0.14605)
		(layer "In5.Cu")
		(net "HDD_PRSNT9")
	)
	(segment
		(start 10.73785 -445.516)
		(end 11.244072 -445.516)
		(width 0.14605)
		(layer "In5.Cu")
		(net "HDD_PRSNT9")
	)
	(segment
		(start 12.018518 -445.512698)
		(end 12.02182 -445.516)
		(width 0.14605)
		(layer "In5.Cu")
		(net "HDD_PRSNT9")
	)
	(segment
		(start 18.418048 -451.807834)
		(end 18.418048 -451.836028)
		(width 0.14605)
		(layer "In5.Cu")
		(net "HDD_PRSNT9")
	)
	(segment
		(start 100.720398 -160.371028)
		(end 100.720398 -159.973772)
		(width 0.14605)
		(layer "In5.Cu")
		(net "HDD_PRSNT9")
	)
	(segment
		(start 12.02182 -445.516)
		(end 12.126214 -445.516)
		(width 0.14605)
		(layer "In5.Cu")
		(net "HDD_PRSNT9")
	)
	(segment
		(start 11.247374 -445.512698)
		(end 12.018518 -445.512698)
		(width 0.14605)
		(layer "In5.Cu")
		(net "HDD_PRSNT9")
	)
	(segment
		(start 100.704396 -103.717344)
		(end 100.571046 -103.583994)
		(width 0.14605)
		(layer "In5.Cu")
		(net "HDD_PRSNT9")
	)
	(segment
		(start 18.418048 -451.836028)
		(end 19.38782 -452.8058)
		(width 0.14605)
		(layer "In5.Cu")
		(net "HDD_PRSNT9")
	)
	(segment
		(start 73.312274 -71.402956)
		(end 57.225692 -71.402956)
		(width 0.14605)
		(layer "In5.Cu")
		(net "HDD_PRSNT9")
	)
	(segment
		(start 100.571046 -103.583994)
		(end 100.571046 -98.661728)
		(width 0.14605)
		(layer "In5.Cu")
		(net "HDD_PRSNT9")
	)
	(segment
		(start 19.38782 -452.8058)
		(end 50.921666 -452.8058)
		(width 0.14605)
		(layer "In5.Cu")
		(net "HDD_PRSNT9")
	)
	(segment
		(start 50.982118 -452.866252)
		(end 51.379374 -452.866252)
		(width 0.14605)
		(layer "In5.Cu")
		(net "HDD_PRSNT9")
	)
	(segment
		(start 87.12962 -452.8058)
		(end 100.704396 -439.231024)
		(width 0.14605)
		(layer "In5.Cu")
		(net "HDD_PRSNT9")
	)
	(segment
		(start 100.704396 -439.231024)
		(end 100.704396 -160.38703)
		(width 0.14605)
		(layer "In5.Cu")
		(net "HDD_PRSNT9")
	)
	(segment
		(start 12.126214 -445.516)
		(end 18.418048 -451.807834)
		(width 0.14605)
		(layer "In5.Cu")
		(net "HDD_PRSNT9")
	)
	(segment
		(start 51.439826 -452.8058)
		(end 87.12962 -452.8058)
		(width 0.14605)
		(layer "In5.Cu")
		(net "HDD_PRSNT9")
	)
	(segment
		(start 188.988446 -458.821536)
		(end 187.972446 -458.821536)
		(width 0.111252)
		(layer "F.Cu")
		(net "EEPROM_A1")
	)
	(segment
		(start 187.972446 -458.821536)
		(end 187.908946 -458.885036)
		(width 0.111252)
		(layer "F.Cu")
		(net "EEPROM_A1")
	)
	(segment
		(start 187.908946 -458.885036)
		(end 186.969146 -457.945236)
		(width 0.111252)
		(layer "F.Cu")
		(net "EEPROM_A1")
	)
	(segment
		(start 186.969146 -457.945236)
		(end 186.067446 -457.945236)
		(width 0.111252)
		(layer "F.Cu")
		(net "EEPROM_A1")
	)
	(segment
		(start 191.503046 -458.829156)
		(end 188.996066 -458.829156)
		(width 0.111252)
		(layer "F.Cu")
		(net "EEPROM_A1")
	)
	(segment
		(start 188.996066 -458.829156)
		(end 188.988446 -458.821536)
		(width 0.111252)
		(layer "F.Cu")
		(net "EEPROM_A1")
	)
	(via
		(at 186.067446 -457.945236)
		(size 0.7112)
		(drill 0.3556)
		(layers "F.Cu" "B.Cu")
		(net "EEPROM_A1")
	)
	(segment
		(start 32.268668 -63.3857)
		(end 31.43631 -63.3857)
		(width 0.09525)
		(layer "F.Cu")
		(net "SAS2X28_B_HDD9_RX_-")
	)
	(via
		(at 31.190946 -63.2841)
		(size 0.5588)
		(drill 0.3048)
		(layers "F.Cu" "B.Cu")
		(net "SAS2X28_B_HDD9_RX_-")
	)
	(arc
		(start 31.43631 -63.3857)
		(mid 31.303533 -63.359289)
		(end 31.190946 -63.2841)
		(width 0.09525)
		(layer "F.Cu")
		(net "SAS2X28_B_HDD9_RX_-")
	)
	(arc
		(start 32.575246 -63.2587)
		(mid 32.434587 -63.352685)
		(end 32.268668 -63.3857)
		(width 0.09525)
		(layer "F.Cu")
		(net "SAS2X28_B_HDD9_RX_-")
	)
	(segment
		(start 32.460946 -64.0969)
		(end 32.460946 -64.892682)
		(width 0.09525)
		(layer "B.Cu")
		(net "SAS2X28_B_HDD9_RX_-")
	)
	(segment
		(start 5.462016 -104.30637)
		(end 5.411216 -104.35717)
		(width 0.09525)
		(layer "B.Cu")
		(net "SAS2X28_B_HDD9_RX_-")
	)
	(segment
		(start 19.046444 -94.123002)
		(end 9.206992 -103.962454)
		(width 0.09525)
		(layer "B.Cu")
		(net "SAS2X28_B_HDD9_RX_-")
	)
	(segment
		(start 5.066538 -104.499918)
		(end 2.81305 -104.499918)
		(width 0.09525)
		(layer "B.Cu")
		(net "SAS2X28_B_HDD9_RX_-")
	)
	(segment
		(start 19.329146 -78.56855)
		(end 19.329146 -93.440504)
		(width 0.09525)
		(layer "B.Cu")
		(net "SAS2X28_B_HDD9_RX_-")
	)
	(segment
		(start 2.81305 -104.499918)
		(end 2.811526 -104.498394)
		(width 0.09525)
		(layer "B.Cu")
		(net "SAS2X28_B_HDD9_RX_-")
	)
	(segment
		(start 8.680196 -104.18064)
		(end 5.765546 -104.18064)
		(width 0.09525)
		(layer "B.Cu")
		(net "SAS2X28_B_HDD9_RX_-")
	)
	(segment
		(start 31.190946 -63.2841)
		(end 31.293816 -63.38697)
		(width 0.09525)
		(layer "B.Cu")
		(net "SAS2X28_B_HDD9_RX_-")
	)
	(segment
		(start 32.262826 -65.371472)
		(end 30.021276 -67.613276)
		(width 0.09525)
		(layer "B.Cu")
		(net "SAS2X28_B_HDD9_RX_-")
	)
	(segment
		(start 30.021276 -67.613276)
		(end 19.515074 -78.119478)
		(width 0.09525)
		(layer "B.Cu")
		(net "SAS2X28_B_HDD9_RX_-")
	)
	(segment
		(start 31.597346 -63.5127)
		(end 31.876746 -63.5127)
		(width 0.09525)
		(layer "B.Cu")
		(net "SAS2X28_B_HDD9_RX_-")
	)
	(segment
		(start 32.262572 -65.371218)
		(end 32.262826 -65.371472)
		(width 0.09525)
		(layer "B.Cu")
		(net "SAS2X28_B_HDD9_RX_-")
	)
	(arc
		(start 5.765546 -104.18064)
		(mid 5.601275 -104.213315)
		(end 5.462016 -104.30637)
		(width 0.09525)
		(layer "B.Cu")
		(net "SAS2X28_B_HDD9_RX_-")
	)
	(arc
		(start 5.411216 -104.35717)
		(mid 5.253076 -104.462836)
		(end 5.066538 -104.499918)
		(width 0.09525)
		(layer "B.Cu")
		(net "SAS2X28_B_HDD9_RX_-")
	)
	(arc
		(start 31.876746 -63.5127)
		(mid 32.289838 -63.683808)
		(end 32.460946 -64.0969)
		(width 0.09525)
		(layer "B.Cu")
		(net "SAS2X28_B_HDD9_RX_-")
	)
	(arc
		(start 19.329146 -93.440504)
		(mid 19.255675 -93.80987)
		(end 19.046444 -94.123002)
		(width 0.09525)
		(layer "B.Cu")
		(net "SAS2X28_B_HDD9_RX_-")
	)
	(arc
		(start 32.460946 -64.892682)
		(mid 32.409336 -65.151671)
		(end 32.262572 -65.371218)
		(width 0.09525)
		(layer "B.Cu")
		(net "SAS2X28_B_HDD9_RX_-")
	)
	(arc
		(start 31.293816 -63.38697)
		(mid 31.433077 -63.480021)
		(end 31.597346 -63.5127)
		(width 0.09525)
		(layer "B.Cu")
		(net "SAS2X28_B_HDD9_RX_-")
	)
	(arc
		(start 9.206992 -103.962454)
		(mid 8.965296 -104.12395)
		(end 8.680196 -104.18064)
		(width 0.09525)
		(layer "B.Cu")
		(net "SAS2X28_B_HDD9_RX_-")
	)
	(arc
		(start 19.515074 -78.119478)
		(mid 19.377405 -78.325514)
		(end 19.329146 -78.56855)
		(width 0.09525)
		(layer "B.Cu")
		(net "SAS2X28_B_HDD9_RX_-")
	)
	(segment
		(start 189.305946 -460.409036)
		(end 190.131446 -460.409036)
		(width 0.111252)
		(layer "F.Cu")
		(net "EEPROM_A0")
	)
	(segment
		(start 188.988446 -461.425036)
		(end 188.988446 -460.726536)
		(width 0.111252)
		(layer "F.Cu")
		(net "EEPROM_A0")
	)
	(segment
		(start 188.988446 -460.726536)
		(end 189.305946 -460.409036)
		(width 0.111252)
		(layer "F.Cu")
		(net "EEPROM_A0")
	)
	(segment
		(start 188.353446 -461.869536)
		(end 188.543946 -461.869536)
		(width 0.111252)
		(layer "F.Cu")
		(net "EEPROM_A0")
	)
	(segment
		(start 187.908946 -460.790036)
		(end 187.908946 -461.425036)
		(width 0.111252)
		(layer "F.Cu")
		(net "EEPROM_A0")
	)
	(segment
		(start 191.061086 -459.479396)
		(end 191.503046 -459.479396)
		(width 0.111252)
		(layer "F.Cu")
		(net "EEPROM_A0")
	)
	(segment
		(start 188.543946 -461.869536)
		(end 188.988446 -461.425036)
		(width 0.111252)
		(layer "F.Cu")
		(net "EEPROM_A0")
	)
	(segment
		(start 187.908946 -461.425036)
		(end 188.353446 -461.869536)
		(width 0.111252)
		(layer "F.Cu")
		(net "EEPROM_A0")
	)
	(segment
		(start 190.131446 -460.409036)
		(end 191.061086 -459.479396)
		(width 0.111252)
		(layer "F.Cu")
		(net "EEPROM_A0")
	)
	(via
		(at 188.353446 -461.869536)
		(size 0.7112)
		(drill 0.3556)
		(layers "F.Cu" "B.Cu")
		(net "EEPROM_A0")
	)
	(segment
		(start 31.267146 -63.7921)
		(end 31.190692 -63.868554)
		(width 0.09525)
		(layer "F.Cu")
		(net "SAS2X28_B_HDD9_RX_+")
	)
	(segment
		(start 32.026606 -63.7159)
		(end 31.451042 -63.7159)
		(width 0.09525)
		(layer "F.Cu")
		(net "SAS2X28_B_HDD9_RX_+")
	)
	(segment
		(start 32.575246 -64.1477)
		(end 32.225996 -63.79845)
		(width 0.09525)
		(layer "F.Cu")
		(net "SAS2X28_B_HDD9_RX_+")
	)
	(segment
		(start 31.088838 -64.114426)
		(end 31.088838 -64.182752)
		(width 0.09525)
		(layer "F.Cu")
		(net "SAS2X28_B_HDD9_RX_+")
	)
	(via
		(at 31.088838 -64.182752)
		(size 0.5588)
		(drill 0.3048)
		(layers "F.Cu" "B.Cu")
		(net "SAS2X28_B_HDD9_RX_+")
	)
	(arc
		(start 32.225996 -63.79845)
		(mid 32.134515 -63.737324)
		(end 32.026606 -63.7159)
		(width 0.09525)
		(layer "F.Cu")
		(net "SAS2X28_B_HDD9_RX_+")
	)
	(arc
		(start 31.451042 -63.7159)
		(mid 31.351508 -63.735699)
		(end 31.267146 -63.7921)
		(width 0.09525)
		(layer "F.Cu")
		(net "SAS2X28_B_HDD9_RX_+")
	)
	(arc
		(start 31.190692 -63.868554)
		(mid 31.115317 -63.981361)
		(end 31.088838 -64.114426)
		(width 0.09525)
		(layer "F.Cu")
		(net "SAS2X28_B_HDD9_RX_+")
	)
	(segment
		(start 8.679942 -103.85044)
		(end 5.668772 -103.85044)
		(width 0.09525)
		(layer "B.Cu")
		(net "SAS2X28_B_HDD9_RX_+")
	)
	(segment
		(start 31.263082 -63.8429)
		(end 31.876746 -63.8429)
		(width 0.09525)
		(layer "B.Cu")
		(net "SAS2X28_B_HDD9_RX_+")
	)
	(segment
		(start 32.003492 -65.1637)
		(end 19.281648 -77.885544)
		(width 0.09525)
		(layer "B.Cu")
		(net "SAS2X28_B_HDD9_RX_+")
	)
	(segment
		(start 5.448046 -103.759)
		(end 5.295646 -103.6066)
		(width 0.09525)
		(layer "B.Cu")
		(net "SAS2X28_B_HDD9_RX_+")
	)
	(segment
		(start 5.036566 -103.498396)
		(end 2.811526 -103.498396)
		(width 0.09525)
		(layer "B.Cu")
		(net "SAS2X28_B_HDD9_RX_+")
	)
	(segment
		(start 31.088838 -64.182752)
		(end 31.088838 -64.017144)
		(width 0.09525)
		(layer "B.Cu")
		(net "SAS2X28_B_HDD9_RX_+")
	)
	(segment
		(start 5.03809 -103.49992)
		(end 5.036566 -103.498396)
		(width 0.09525)
		(layer "B.Cu")
		(net "SAS2X28_B_HDD9_RX_+")
	)
	(segment
		(start 18.813018 -93.889322)
		(end 8.973566 -103.728774)
		(width 0.09525)
		(layer "B.Cu")
		(net "SAS2X28_B_HDD9_RX_+")
	)
	(segment
		(start 32.130746 -64.0969)
		(end 32.130746 -64.89827)
		(width 0.09525)
		(layer "B.Cu")
		(net "SAS2X28_B_HDD9_RX_+")
	)
	(segment
		(start 18.998946 -78.568042)
		(end 18.998946 -93.44025)
		(width 0.09525)
		(layer "B.Cu")
		(net "SAS2X28_B_HDD9_RX_+")
	)
	(segment
		(start 32.032956 -65.133982)
		(end 32.003492 -65.1637)
		(width 0.09525)
		(layer "B.Cu")
		(net "SAS2X28_B_HDD9_RX_+")
	)
	(arc
		(start 18.998946 -93.44025)
		(mid 18.95061 -93.683254)
		(end 18.813018 -93.889322)
		(width 0.09525)
		(layer "B.Cu")
		(net "SAS2X28_B_HDD9_RX_+")
	)
	(arc
		(start 19.281648 -77.885544)
		(mid 19.072419 -78.198677)
		(end 18.998946 -78.568042)
		(width 0.09525)
		(layer "B.Cu")
		(net "SAS2X28_B_HDD9_RX_+")
	)
	(arc
		(start 31.088838 -64.017144)
		(mid 31.102102 -63.950464)
		(end 31.139892 -63.893954)
		(width 0.09525)
		(layer "B.Cu")
		(net "SAS2X28_B_HDD9_RX_+")
	)
	(arc
		(start 5.668772 -103.85044)
		(mid 5.549311 -103.826678)
		(end 5.448046 -103.759)
		(width 0.09525)
		(layer "B.Cu")
		(net "SAS2X28_B_HDD9_RX_+")
	)
	(arc
		(start 31.139892 -63.893954)
		(mid 31.196412 -63.856189)
		(end 31.263082 -63.8429)
		(width 0.09525)
		(layer "B.Cu")
		(net "SAS2X28_B_HDD9_RX_+")
	)
	(arc
		(start 32.130746 -64.89827)
		(mid 32.105277 -65.025842)
		(end 32.032956 -65.133982)
		(width 0.09525)
		(layer "B.Cu")
		(net "SAS2X28_B_HDD9_RX_+")
	)
	(arc
		(start 31.876746 -63.8429)
		(mid 32.056351 -63.917295)
		(end 32.130746 -64.0969)
		(width 0.09525)
		(layer "B.Cu")
		(net "SAS2X28_B_HDD9_RX_+")
	)
	(arc
		(start 5.295646 -103.6066)
		(mid 5.177478 -103.527643)
		(end 5.03809 -103.49992)
		(width 0.09525)
		(layer "B.Cu")
		(net "SAS2X28_B_HDD9_RX_+")
	)
	(arc
		(start 8.973566 -103.728774)
		(mid 8.83885 -103.818788)
		(end 8.679942 -103.85044)
		(width 0.09525)
		(layer "B.Cu")
		(net "SAS2X28_B_HDD9_RX_+")
	)
	(segment
		(start 195.465446 -461.679036)
		(end 195.211446 -461.425036)
		(width 0.111252)
		(layer "F.Cu")
		(net "EEPROM_WP")
	)
	(segment
		(start 195.211446 -459.520036)
		(end 195.211446 -461.425036)
		(width 0.111252)
		(layer "F.Cu")
		(net "EEPROM_WP")
	)
	(segment
		(start 195.902326 -458.829156)
		(end 195.211446 -459.520036)
		(width 0.111252)
		(layer "F.Cu")
		(net "EEPROM_WP")
	)
	(segment
		(start 197.141846 -458.829156)
		(end 195.902326 -458.829156)
		(width 0.111252)
		(layer "F.Cu")
		(net "EEPROM_WP")
	)
	(segment
		(start 196.671946 -461.679036)
		(end 195.465446 -461.679036)
		(width 0.111252)
		(layer "F.Cu")
		(net "EEPROM_WP")
	)
	(via
		(at 195.211446 -461.425036)
		(size 0.7112)
		(drill 0.3556)
		(layers "F.Cu" "B.Cu")
		(net "EEPROM_WP")
	)
	(segment
		(start 207.454246 -42.4307)
		(end 207.454246 -43.6372)
		(width 0.111252)
		(layer "F.Cu")
		(net "I2C_B_TMP4_A2")
	)
	(segment
		(start 207.390746 -41.3512)
		(end 207.390746 -42.3672)
		(width 0.111252)
		(layer "F.Cu")
		(net "I2C_B_TMP4_A2")
	)
	(segment
		(start 207.390746 -42.3672)
		(end 207.454246 -42.4307)
		(width 0.111252)
		(layer "F.Cu")
		(net "I2C_B_TMP4_A2")
	)
	(segment
		(start 208.75879 -44.941744)
		(end 207.775302 -43.958256)
		(width 0.111252)
		(layer "F.Cu")
		(net "I2C_B_TMP4_A2")
	)
	(segment
		(start 207.454246 -43.6372)
		(end 207.775302 -43.958256)
		(width 0.111252)
		(layer "F.Cu")
		(net "I2C_B_TMP4_A2")
	)
	(segment
		(start 209.63128 -44.941744)
		(end 208.75879 -44.941744)
		(width 0.111252)
		(layer "F.Cu")
		(net "I2C_B_TMP4_A2")
	)
	(segment
		(start 209.634582 -44.945046)
		(end 209.63128 -44.941744)
		(width 0.111252)
		(layer "F.Cu")
		(net "I2C_B_TMP4_A2")
	)
	(via
		(at 207.775302 -43.958256)
		(size 0.7112)
		(drill 0.3556)
		(layers "F.Cu" "B.Cu")
		(net "I2C_B_TMP4_A2")
	)
	(segment
		(start 31.229808 -155.221178)
		(end 27.561286 -158.890208)
		(width 0.09525)
		(layer "F.Cu")
		(net "SAS2X28_A_HDD9_TX_+")
	)
	(segment
		(start 10.926064 -358.869488)
		(end 10.926064 -362.4707)
		(width 0.09525)
		(layer "F.Cu")
		(net "SAS2X28_A_HDD9_TX_+")
	)
	(segment
		(start 31.876746 -127.544068)
		(end 31.877 -127.543814)
		(width 0.09525)
		(layer "F.Cu")
		(net "SAS2X28_A_HDD9_TX_+")
	)
	(segment
		(start 4.647692 -365.498888)
		(end 3.192526 -365.498888)
		(width 0.09525)
		(layer "F.Cu")
		(net "SAS2X28_A_HDD9_TX_+")
	)
	(segment
		(start 26.7208 -160.919922)
		(end 26.7208 -183.199532)
		(width 0.09525)
		(layer "F.Cu")
		(net "SAS2X28_A_HDD9_TX_+")
	)
	(segment
		(start 27.464766 -184.995566)
		(end 32.809434 -190.340234)
		(width 0.09525)
		(layer "F.Cu")
		(net "SAS2X28_A_HDD9_TX_+")
	)
	(segment
		(start 36.82746 -53.231542)
		(end 36.82746 -53.434996)
		(width 0.09525)
		(layer "F.Cu")
		(net "SAS2X28_A_HDD9_TX_+")
	)
	(segment
		(start 28.829 -59.421268)
		(end 28.829 -122.392186)
		(width 0.09525)
		(layer "F.Cu")
		(net "SAS2X28_A_HDD9_TX_+")
	)
	(segment
		(start 33.5534 -192.136268)
		(end 33.5534 -253.430532)
		(width 0.09525)
		(layer "F.Cu")
		(net "SAS2X28_A_HDD9_TX_+")
	)
	(segment
		(start 31.877 -127.543814)
		(end 31.877 -153.659078)
		(width 0.09525)
		(layer "F.Cu")
		(net "SAS2X28_A_HDD9_TX_+")
	)
	(segment
		(start 12.864338 -276.257766)
		(end 12.864338 -355.946202)
		(width 0.09525)
		(layer "F.Cu")
		(net "SAS2X28_A_HDD9_TX_+")
	)
	(segment
		(start 10.480294 -363.546898)
		(end 8.378698 -365.648494)
		(width 0.09525)
		(layer "F.Cu")
		(net "SAS2X28_A_HDD9_TX_+")
	)
	(segment
		(start 15.293086 -272.74266)
		(end 13.632434 -274.403312)
		(width 0.09525)
		(layer "F.Cu")
		(net "SAS2X28_A_HDD9_TX_+")
	)
	(segment
		(start 4.649216 -365.500412)
		(end 4.647692 -365.498888)
		(width 0.09525)
		(layer "F.Cu")
		(net "SAS2X28_A_HDD9_TX_+")
	)
	(segment
		(start 29.572966 -124.187966)
		(end 31.133034 -125.748034)
		(width 0.09525)
		(layer "F.Cu")
		(net "SAS2X28_A_HDD9_TX_+")
	)
	(segment
		(start 32.683958 -54.377082)
		(end 29.669486 -57.391554)
		(width 0.09525)
		(layer "F.Cu")
		(net "SAS2X28_A_HDD9_TX_+")
	)
	(segment
		(start 12.570968 -356.613968)
		(end 11.358372 -357.826564)
		(width 0.09525)
		(layer "F.Cu")
		(net "SAS2X28_A_HDD9_TX_+")
	)
	(segment
		(start 7.939024 -365.830612)
		(end 5.446522 -365.830612)
		(width 0.09525)
		(layer "F.Cu")
		(net "SAS2X28_A_HDD9_TX_+")
	)
	(segment
		(start 36.72586 -53.536596)
		(end 34.713672 -53.536596)
		(width 0.09525)
		(layer "F.Cu")
		(net "SAS2X28_A_HDD9_TX_+")
	)
	(segment
		(start 31.877 -153.659078)
		(end 31.876746 -153.658824)
		(width 0.09525)
		(layer "F.Cu")
		(net "SAS2X28_A_HDD9_TX_+")
	)
	(segment
		(start 38.250114 -53.069998)
		(end 36.989258 -53.069998)
		(width 0.09525)
		(layer "F.Cu")
		(net "SAS2X28_A_HDD9_TX_+")
	)
	(segment
		(start 32.809434 -255.226566)
		(end 15.293086 -272.74266)
		(width 0.09525)
		(layer "F.Cu")
		(net "SAS2X28_A_HDD9_TX_+")
	)
	(arc
		(start 36.82746 -53.434996)
		(mid 36.797702 -53.506838)
		(end 36.72586 -53.536596)
		(width 0.09525)
		(layer "F.Cu")
		(net "SAS2X28_A_HDD9_TX_+")
	)
	(arc
		(start 28.829 -122.392186)
		(mid 29.022395 -123.364065)
		(end 29.572966 -124.187966)
		(width 0.09525)
		(layer "F.Cu")
		(net "SAS2X28_A_HDD9_TX_+")
	)
	(arc
		(start 36.989258 -53.069998)
		(mid 36.927258 -53.082349)
		(end 36.874704 -53.117496)
		(width 0.09525)
		(layer "F.Cu")
		(net "SAS2X28_A_HDD9_TX_+")
	)
	(arc
		(start 32.809434 -190.340234)
		(mid 33.360032 -191.164261)
		(end 33.5534 -192.136268)
		(width 0.09525)
		(layer "F.Cu")
		(net "SAS2X28_A_HDD9_TX_+")
	)
	(arc
		(start 10.926064 -362.4707)
		(mid 10.810211 -363.053132)
		(end 10.480294 -363.546898)
		(width 0.09525)
		(layer "F.Cu")
		(net "SAS2X28_A_HDD9_TX_+")
	)
	(arc
		(start 8.378698 -365.648494)
		(mid 8.176974 -365.783282)
		(end 7.939024 -365.830612)
		(width 0.09525)
		(layer "F.Cu")
		(net "SAS2X28_A_HDD9_TX_+")
	)
	(arc
		(start 13.101574 -275.167598)
		(mid 12.924325 -275.699922)
		(end 12.864338 -276.257766)
		(width 0.09525)
		(layer "F.Cu")
		(net "SAS2X28_A_HDD9_TX_+")
	)
	(arc
		(start 31.133034 -125.748034)
		(mid 31.683495 -126.572091)
		(end 31.876746 -127.544068)
		(width 0.09525)
		(layer "F.Cu")
		(net "SAS2X28_A_HDD9_TX_+")
	)
	(arc
		(start 27.561286 -158.890208)
		(mid 26.939134 -159.821464)
		(end 26.7208 -160.919922)
		(width 0.09525)
		(layer "F.Cu")
		(net "SAS2X28_A_HDD9_TX_+")
	)
	(arc
		(start 5.21589 -365.735108)
		(mid 4.955898 -365.561387)
		(end 4.649216 -365.500412)
		(width 0.09525)
		(layer "F.Cu")
		(net "SAS2X28_A_HDD9_TX_+")
	)
	(arc
		(start 5.446522 -365.830612)
		(mid 5.321715 -365.805786)
		(end 5.21589 -365.735108)
		(width 0.09525)
		(layer "F.Cu")
		(net "SAS2X28_A_HDD9_TX_+")
	)
	(arc
		(start 13.632434 -274.403312)
		(mid 13.332851 -274.761731)
		(end 13.101574 -275.167598)
		(width 0.09525)
		(layer "F.Cu")
		(net "SAS2X28_A_HDD9_TX_+")
	)
	(arc
		(start 11.358372 -357.826564)
		(mid 11.038435 -358.305005)
		(end 10.926064 -358.869488)
		(width 0.09525)
		(layer "F.Cu")
		(net "SAS2X28_A_HDD9_TX_+")
	)
	(arc
		(start 34.713672 -53.536596)
		(mid 33.61524 -53.754994)
		(end 32.683958 -54.377082)
		(width 0.09525)
		(layer "F.Cu")
		(net "SAS2X28_A_HDD9_TX_+")
	)
	(arc
		(start 29.669486 -57.391554)
		(mid 29.047334 -58.32281)
		(end 28.829 -59.421268)
		(width 0.09525)
		(layer "F.Cu")
		(net "SAS2X28_A_HDD9_TX_+")
	)
	(arc
		(start 36.874704 -53.117496)
		(mid 36.839742 -53.169821)
		(end 36.82746 -53.231542)
		(width 0.09525)
		(layer "F.Cu")
		(net "SAS2X28_A_HDD9_TX_+")
	)
	(arc
		(start 33.5534 -253.430532)
		(mid 33.360054 -254.402548)
		(end 32.809434 -255.226566)
		(width 0.09525)
		(layer "F.Cu")
		(net "SAS2X28_A_HDD9_TX_+")
	)
	(arc
		(start 26.7208 -183.199532)
		(mid 26.914146 -184.171548)
		(end 27.464766 -184.995566)
		(width 0.09525)
		(layer "F.Cu")
		(net "SAS2X28_A_HDD9_TX_+")
	)
	(arc
		(start 12.864338 -355.946202)
		(mid 12.780389 -356.307647)
		(end 12.570968 -356.613968)
		(width 0.09525)
		(layer "F.Cu")
		(net "SAS2X28_A_HDD9_TX_+")
	)
	(arc
		(start 31.876746 -153.658824)
		(mid 31.708672 -154.504351)
		(end 31.229808 -155.221178)
		(width 0.09525)
		(layer "F.Cu")
		(net "SAS2X28_A_HDD9_TX_+")
	)
	(segment
		(start 210.284822 -45.886624)
		(end 210.284822 -44.945046)
		(width 0.111252)
		(layer "F.Cu")
		(net "I2C_B_TMP4_A1")
	)
	(segment
		(start 209.295746 -41.3512)
		(end 209.295746 -42.3672)
		(width 0.111252)
		(layer "F.Cu")
		(net "I2C_B_TMP4_A1")
	)
	(segment
		(start 209.359246 -42.8752)
		(end 210.284822 -43.800776)
		(width 0.111252)
		(layer "F.Cu")
		(net "I2C_B_TMP4_A1")
	)
	(segment
		(start 209.930746 -46.2407)
		(end 210.284822 -45.886624)
		(width 0.111252)
		(layer "F.Cu")
		(net "I2C_B_TMP4_A1")
	)
	(segment
		(start 209.359246 -42.4307)
		(end 209.359246 -42.8752)
		(width 0.111252)
		(layer "F.Cu")
		(net "I2C_B_TMP4_A1")
	)
	(segment
		(start 207.771746 -46.2407)
		(end 209.930746 -46.2407)
		(width 0.111252)
		(layer "F.Cu")
		(net "I2C_B_TMP4_A1")
	)
	(segment
		(start 209.295746 -42.3672)
		(end 209.359246 -42.4307)
		(width 0.111252)
		(layer "F.Cu")
		(net "I2C_B_TMP4_A1")
	)
	(segment
		(start 210.284822 -43.800776)
		(end 210.284822 -44.945046)
		(width 0.111252)
		(layer "F.Cu")
		(net "I2C_B_TMP4_A1")
	)
	(via
		(at 207.771746 -46.2407)
		(size 0.7112)
		(drill 0.3556)
		(layers "F.Cu" "B.Cu")
		(net "I2C_B_TMP4_A1")
	)
	(segment
		(start 39.404544 -60.989972)
		(end 39.401242 -60.98667)
		(width 0.09525)
		(layer "F.Cu")
		(net "SAS2X28_B_HDD9_TX_+")
	)
	(segment
		(start 39.226998 -61.058806)
		(end 39.171372 -61.114432)
		(width 0.09525)
		(layer "F.Cu")
		(net "SAS2X28_B_HDD9_TX_+")
	)
	(segment
		(start 3.19405 -107.500166)
		(end 3.192526 -107.498642)
		(width 0.09525)
		(layer "F.Cu")
		(net "SAS2X28_B_HDD9_TX_+")
	)
	(segment
		(start 38.912546 -61.22162)
		(end 38.514528 -61.22162)
		(width 0.09525)
		(layer "F.Cu")
		(net "SAS2X28_B_HDD9_TX_+")
	)
	(segment
		(start 40.39997 -60.989972)
		(end 39.404544 -60.989972)
		(width 0.09525)
		(layer "F.Cu")
		(net "SAS2X28_B_HDD9_TX_+")
	)
	(segment
		(start 38.371018 -61.162184)
		(end 38.099746 -60.891166)
		(width 0.09525)
		(layer "F.Cu")
		(net "SAS2X28_B_HDD9_TX_+")
	)
	(segment
		(start 6.442964 -107.6325)
		(end 5.662676 -107.6325)
		(width 0.09525)
		(layer "F.Cu")
		(net "SAS2X28_B_HDD9_TX_+")
	)
	(segment
		(start 5.343144 -107.500166)
		(end 3.19405 -107.500166)
		(width 0.09525)
		(layer "F.Cu")
		(net "SAS2X28_B_HDD9_TX_+")
	)
	(via
		(at 6.705346 -107.523788)
		(size 0.5588)
		(drill 0.3048)
		(layers "F.Cu" "B.Cu")
		(net "SAS2X28_B_HDD9_TX_+")
	)
	(via
		(at 38.099746 -60.891166)
		(size 0.5588)
		(drill 0.3048)
		(layers "F.Cu" "B.Cu")
		(net "SAS2X28_B_HDD9_TX_+")
	)
	(arc
		(start 5.566156 -107.611672)
		(mid 5.529463 -107.590907)
		(end 5.497068 -107.56392)
		(width 0.09525)
		(layer "F.Cu")
		(net "SAS2X28_B_HDD9_TX_+")
	)
	(arc
		(start 5.497068 -107.56392)
		(mid 5.426447 -107.516733)
		(end 5.343144 -107.500166)
		(width 0.09525)
		(layer "F.Cu")
		(net "SAS2X28_B_HDD9_TX_+")
	)
	(arc
		(start 39.401242 -60.98667)
		(mid 39.306956 -61.005425)
		(end 39.226998 -61.058806)
		(width 0.09525)
		(layer "F.Cu")
		(net "SAS2X28_B_HDD9_TX_+")
	)
	(arc
		(start 6.705346 -107.523788)
		(mid 6.584964 -107.604225)
		(end 6.442964 -107.6325)
		(width 0.09525)
		(layer "F.Cu")
		(net "SAS2X28_B_HDD9_TX_+")
	)
	(arc
		(start 5.631942 -107.630468)
		(mid 5.598358 -107.623488)
		(end 5.566156 -107.611672)
		(width 0.09525)
		(layer "F.Cu")
		(net "SAS2X28_B_HDD9_TX_+")
	)
	(arc
		(start 38.514528 -61.22162)
		(mid 38.436864 -61.206172)
		(end 38.371018 -61.162184)
		(width 0.09525)
		(layer "F.Cu")
		(net "SAS2X28_B_HDD9_TX_+")
	)
	(arc
		(start 5.662676 -107.6325)
		(mid 5.647275 -107.631993)
		(end 5.631942 -107.630468)
		(width 0.09525)
		(layer "F.Cu")
		(net "SAS2X28_B_HDD9_TX_+")
	)
	(arc
		(start 39.171372 -61.114432)
		(mid 39.052622 -61.193778)
		(end 38.912546 -61.22162)
		(width 0.09525)
		(layer "F.Cu")
		(net "SAS2X28_B_HDD9_TX_+")
	)
	(segment
		(start 32.884872 -65.61201)
		(end 32.839406 -65.657476)
		(width 0.09525)
		(layer "B.Cu")
		(net "SAS2X28_B_HDD9_TX_+")
	)
	(segment
		(start 19.752818 -95.931228)
		(end 8.184896 -107.49915)
		(width 0.09525)
		(layer "B.Cu")
		(net "SAS2X28_B_HDD9_TX_+")
	)
	(segment
		(start 35.135566 -61.56452)
		(end 33.459166 -63.24092)
		(width 0.09525)
		(layer "B.Cu")
		(net "SAS2X28_B_HDD9_TX_+")
	)
	(segment
		(start 8.184896 -107.49915)
		(end 8.184896 -107.498896)
		(width 0.09525)
		(layer "B.Cu")
		(net "SAS2X28_B_HDD9_TX_+")
	)
	(segment
		(start 19.938746 -79.157322)
		(end 19.938746 -95.482156)
		(width 0.09525)
		(layer "B.Cu")
		(net "SAS2X28_B_HDD9_TX_+")
	)
	(segment
		(start 32.36341 -66.133218)
		(end 30.366716 -68.130166)
		(width 0.09525)
		(layer "B.Cu")
		(net "SAS2X28_B_HDD9_TX_+")
	)
	(segment
		(start 7.951216 -107.733084)
		(end 7.911084 -107.773216)
		(width 0.09525)
		(layer "B.Cu")
		(net "SAS2X28_B_HDD9_TX_+")
	)
	(segment
		(start 7.754874 -107.837986)
		(end 6.883146 -107.837986)
		(width 0.09525)
		(layer "B.Cu")
		(net "SAS2X28_B_HDD9_TX_+")
	)
	(segment
		(start 33.070546 -64.17945)
		(end 33.070546 -65.1637)
		(width 0.09525)
		(layer "B.Cu")
		(net "SAS2X28_B_HDD9_TX_+")
	)
	(segment
		(start 7.951216 -107.73283)
		(end 7.951216 -107.733084)
		(width 0.09525)
		(layer "B.Cu")
		(net "SAS2X28_B_HDD9_TX_+")
	)
	(segment
		(start 6.705346 -107.660186)
		(end 6.705346 -107.523788)
		(width 0.09525)
		(layer "B.Cu")
		(net "SAS2X28_B_HDD9_TX_+")
	)
	(segment
		(start 37.970206 -61.20384)
		(end 37.896546 -61.2775)
		(width 0.09525)
		(layer "B.Cu")
		(net "SAS2X28_B_HDD9_TX_+")
	)
	(segment
		(start 32.364934 -66.133218)
		(end 32.36341 -66.133218)
		(width 0.09525)
		(layer "B.Cu")
		(net "SAS2X28_B_HDD9_TX_+")
	)
	(segment
		(start 8.184896 -107.498896)
		(end 7.951216 -107.73283)
		(width 0.09525)
		(layer "B.Cu")
		(net "SAS2X28_B_HDD9_TX_+")
	)
	(segment
		(start 32.839406 -65.657476)
		(end 32.364934 -66.133218)
		(width 0.09525)
		(layer "B.Cu")
		(net "SAS2X28_B_HDD9_TX_+")
	)
	(segment
		(start 30.366716 -68.130166)
		(end 20.362164 -78.134718)
		(width 0.09525)
		(layer "B.Cu")
		(net "SAS2X28_B_HDD9_TX_+")
	)
	(segment
		(start 37.71265 -61.3537)
		(end 35.644836 -61.3537)
		(width 0.09525)
		(layer "B.Cu")
		(net "SAS2X28_B_HDD9_TX_+")
	)
	(arc
		(start 20.362164 -78.134718)
		(mid 20.048779 -78.603921)
		(end 19.938746 -79.157322)
		(width 0.09525)
		(layer "B.Cu")
		(net "SAS2X28_B_HDD9_TX_+")
	)
	(arc
		(start 37.896546 -61.2775)
		(mid 37.812174 -61.333876)
		(end 37.71265 -61.3537)
		(width 0.09525)
		(layer "B.Cu")
		(net "SAS2X28_B_HDD9_TX_+")
	)
	(arc
		(start 33.364424 -63.346584)
		(mid 33.146139 -63.737851)
		(end 33.070546 -64.17945)
		(width 0.09525)
		(layer "B.Cu")
		(net "SAS2X28_B_HDD9_TX_+")
	)
	(arc
		(start 33.070546 -65.1637)
		(mid 33.022287 -65.406315)
		(end 32.884872 -65.61201)
		(width 0.09525)
		(layer "B.Cu")
		(net "SAS2X28_B_HDD9_TX_+")
	)
	(arc
		(start 7.911084 -107.773216)
		(mid 7.839414 -107.821104)
		(end 7.754874 -107.837986)
		(width 0.09525)
		(layer "B.Cu")
		(net "SAS2X28_B_HDD9_TX_+")
	)
	(arc
		(start 38.099746 -60.891166)
		(mid 38.066084 -61.060394)
		(end 37.970206 -61.20384)
		(width 0.09525)
		(layer "B.Cu")
		(net "SAS2X28_B_HDD9_TX_+")
	)
	(arc
		(start 19.938746 -95.482156)
		(mid 19.89041 -95.72516)
		(end 19.752818 -95.931228)
		(width 0.09525)
		(layer "B.Cu")
		(net "SAS2X28_B_HDD9_TX_+")
	)
	(arc
		(start 35.644836 -61.3537)
		(mid 35.369241 -61.408484)
		(end 35.135566 -61.56452)
		(width 0.09525)
		(layer "B.Cu")
		(net "SAS2X28_B_HDD9_TX_+")
	)
	(arc
		(start 6.883146 -107.837986)
		(mid 6.757422 -107.78591)
		(end 6.705346 -107.660186)
		(width 0.09525)
		(layer "B.Cu")
		(net "SAS2X28_B_HDD9_TX_+")
	)
	(arc
		(start 33.459166 -63.24092)
		(mid 33.410381 -63.292484)
		(end 33.364424 -63.346584)
		(width 0.09525)
		(layer "B.Cu")
		(net "SAS2X28_B_HDD9_TX_+")
	)
	(segment
		(start 3.193542 -198.501254)
		(end 3.19024 -198.504556)
		(width 0.111252)
		(layer "F.Cu")
		(net "SAS_EXP_B_PWR14")
	)
	(segment
		(start 97.266506 -14.25194)
		(end 98.488246 -14.25194)
		(width 0.111252)
		(layer "F.Cu")
		(net "SAS_EXP_B_PWR14")
	)
	(segment
		(start 97.027746 -14.4907)
		(end 97.266506 -14.25194)
		(width 0.111252)
		(layer "F.Cu")
		(net "SAS_EXP_B_PWR14")
	)
	(segment
		(start 6.933946 -199.0217)
		(end 6.4135 -198.501254)
		(width 0.111252)
		(layer "F.Cu")
		(net "SAS_EXP_B_PWR14")
	)
	(segment
		(start 96.202246 -14.4907)
		(end 97.027746 -14.4907)
		(width 0.111252)
		(layer "F.Cu")
		(net "SAS_EXP_B_PWR14")
	)
	(segment
		(start 6.4135 -198.501254)
		(end 3.193542 -198.501254)
		(width 0.111252)
		(layer "F.Cu")
		(net "SAS_EXP_B_PWR14")
	)
	(via
		(at 97.916746 -15.1257)
		(size 0.7112)
		(drill 0.3556)
		(layers "F.Cu" "B.Cu")
		(net "SAS_EXP_B_PWR14")
	)
	(via
		(at 97.027746 -14.4907)
		(size 0.5588)
		(drill 0.3048)
		(layers "F.Cu" "B.Cu")
		(net "SAS_EXP_B_PWR14")
	)
	(via
		(at 6.933946 -199.0217)
		(size 0.5588)
		(drill 0.3048)
		(layers "F.Cu" "B.Cu")
		(net "SAS_EXP_B_PWR14")
	)
	(segment
		(start 97.281746 -14.4907)
		(end 97.916746 -15.1257)
		(width 0.111252)
		(layer "B.Cu")
		(net "SAS_EXP_B_PWR14")
	)
	(segment
		(start 97.027746 -14.4907)
		(end 97.281746 -14.4907)
		(width 0.111252)
		(layer "B.Cu")
		(net "SAS_EXP_B_PWR14")
	)
	(segment
		(start 31.258256 -458.6351)
		(end 31.338774 -458.619098)
		(width 0.14605)
		(layer "In5.Cu")
		(net "SAS_EXP_B_PWR14")
	)
	(segment
		(start 8.721344 -388.22503)
		(end 8.721344 -389.234172)
		(width 0.14605)
		(layer "In5.Cu")
		(net "SAS_EXP_B_PWR14")
	)
	(segment
		(start 15.423896 -449.451476)
		(end 15.423896 -454.727056)
		(width 0.14605)
		(layer "In5.Cu")
		(net "SAS_EXP_B_PWR14")
	)
	(segment
		(start 8.737346 -389.250174)
		(end 8.737346 -390.066022)
		(width 0.14605)
		(layer "In5.Cu")
		(net "SAS_EXP_B_PWR14")
	)
	(segment
		(start 18.836386 -458.161898)
		(end 19.01825 -458.343762)
		(width 0.14605)
		(layer "In5.Cu")
		(net "SAS_EXP_B_PWR14")
	)
	(segment
		(start 11.402314 -445.995552)
		(end 11.434318 -445.963548)
		(width 0.14605)
		(layer "In5.Cu")
		(net "SAS_EXP_B_PWR14")
	)
	(segment
		(start 7.978648 -441.811918)
		(end 8.881364 -442.714634)
		(width 0.14605)
		(layer "In5.Cu")
		(net "SAS_EXP_B_PWR14")
	)
	(segment
		(start 102.66045 -400.69897)
		(end 102.784148 -400.575272)
		(width 0.14605)
		(layer "In5.Cu")
		(net "SAS_EXP_B_PWR14")
	)
	(segment
		(start 9.924796 -393.930124)
		(end 11.098784 -395.104112)
		(width 0.14605)
		(layer "In5.Cu")
		(net "SAS_EXP_B_PWR14")
	)
	(segment
		(start 8.881364 -444.845694)
		(end 10.031222 -445.995552)
		(width 0.14605)
		(layer "In5.Cu")
		(net "SAS_EXP_B_PWR14")
	)
	(segment
		(start 102.736396 -20.19935)
		(end 97.027746 -14.4907)
		(width 0.14605)
		(layer "In5.Cu")
		(net "SAS_EXP_B_PWR14")
	)
	(segment
		(start 13.541502 -401.176236)
		(end 13.28674 -401.430998)
		(width 0.14605)
		(layer "In5.Cu")
		(net "SAS_EXP_B_PWR14")
	)
	(segment
		(start 35.73907 -454.218802)
		(end 51.940206 -454.218802)
		(width 0.14605)
		(layer "In5.Cu")
		(net "SAS_EXP_B_PWR14")
	)
	(segment
		(start 8.429498 -207.901032)
		(end 8.429498 -215.878664)
		(width 0.14605)
		(layer "In5.Cu")
		(net "SAS_EXP_B_PWR14")
	)
	(segment
		(start 19.396456 -458.6351)
		(end 31.258256 -458.6351)
		(width 0.14605)
		(layer "In5.Cu")
		(net "SAS_EXP_B_PWR14")
	)
	(segment
		(start 10.839196 -218.288362)
		(end 10.839196 -386.107178)
		(width 0.14605)
		(layer "In5.Cu")
		(net "SAS_EXP_B_PWR14")
	)
	(segment
		(start 102.736396 -399.756376)
		(end 102.736396 -20.19935)
		(width 0.14605)
		(layer "In5.Cu")
		(net "SAS_EXP_B_PWR14")
	)
	(segment
		(start 8.429498 -215.878664)
		(end 10.839196 -218.288362)
		(width 0.14605)
		(layer "In5.Cu")
		(net "SAS_EXP_B_PWR14")
	)
	(segment
		(start 18.791174 -458.094588)
		(end 18.836386 -458.161898)
		(width 0.14605)
		(layer "In5.Cu")
		(net "SAS_EXP_B_PWR14")
	)
	(segment
		(start 6.933946 -206.40548)
		(end 8.429498 -207.901032)
		(width 0.14605)
		(layer "In5.Cu")
		(net "SAS_EXP_B_PWR14")
	)
	(segment
		(start 102.66045 -439.31459)
		(end 102.66045 -400.69897)
		(width 0.14605)
		(layer "In5.Cu")
		(net "SAS_EXP_B_PWR14")
	)
	(segment
		(start 102.784148 -400.575272)
		(end 102.784148 -399.804128)
		(width 0.14605)
		(layer "In5.Cu")
		(net "SAS_EXP_B_PWR14")
	)
	(segment
		(start 8.721344 -389.234172)
		(end 8.737346 -389.250174)
		(width 0.14605)
		(layer "In5.Cu")
		(net "SAS_EXP_B_PWR14")
	)
	(segment
		(start 13.541502 -397.296386)
		(end 13.541502 -401.176236)
		(width 0.14605)
		(layer "In5.Cu")
		(net "SAS_EXP_B_PWR14")
	)
	(segment
		(start 13.28674 -401.430998)
		(end 13.28674 -430.955704)
		(width 0.14605)
		(layer "In5.Cu")
		(net "SAS_EXP_B_PWR14")
	)
	(segment
		(start 19.08556 -458.388974)
		(end 19.315938 -458.619098)
		(width 0.14605)
		(layer "In5.Cu")
		(net "SAS_EXP_B_PWR14")
	)
	(segment
		(start 102.784148 -399.804128)
		(end 102.736396 -399.756376)
		(width 0.14605)
		(layer "In5.Cu")
		(net "SAS_EXP_B_PWR14")
	)
	(segment
		(start 11.098784 -395.104112)
		(end 11.349228 -395.104112)
		(width 0.14605)
		(layer "In5.Cu")
		(net "SAS_EXP_B_PWR14")
	)
	(segment
		(start 10.031222 -445.995552)
		(end 11.402314 -445.995552)
		(width 0.14605)
		(layer "In5.Cu")
		(net "SAS_EXP_B_PWR14")
	)
	(segment
		(start 8.881364 -442.714634)
		(end 8.881364 -444.845694)
		(width 0.14605)
		(layer "In5.Cu")
		(net "SAS_EXP_B_PWR14")
	)
	(segment
		(start 19.01825 -458.343762)
		(end 19.08556 -458.388974)
		(width 0.14605)
		(layer "In5.Cu")
		(net "SAS_EXP_B_PWR14")
	)
	(segment
		(start 19.315938 -458.619098)
		(end 19.396456 -458.6351)
		(width 0.14605)
		(layer "In5.Cu")
		(net "SAS_EXP_B_PWR14")
	)
	(segment
		(start 52.000658 -454.15835)
		(end 87.81669 -454.15835)
		(width 0.14605)
		(layer "In5.Cu")
		(net "SAS_EXP_B_PWR14")
	)
	(segment
		(start 6.933946 -199.0217)
		(end 6.933946 -206.40548)
		(width 0.14605)
		(layer "In5.Cu")
		(net "SAS_EXP_B_PWR14")
	)
	(segment
		(start 87.81669 -454.15835)
		(end 102.66045 -439.31459)
		(width 0.14605)
		(layer "In5.Cu")
		(net "SAS_EXP_B_PWR14")
	)
	(segment
		(start 51.940206 -454.218802)
		(end 52.000658 -454.15835)
		(width 0.14605)
		(layer "In5.Cu")
		(net "SAS_EXP_B_PWR14")
	)
	(segment
		(start 8.737346 -390.066022)
		(end 9.924796 -391.253472)
		(width 0.14605)
		(layer "In5.Cu")
		(net "SAS_EXP_B_PWR14")
	)
	(segment
		(start 11.935968 -445.963548)
		(end 15.423896 -449.451476)
		(width 0.14605)
		(layer "In5.Cu")
		(net "SAS_EXP_B_PWR14")
	)
	(segment
		(start 11.434318 -445.963548)
		(end 11.935968 -445.963548)
		(width 0.14605)
		(layer "In5.Cu")
		(net "SAS_EXP_B_PWR14")
	)
	(segment
		(start 9.924796 -391.253472)
		(end 9.924796 -393.930124)
		(width 0.14605)
		(layer "In5.Cu")
		(net "SAS_EXP_B_PWR14")
	)
	(segment
		(start 10.839196 -386.107178)
		(end 8.721344 -388.22503)
		(width 0.14605)
		(layer "In5.Cu")
		(net "SAS_EXP_B_PWR14")
	)
	(segment
		(start 15.423896 -454.727056)
		(end 18.791174 -458.094588)
		(width 0.14605)
		(layer "In5.Cu")
		(net "SAS_EXP_B_PWR14")
	)
	(segment
		(start 7.978648 -436.263796)
		(end 7.978648 -441.811918)
		(width 0.14605)
		(layer "In5.Cu")
		(net "SAS_EXP_B_PWR14")
	)
	(segment
		(start 11.349228 -395.104112)
		(end 13.541502 -397.296386)
		(width 0.14605)
		(layer "In5.Cu")
		(net "SAS_EXP_B_PWR14")
	)
	(segment
		(start 13.28674 -430.955704)
		(end 7.978648 -436.263796)
		(width 0.14605)
		(layer "In5.Cu")
		(net "SAS_EXP_B_PWR14")
	)
	(segment
		(start 31.338774 -458.619098)
		(end 35.73907 -454.218802)
		(width 0.14605)
		(layer "In5.Cu")
		(net "SAS_EXP_B_PWR14")
	)
	(segment
		(start 210.935062 -45.975016)
		(end 210.935062 -44.945046)
		(width 0.111252)
		(layer "F.Cu")
		(net "I2C_B_TMP4_A0")
	)
	(segment
		(start 211.327746 -46.3677)
		(end 210.935062 -45.975016)
		(width 0.111252)
		(layer "F.Cu")
		(net "I2C_B_TMP4_A0")
	)
	(segment
		(start 210.934808 -43.5102)
		(end 210.935062 -43.510454)
		(width 0.111252)
		(layer "F.Cu")
		(net "I2C_B_TMP4_A0")
	)
	(segment
		(start 210.934808 -42.760138)
		(end 210.934808 -43.5102)
		(width 0.111252)
		(layer "F.Cu")
		(net "I2C_B_TMP4_A0")
	)
	(segment
		(start 210.935062 -43.510454)
		(end 210.935062 -44.945046)
		(width 0.111252)
		(layer "F.Cu")
		(net "I2C_B_TMP4_A0")
	)
	(segment
		(start 213.486746 -46.3677)
		(end 211.327746 -46.3677)
		(width 0.111252)
		(layer "F.Cu")
		(net "I2C_B_TMP4_A0")
	)
	(segment
		(start 211.264246 -42.4307)
		(end 210.934808 -42.760138)
		(width 0.111252)
		(layer "F.Cu")
		(net "I2C_B_TMP4_A0")
	)
	(segment
		(start 211.264246 -41.4147)
		(end 211.264246 -42.4307)
		(width 0.111252)
		(layer "F.Cu")
		(net "I2C_B_TMP4_A0")
	)
	(segment
		(start 211.200746 -41.3512)
		(end 211.264246 -41.4147)
		(width 0.111252)
		(layer "F.Cu")
		(net "I2C_B_TMP4_A0")
	)
	(via
		(at 213.486746 -46.3677)
		(size 0.7112)
		(drill 0.3556)
		(layers "F.Cu" "B.Cu")
		(net "I2C_B_TMP4_A0")
	)
	(segment
		(start 31.22422 -57.488074)
		(end 30.602174 -58.11012)
		(width 0.09525)
		(layer "F.Cu")
		(net "SAS2X28_A_HDD9_RX_-")
	)
	(segment
		(start 13.004546 -357.505254)
		(end 12.191746 -358.3178)
		(width 0.09525)
		(layer "F.Cu")
		(net "SAS2X28_A_HDD9_RX_-")
	)
	(segment
		(start 27.838146 -161.224722)
		(end 27.838146 -182.767478)
		(width 0.09525)
		(layer "F.Cu")
		(net "SAS2X28_A_HDD9_RX_-")
	)
	(segment
		(start 13.261594 -357.253286)
		(end 13.26007 -357.25481)
		(width 0.09525)
		(layer "F.Cu")
		(net "SAS2X28_A_HDD9_RX_-")
	)
	(segment
		(start 15.874492 -273.8247)
		(end 14.404848 -275.294852)
		(width 0.09525)
		(layer "F.Cu")
		(net "SAS2X28_A_HDD9_RX_-")
	)
	(segment
		(start 31.931356 -57.3024)
		(end 31.67253 -57.3024)
		(width 0.09525)
		(layer "F.Cu")
		(net "SAS2X28_A_HDD9_RX_-")
	)
	(segment
		(start 13.261594 -357.252778)
		(end 13.261594 -357.253286)
		(width 0.09525)
		(layer "F.Cu")
		(net "SAS2X28_A_HDD9_RX_-")
	)
	(segment
		(start 11.531092 -363.82706)
		(end 8.543036 -366.815116)
		(width 0.09525)
		(layer "F.Cu")
		(net "SAS2X28_A_HDD9_RX_-")
	)
	(segment
		(start 34.594546 -191.628014)
		(end 34.594546 -254.2667)
		(width 0.09525)
		(layer "F.Cu")
		(net "SAS2X28_A_HDD9_RX_-")
	)
	(segment
		(start 32.9438 -126.753112)
		(end 32.9438 -154.014932)
		(width 0.09525)
		(layer "F.Cu")
		(net "SAS2X28_A_HDD9_RX_-")
	)
	(segment
		(start 28.582112 -184.563512)
		(end 33.85058 -189.83198)
		(width 0.09525)
		(layer "F.Cu")
		(net "SAS2X28_A_HDD9_RX_-")
	)
	(segment
		(start 32.199834 -155.810966)
		(end 28.582112 -159.428688)
		(width 0.09525)
		(layer "F.Cu")
		(net "SAS2X28_A_HDD9_RX_-")
	)
	(segment
		(start 34.002218 -255.696974)
		(end 15.874492 -273.8247)
		(width 0.09525)
		(layer "F.Cu")
		(net "SAS2X28_A_HDD9_RX_-")
	)
	(segment
		(start 29.895546 -59.816238)
		(end 29.895546 -121.934478)
		(width 0.09525)
		(layer "F.Cu")
		(net "SAS2X28_A_HDD9_RX_-")
	)
	(segment
		(start 11.865864 -359.104946)
		(end 11.865864 -363.018832)
		(width 0.09525)
		(layer "F.Cu")
		(net "SAS2X28_A_HDD9_RX_-")
	)
	(segment
		(start 13.009372 -357.505254)
		(end 13.004546 -357.505254)
		(width 0.09525)
		(layer "F.Cu")
		(net "SAS2X28_A_HDD9_RX_-")
	)
	(segment
		(start 7.363206 -367.867184)
		(end 7.289038 -367.867184)
		(width 0.09525)
		(layer "F.Cu")
		(net "SAS2X28_A_HDD9_RX_-")
	)
	(segment
		(start 13.26007 -357.25481)
		(end 13.009372 -357.505254)
		(width 0.09525)
		(layer "F.Cu")
		(net "SAS2X28_A_HDD9_RX_-")
	)
	(segment
		(start 30.639512 -123.730512)
		(end 32.4358 -125.5268)
		(width 0.09525)
		(layer "F.Cu")
		(net "SAS2X28_A_HDD9_RX_-")
	)
	(segment
		(start 13.804138 -276.744684)
		(end 13.804138 -355.9937)
		(width 0.09525)
		(layer "F.Cu")
		(net "SAS2X28_A_HDD9_RX_-")
	)
	(segment
		(start 13.297662 -357.21671)
		(end 13.261594 -357.252778)
		(width 0.09525)
		(layer "F.Cu")
		(net "SAS2X28_A_HDD9_RX_-")
	)
	(segment
		(start 7.993634 -367.0427)
		(end 7.993634 -367.042446)
		(width 0.09525)
		(layer "F.Cu")
		(net "SAS2X28_A_HDD9_RX_-")
	)
	(via
		(at 7.289038 -367.867184)
		(size 0.5588)
		(drill 0.3048)
		(layers "F.Cu" "B.Cu")
		(net "SAS2X28_A_HDD9_RX_-")
	)
	(arc
		(start 12.191746 -358.3178)
		(mid 11.950544 -358.678974)
		(end 11.865864 -359.104946)
		(width 0.09525)
		(layer "F.Cu")
		(net "SAS2X28_A_HDD9_RX_-")
	)
	(arc
		(start 13.804138 -355.9937)
		(mid 13.672504 -356.65556)
		(end 13.297662 -357.21671)
		(width 0.09525)
		(layer "F.Cu")
		(net "SAS2X28_A_HDD9_RX_-")
	)
	(arc
		(start 7.525258 -367.655348)
		(mid 7.496566 -367.801304)
		(end 7.363206 -367.867184)
		(width 0.09525)
		(layer "F.Cu")
		(net "SAS2X28_A_HDD9_RX_-")
	)
	(arc
		(start 33.85058 -189.83198)
		(mid 34.401178 -190.656007)
		(end 34.594546 -191.628014)
		(width 0.09525)
		(layer "F.Cu")
		(net "SAS2X28_A_HDD9_RX_-")
	)
	(arc
		(start 29.895546 -121.934478)
		(mid 30.088892 -122.906494)
		(end 30.639512 -123.730512)
		(width 0.09525)
		(layer "F.Cu")
		(net "SAS2X28_A_HDD9_RX_-")
	)
	(arc
		(start 32.575246 -57.0357)
		(mid 32.279827 -57.233093)
		(end 31.931356 -57.3024)
		(width 0.09525)
		(layer "F.Cu")
		(net "SAS2X28_A_HDD9_RX_-")
	)
	(arc
		(start 14.404848 -275.294852)
		(mid 13.9603 -275.960026)
		(end 13.804138 -276.744684)
		(width 0.09525)
		(layer "F.Cu")
		(net "SAS2X28_A_HDD9_RX_-")
	)
	(arc
		(start 32.4358 -125.5268)
		(mid 32.811742 -126.089437)
		(end 32.9438 -126.753112)
		(width 0.09525)
		(layer "F.Cu")
		(net "SAS2X28_A_HDD9_RX_-")
	)
	(arc
		(start 34.594546 -254.2667)
		(mid 34.4406 -255.040731)
		(end 34.002218 -255.696974)
		(width 0.09525)
		(layer "F.Cu")
		(net "SAS2X28_A_HDD9_RX_-")
	)
	(arc
		(start 32.9438 -154.014932)
		(mid 32.750454 -154.986948)
		(end 32.199834 -155.810966)
		(width 0.09525)
		(layer "F.Cu")
		(net "SAS2X28_A_HDD9_RX_-")
	)
	(arc
		(start 27.838146 -182.767478)
		(mid 28.031492 -183.739494)
		(end 28.582112 -184.563512)
		(width 0.09525)
		(layer "F.Cu")
		(net "SAS2X28_A_HDD9_RX_-")
	)
	(arc
		(start 8.543036 -366.815116)
		(mid 8.290968 -366.983542)
		(end 7.993634 -367.0427)
		(width 0.09525)
		(layer "F.Cu")
		(net "SAS2X28_A_HDD9_RX_-")
	)
	(arc
		(start 28.582112 -159.428688)
		(mid 28.031514 -160.252715)
		(end 27.838146 -161.224722)
		(width 0.09525)
		(layer "F.Cu")
		(net "SAS2X28_A_HDD9_RX_-")
	)
	(arc
		(start 7.993634 -367.042446)
		(mid 7.608025 -367.233197)
		(end 7.525258 -367.655348)
		(width 0.09525)
		(layer "F.Cu")
		(net "SAS2X28_A_HDD9_RX_-")
	)
	(arc
		(start 30.602174 -58.11012)
		(mid 30.079171 -58.892894)
		(end 29.895546 -59.816238)
		(width 0.09525)
		(layer "F.Cu")
		(net "SAS2X28_A_HDD9_RX_-")
	)
	(arc
		(start 31.67253 -57.3024)
		(mid 31.429915 -57.350659)
		(end 31.22422 -57.488074)
		(width 0.09525)
		(layer "F.Cu")
		(net "SAS2X28_A_HDD9_RX_-")
	)
	(arc
		(start 11.865864 -363.018832)
		(mid 11.778858 -363.456239)
		(end 11.531092 -363.82706)
		(width 0.09525)
		(layer "F.Cu")
		(net "SAS2X28_A_HDD9_RX_-")
	)
	(segment
		(start 7.670546 -366.9157)
		(end 7.670546 -367.2967)
		(width 0.09525)
		(layer "B.Cu")
		(net "SAS2X28_A_HDD9_RX_-")
	)
	(segment
		(start 6.6548 -364.476284)
		(end 6.6548 -364.871)
		(width 0.09525)
		(layer "B.Cu")
		(net "SAS2X28_A_HDD9_RX_-")
	)
	(segment
		(start 5.545074 -364.196884)
		(end 6.3754 -364.196884)
		(width 0.09525)
		(layer "B.Cu")
		(net "SAS2X28_A_HDD9_RX_-")
	)
	(segment
		(start 7.12597 -366.00003)
		(end 7.408164 -366.282224)
		(width 0.09525)
		(layer "B.Cu")
		(net "SAS2X28_A_HDD9_RX_-")
	)
	(segment
		(start 7.536942 -367.61928)
		(end 7.289038 -367.867184)
		(width 0.09525)
		(layer "B.Cu")
		(net "SAS2X28_A_HDD9_RX_-")
	)
	(segment
		(start 2.811526 -364.49889)
		(end 4.81076 -364.49889)
		(width 0.09525)
		(layer "B.Cu")
		(net "SAS2X28_A_HDD9_RX_-")
	)
	(segment
		(start 4.81076 -364.49889)
		(end 4.812284 -364.500414)
		(width 0.09525)
		(layer "B.Cu")
		(net "SAS2X28_A_HDD9_RX_-")
	)
	(arc
		(start 6.6548 -364.871)
		(mid 6.673963 -365.127839)
		(end 6.731 -365.379)
		(width 0.09525)
		(layer "B.Cu")
		(net "SAS2X28_A_HDD9_RX_-")
	)
	(arc
		(start 5.184394 -364.346236)
		(mid 5.34989 -364.235719)
		(end 5.545074 -364.196884)
		(width 0.09525)
		(layer "B.Cu")
		(net "SAS2X28_A_HDD9_RX_-")
	)
	(arc
		(start 7.408164 -366.282224)
		(mid 7.602364 -366.572865)
		(end 7.670546 -366.9157)
		(width 0.09525)
		(layer "B.Cu")
		(net "SAS2X28_A_HDD9_RX_-")
	)
	(arc
		(start 4.812284 -364.500414)
		(mid 5.013686 -364.460353)
		(end 5.184394 -364.346236)
		(width 0.09525)
		(layer "B.Cu")
		(net "SAS2X28_A_HDD9_RX_-")
	)
	(arc
		(start 7.670546 -367.2967)
		(mid 7.635821 -367.471274)
		(end 7.536942 -367.61928)
		(width 0.09525)
		(layer "B.Cu")
		(net "SAS2X28_A_HDD9_RX_-")
	)
	(arc
		(start 6.3754 -364.196884)
		(mid 6.572966 -364.278718)
		(end 6.6548 -364.476284)
		(width 0.09525)
		(layer "B.Cu")
		(net "SAS2X28_A_HDD9_RX_-")
	)
	(arc
		(start 6.731 -365.379)
		(mid 6.886614 -365.716144)
		(end 7.12597 -366.00003)
		(width 0.09525)
		(layer "B.Cu")
		(net "SAS2X28_A_HDD9_RX_-")
	)
	(segment
		(start 207.009746 -453.0852)
		(end 207.581246 -453.6567)
		(width 0.111252)
		(layer "F.Cu")
		(net "I2C_B_TMP3_A2")
	)
	(segment
		(start 207.581246 -456.3872)
		(end 207.581246 -455.4347)
		(width 0.111252)
		(layer "F.Cu")
		(net "I2C_B_TMP3_A2")
	)
	(segment
		(start 207.581246 -453.6567)
		(end 207.581246 -454.1647)
		(width 0.111252)
		(layer "F.Cu")
		(net "I2C_B_TMP3_A2")
	)
	(segment
		(start 209.634582 -456.945238)
		(end 208.13903 -456.945238)
		(width 0.111252)
		(layer "F.Cu")
		(net "I2C_B_TMP3_A2")
	)
	(segment
		(start 208.13903 -456.945238)
		(end 207.981296 -456.787504)
		(width 0.111252)
		(layer "F.Cu")
		(net "I2C_B_TMP3_A2")
	)
	(segment
		(start 207.581246 -454.1647)
		(end 207.581246 -455.4347)
		(width 0.111252)
		(layer "F.Cu")
		(net "I2C_B_TMP3_A2")
	)
	(segment
		(start 207.981296 -456.787504)
		(end 207.581246 -456.3872)
		(width 0.111252)
		(layer "F.Cu")
		(net "I2C_B_TMP3_A2")
	)
	(via
		(at 207.581246 -455.4347)
		(size 0.7112)
		(drill 0.3556)
		(layers "F.Cu" "B.Cu")
		(net "I2C_B_TMP3_A2")
	)
	(segment
		(start 12.196064 -359.1052)
		(end 12.196064 -363.01934)
		(width 0.09525)
		(layer "F.Cu")
		(net "SAS2X28_A_HDD9_RX_+")
	)
	(segment
		(start 7.993634 -367.373154)
		(end 7.993888 -367.3729)
		(width 0.09525)
		(layer "F.Cu")
		(net "SAS2X28_A_HDD9_RX_+")
	)
	(segment
		(start 13.141452 -357.835454)
		(end 12.425426 -358.55148)
		(width 0.09525)
		(layer "F.Cu")
		(net "SAS2X28_A_HDD9_RX_+")
	)
	(segment
		(start 30.226 -59.816238)
		(end 30.225746 -59.815984)
		(width 0.09525)
		(layer "F.Cu")
		(net "SAS2X28_A_HDD9_RX_+")
	)
	(segment
		(start 32.575246 -57.9247)
		(end 32.44469 -57.794144)
		(width 0.09525)
		(layer "F.Cu")
		(net "SAS2X28_A_HDD9_RX_+")
	)
	(segment
		(start 28.815792 -184.329832)
		(end 34.08426 -189.5983)
		(width 0.09525)
		(layer "F.Cu")
		(net "SAS2X28_A_HDD9_RX_+")
	)
	(segment
		(start 32.433514 -156.044646)
		(end 28.912312 -159.565848)
		(width 0.09525)
		(layer "F.Cu")
		(net "SAS2X28_A_HDD9_RX_+")
	)
	(segment
		(start 30.225746 -59.815984)
		(end 30.225746 -121.934478)
		(width 0.09525)
		(layer "F.Cu")
		(net "SAS2X28_A_HDD9_RX_+")
	)
	(segment
		(start 16.108172 -274.05838)
		(end 14.638528 -275.528532)
		(width 0.09525)
		(layer "F.Cu")
		(net "SAS2X28_A_HDD9_RX_+")
	)
	(segment
		(start 34.235898 -255.930654)
		(end 16.108172 -274.05838)
		(width 0.09525)
		(layer "F.Cu")
		(net "SAS2X28_A_HDD9_RX_+")
	)
	(segment
		(start 34.924746 -191.628014)
		(end 34.924746 -254.266446)
		(width 0.09525)
		(layer "F.Cu")
		(net "SAS2X28_A_HDD9_RX_+")
	)
	(segment
		(start 13.531342 -357.45039)
		(end 13.43152 -357.55072)
		(width 0.09525)
		(layer "F.Cu")
		(net "SAS2X28_A_HDD9_RX_+")
	)
	(segment
		(start 13.43152 -357.55072)
		(end 13.146278 -357.835454)
		(width 0.09525)
		(layer "F.Cu")
		(net "SAS2X28_A_HDD9_RX_+")
	)
	(segment
		(start 32.0548 -57.6326)
		(end 31.672276 -57.6326)
		(width 0.09525)
		(layer "F.Cu")
		(net "SAS2X28_A_HDD9_RX_+")
	)
	(segment
		(start 7.88416 -367.637822)
		(end 8.151876 -367.905792)
		(width 0.09525)
		(layer "F.Cu")
		(net "SAS2X28_A_HDD9_RX_+")
	)
	(segment
		(start 31.4579 -57.721754)
		(end 30.835854 -58.3438)
		(width 0.09525)
		(layer "F.Cu")
		(net "SAS2X28_A_HDD9_RX_+")
	)
	(segment
		(start 14.134338 -276.744938)
		(end 14.134338 -355.9937)
		(width 0.09525)
		(layer "F.Cu")
		(net "SAS2X28_A_HDD9_RX_+")
	)
	(segment
		(start 33.274 -126.752858)
		(end 33.274 -154.014932)
		(width 0.09525)
		(layer "F.Cu")
		(net "SAS2X28_A_HDD9_RX_+")
	)
	(segment
		(start 11.764518 -364.060994)
		(end 8.776716 -367.048796)
		(width 0.09525)
		(layer "F.Cu")
		(net "SAS2X28_A_HDD9_RX_+")
	)
	(segment
		(start 13.146278 -357.835454)
		(end 13.141452 -357.835454)
		(width 0.09525)
		(layer "F.Cu")
		(net "SAS2X28_A_HDD9_RX_+")
	)
	(segment
		(start 28.168346 -161.361882)
		(end 28.168346 -182.767478)
		(width 0.09525)
		(layer "F.Cu")
		(net "SAS2X28_A_HDD9_RX_+")
	)
	(segment
		(start 30.873192 -123.496832)
		(end 32.66948 -125.29312)
		(width 0.09525)
		(layer "F.Cu")
		(net "SAS2X28_A_HDD9_RX_+")
	)
	(via
		(at 8.151876 -367.905792)
		(size 0.5588)
		(drill 0.3048)
		(layers "F.Cu" "B.Cu")
		(net "SAS2X28_A_HDD9_RX_+")
	)
	(arc
		(start 34.924746 -254.266446)
		(mid 34.745894 -255.167097)
		(end 34.235898 -255.930654)
		(width 0.09525)
		(layer "F.Cu")
		(net "SAS2X28_A_HDD9_RX_+")
	)
	(arc
		(start 33.274 -154.014932)
		(mid 33.055602 -155.113364)
		(end 32.433514 -156.044646)
		(width 0.09525)
		(layer "F.Cu")
		(net "SAS2X28_A_HDD9_RX_+")
	)
	(arc
		(start 32.66948 -125.29312)
		(mid 33.116874 -125.962882)
		(end 33.274 -126.752858)
		(width 0.09525)
		(layer "F.Cu")
		(net "SAS2X28_A_HDD9_RX_+")
	)
	(arc
		(start 14.134338 -355.9937)
		(mid 13.97775 -356.782044)
		(end 13.531342 -357.45039)
		(width 0.09525)
		(layer "F.Cu")
		(net "SAS2X28_A_HDD9_RX_+")
	)
	(arc
		(start 30.225746 -121.934478)
		(mid 30.394055 -122.780064)
		(end 30.873192 -123.496832)
		(width 0.09525)
		(layer "F.Cu")
		(net "SAS2X28_A_HDD9_RX_+")
	)
	(arc
		(start 7.993888 -367.3729)
		(mid 7.870425 -367.433729)
		(end 7.844028 -367.568734)
		(width 0.09525)
		(layer "F.Cu")
		(net "SAS2X28_A_HDD9_RX_+")
	)
	(arc
		(start 12.196064 -363.01934)
		(mid 12.083923 -363.583109)
		(end 11.764518 -364.060994)
		(width 0.09525)
		(layer "F.Cu")
		(net "SAS2X28_A_HDD9_RX_+")
	)
	(arc
		(start 12.425426 -358.55148)
		(mid 12.255676 -358.805529)
		(end 12.196064 -359.1052)
		(width 0.09525)
		(layer "F.Cu")
		(net "SAS2X28_A_HDD9_RX_+")
	)
	(arc
		(start 32.44469 -57.794144)
		(mid 32.265808 -57.674589)
		(end 32.0548 -57.6326)
		(width 0.09525)
		(layer "F.Cu")
		(net "SAS2X28_A_HDD9_RX_+")
	)
	(arc
		(start 34.08426 -189.5983)
		(mid 34.706412 -190.529556)
		(end 34.924746 -191.628014)
		(width 0.09525)
		(layer "F.Cu")
		(net "SAS2X28_A_HDD9_RX_+")
	)
	(arc
		(start 30.835854 -58.3438)
		(mid 30.384405 -59.019346)
		(end 30.226 -59.816238)
		(width 0.09525)
		(layer "F.Cu")
		(net "SAS2X28_A_HDD9_RX_+")
	)
	(arc
		(start 28.168346 -182.767478)
		(mid 28.336655 -183.613064)
		(end 28.815792 -184.329832)
		(width 0.09525)
		(layer "F.Cu")
		(net "SAS2X28_A_HDD9_RX_+")
	)
	(arc
		(start 31.672276 -57.6326)
		(mid 31.556227 -57.655871)
		(end 31.4579 -57.721754)
		(width 0.09525)
		(layer "F.Cu")
		(net "SAS2X28_A_HDD9_RX_+")
	)
	(arc
		(start 7.844028 -367.568734)
		(mid 7.859555 -367.605917)
		(end 7.88416 -367.637822)
		(width 0.09525)
		(layer "F.Cu")
		(net "SAS2X28_A_HDD9_RX_+")
	)
	(arc
		(start 14.638528 -275.528532)
		(mid 14.265433 -276.08658)
		(end 14.134338 -276.744938)
		(width 0.09525)
		(layer "F.Cu")
		(net "SAS2X28_A_HDD9_RX_+")
	)
	(arc
		(start 28.912312 -159.565848)
		(mid 28.361714 -160.389875)
		(end 28.168346 -161.361882)
		(width 0.09525)
		(layer "F.Cu")
		(net "SAS2X28_A_HDD9_RX_+")
	)
	(arc
		(start 8.776716 -367.048796)
		(mid 8.417435 -367.28886)
		(end 7.993634 -367.373154)
		(width 0.09525)
		(layer "F.Cu")
		(net "SAS2X28_A_HDD9_RX_+")
	)
	(segment
		(start 8.000746 -367.541048)
		(end 8.000746 -366.9157)
		(width 0.09525)
		(layer "B.Cu")
		(net "SAS2X28_A_HDD9_RX_+")
	)
	(segment
		(start 6.985 -364.871)
		(end 6.985 -364.476284)
		(width 0.09525)
		(layer "B.Cu")
		(net "SAS2X28_A_HDD9_RX_+")
	)
	(segment
		(start 4.944618 -363.498892)
		(end 2.811526 -363.498892)
		(width 0.09525)
		(layer "B.Cu")
		(net "SAS2X28_A_HDD9_RX_+")
	)
	(segment
		(start 4.946142 -363.500416)
		(end 4.944618 -363.498892)
		(width 0.09525)
		(layer "B.Cu")
		(net "SAS2X28_A_HDD9_RX_+")
	)
	(segment
		(start 7.641844 -366.048544)
		(end 7.353554 -365.760254)
		(width 0.09525)
		(layer "B.Cu")
		(net "SAS2X28_A_HDD9_RX_+")
	)
	(segment
		(start 7.046722 -365.281972)
		(end 7.046468 -365.281972)
		(width 0.09525)
		(layer "B.Cu")
		(net "SAS2X28_A_HDD9_RX_+")
	)
	(segment
		(start 6.3754 -363.866684)
		(end 5.830316 -363.866684)
		(width 0.09525)
		(layer "B.Cu")
		(net "SAS2X28_A_HDD9_RX_+")
	)
	(arc
		(start 5.399278 -363.688122)
		(mid 5.191377 -363.549207)
		(end 4.946142 -363.500416)
		(width 0.09525)
		(layer "B.Cu")
		(net "SAS2X28_A_HDD9_RX_+")
	)
	(arc
		(start 8.151876 -367.905792)
		(mid 8.040059 -367.738446)
		(end 8.000746 -367.541048)
		(width 0.09525)
		(layer "B.Cu")
		(net "SAS2X28_A_HDD9_RX_+")
	)
	(arc
		(start 7.347712 -365.755174)
		(mid 7.165342 -365.538851)
		(end 7.046722 -365.281972)
		(width 0.09525)
		(layer "B.Cu")
		(net "SAS2X28_A_HDD9_RX_+")
	)
	(arc
		(start 6.985 -364.476284)
		(mid 6.806452 -364.045232)
		(end 6.3754 -363.866684)
		(width 0.09525)
		(layer "B.Cu")
		(net "SAS2X28_A_HDD9_RX_+")
	)
	(arc
		(start 7.353554 -365.760254)
		(mid 7.350628 -365.757719)
		(end 7.347712 -365.755174)
		(width 0.09525)
		(layer "B.Cu")
		(net "SAS2X28_A_HDD9_RX_+")
	)
	(arc
		(start 8.000746 -366.9157)
		(mid 7.907516 -366.44644)
		(end 7.641844 -366.048544)
		(width 0.09525)
		(layer "B.Cu")
		(net "SAS2X28_A_HDD9_RX_+")
	)
	(arc
		(start 7.046468 -365.281972)
		(mid 7.000402 -365.078779)
		(end 6.985 -364.871)
		(width 0.09525)
		(layer "B.Cu")
		(net "SAS2X28_A_HDD9_RX_+")
	)
	(arc
		(start 5.830316 -363.866684)
		(mid 5.597032 -363.820281)
		(end 5.399278 -363.688122)
		(width 0.09525)
		(layer "B.Cu")
		(net "SAS2X28_A_HDD9_RX_+")
	)
	(segment
		(start 208.559146 -453.5551)
		(end 208.177638 -453.173592)
		(width 0.111252)
		(layer "F.Cu")
		(net "I2C_B_TMP3_A1")
	)
	(segment
		(start 209.459576 -454.1647)
		(end 208.849976 -453.5551)
		(width 0.111252)
		(layer "F.Cu")
		(net "I2C_B_TMP3_A1")
	)
	(segment
		(start 208.178146 -453.086978)
		(end 208.176622 -453.086978)
		(width 0.111252)
		(layer "F.Cu")
		(net "I2C_B_TMP3_A1")
	)
	(segment
		(start 209.232246 -452.8947)
		(end 208.370424 -452.8947)
		(width 0.111252)
		(layer "F.Cu")
		(net "I2C_B_TMP3_A1")
	)
	(segment
		(start 208.370424 -452.8947)
		(end 208.178146 -453.086978)
		(width 0.111252)
		(layer "F.Cu")
		(net "I2C_B_TMP3_A1")
	)
	(segment
		(start 208.849976 -453.5551)
		(end 208.559146 -453.5551)
		(width 0.111252)
		(layer "F.Cu")
		(net "I2C_B_TMP3_A1")
	)
	(segment
		(start 210.284822 -456.945238)
		(end 210.284822 -456.169776)
		(width 0.111252)
		(layer "F.Cu")
		(net "I2C_B_TMP3_A1")
	)
	(segment
		(start 209.486246 -454.1647)
		(end 209.459576 -454.1647)
		(width 0.111252)
		(layer "F.Cu")
		(net "I2C_B_TMP3_A1")
	)
	(segment
		(start 209.422746 -453.0852)
		(end 209.232246 -452.8947)
		(width 0.111252)
		(layer "F.Cu")
		(net "I2C_B_TMP3_A1")
	)
	(segment
		(start 209.486246 -455.3712)
		(end 209.486246 -454.1647)
		(width 0.111252)
		(layer "F.Cu")
		(net "I2C_B_TMP3_A1")
	)
	(segment
		(start 208.177638 -453.087994)
		(end 208.176622 -453.086978)
		(width 0.111252)
		(layer "F.Cu")
		(net "I2C_B_TMP3_A1")
	)
	(segment
		(start 210.284822 -456.169776)
		(end 209.486246 -455.3712)
		(width 0.111252)
		(layer "F.Cu")
		(net "I2C_B_TMP3_A1")
	)
	(segment
		(start 208.177638 -453.173592)
		(end 208.177638 -453.087994)
		(width 0.111252)
		(layer "F.Cu")
		(net "I2C_B_TMP3_A1")
	)
	(via
		(at 208.176622 -453.086978)
		(size 0.7112)
		(drill 0.3556)
		(layers "F.Cu" "B.Cu")
		(net "I2C_B_TMP3_A1")
	)
	(segment
		(start 40.39997 -61.789818)
		(end 39.39667 -61.789818)
		(width 0.09525)
		(layer "F.Cu")
		(net "SAS2X28_B_HDD9_TX_-")
	)
	(segment
		(start 6.312916 -107.9627)
		(end 5.588 -107.9627)
		(width 0.09525)
		(layer "F.Cu")
		(net "SAS2X28_B_HDD9_TX_-")
	)
	(segment
		(start 5.304282 -108.182918)
		(end 5.304282 -108.19257)
		(width 0.09525)
		(layer "F.Cu")
		(net "SAS2X28_B_HDD9_TX_-")
	)
	(segment
		(start 5.228082 -108.309918)
		(end 5.207 -108.331)
		(width 0.09525)
		(layer "F.Cu")
		(net "SAS2X28_B_HDD9_TX_-")
	)
	(segment
		(start 39.232078 -61.719714)
		(end 39.155878 -61.643514)
		(width 0.09525)
		(layer "F.Cu")
		(net "SAS2X28_B_HDD9_TX_-")
	)
	(segment
		(start 39.39667 -61.789818)
		(end 39.393368 -61.786516)
		(width 0.09525)
		(layer "F.Cu")
		(net "SAS2X28_B_HDD9_TX_-")
	)
	(segment
		(start 38.322504 -61.627258)
		(end 38.099746 -61.850016)
		(width 0.09525)
		(layer "F.Cu")
		(net "SAS2X28_B_HDD9_TX_-")
	)
	(segment
		(start 38.93439 -61.55182)
		(end 38.504622 -61.55182)
		(width 0.09525)
		(layer "F.Cu")
		(net "SAS2X28_B_HDD9_TX_-")
	)
	(segment
		(start 4.801616 -108.498894)
		(end 3.192526 -108.498894)
		(width 0.09525)
		(layer "F.Cu")
		(net "SAS2X28_B_HDD9_TX_-")
	)
	(via
		(at 6.737096 -108.38688)
		(size 0.5588)
		(drill 0.3048)
		(layers "F.Cu" "B.Cu")
		(net "SAS2X28_B_HDD9_TX_-")
	)
	(via
		(at 38.099746 -61.850016)
		(size 0.5588)
		(drill 0.3048)
		(layers "F.Cu" "B.Cu")
		(net "SAS2X28_B_HDD9_TX_-")
	)
	(arc
		(start 38.490144 -61.552074)
		(mid 38.3994 -61.574225)
		(end 38.322504 -61.627258)
		(width 0.09525)
		(layer "F.Cu")
		(net "SAS2X28_B_HDD9_TX_-")
	)
	(arc
		(start 38.504622 -61.55182)
		(mid 38.497381 -61.551843)
		(end 38.490144 -61.552074)
		(width 0.09525)
		(layer "F.Cu")
		(net "SAS2X28_B_HDD9_TX_-")
	)
	(arc
		(start 39.155878 -61.643514)
		(mid 39.054258 -61.575614)
		(end 38.93439 -61.55182)
		(width 0.09525)
		(layer "F.Cu")
		(net "SAS2X28_B_HDD9_TX_-")
	)
	(arc
		(start 6.737096 -108.38688)
		(mid 6.612857 -108.086939)
		(end 6.312916 -107.9627)
		(width 0.09525)
		(layer "F.Cu")
		(net "SAS2X28_B_HDD9_TX_-")
	)
	(arc
		(start 39.393368 -61.786516)
		(mid 39.306081 -61.769154)
		(end 39.232078 -61.719714)
		(width 0.09525)
		(layer "F.Cu")
		(net "SAS2X28_B_HDD9_TX_-")
	)
	(arc
		(start 5.363972 -108.0389)
		(mid 5.319821 -108.104976)
		(end 5.304282 -108.182918)
		(width 0.09525)
		(layer "F.Cu")
		(net "SAS2X28_B_HDD9_TX_-")
	)
	(arc
		(start 5.588 -107.9627)
		(mid 5.469667 -107.982227)
		(end 5.363972 -108.0389)
		(width 0.09525)
		(layer "F.Cu")
		(net "SAS2X28_B_HDD9_TX_-")
	)
	(arc
		(start 5.207 -108.331)
		(mid 5.021008 -108.455276)
		(end 4.801616 -108.498894)
		(width 0.09525)
		(layer "F.Cu")
		(net "SAS2X28_B_HDD9_TX_-")
	)
	(arc
		(start 5.304282 -108.19257)
		(mid 5.272342 -108.255241)
		(end 5.228082 -108.309918)
		(width 0.09525)
		(layer "F.Cu")
		(net "SAS2X28_B_HDD9_TX_-")
	)
	(segment
		(start 20.268946 -79.157576)
		(end 20.268946 -95.48241)
		(width 0.09525)
		(layer "B.Cu")
		(net "SAS2X28_B_HDD9_TX_-")
	)
	(segment
		(start 6.755892 -108.368338)
		(end 6.737096 -108.38688)
		(width 0.09525)
		(layer "B.Cu")
		(net "SAS2X28_B_HDD9_TX_-")
	)
	(segment
		(start 7.75462 -108.168186)
		(end 7.238746 -108.168186)
		(width 0.09525)
		(layer "B.Cu")
		(net "SAS2X28_B_HDD9_TX_-")
	)
	(segment
		(start 8.418322 -107.73283)
		(end 8.418576 -107.733084)
		(width 0.09525)
		(layer "B.Cu")
		(net "SAS2X28_B_HDD9_TX_-")
	)
	(segment
		(start 37.69868 -61.6839)
		(end 35.64509 -61.6839)
		(width 0.09525)
		(layer "B.Cu")
		(net "SAS2X28_B_HDD9_TX_-")
	)
	(segment
		(start 32.500824 -66.463418)
		(end 20.595844 -78.368398)
		(width 0.09525)
		(layer "B.Cu")
		(net "SAS2X28_B_HDD9_TX_-")
	)
	(segment
		(start 33.400746 -64.179704)
		(end 33.400746 -65.1637)
		(width 0.09525)
		(layer "B.Cu")
		(net "SAS2X28_B_HDD9_TX_-")
	)
	(segment
		(start 33.118044 -65.846198)
		(end 33.024064 -65.940178)
		(width 0.09525)
		(layer "B.Cu")
		(net "SAS2X28_B_HDD9_TX_-")
	)
	(segment
		(start 8.418576 -107.733084)
		(end 8.14451 -108.006896)
		(width 0.09525)
		(layer "B.Cu")
		(net "SAS2X28_B_HDD9_TX_-")
	)
	(segment
		(start 33.024064 -65.940178)
		(end 32.502094 -66.463418)
		(width 0.09525)
		(layer "B.Cu")
		(net "SAS2X28_B_HDD9_TX_-")
	)
	(segment
		(start 32.502094 -66.463418)
		(end 32.500824 -66.463418)
		(width 0.09525)
		(layer "B.Cu")
		(net "SAS2X28_B_HDD9_TX_-")
	)
	(segment
		(start 19.986244 -96.164908)
		(end 8.418322 -107.73283)
		(width 0.09525)
		(layer "B.Cu")
		(net "SAS2X28_B_HDD9_TX_-")
	)
	(segment
		(start 35.369246 -61.7982)
		(end 33.692846 -63.4746)
		(width 0.09525)
		(layer "B.Cu")
		(net "SAS2X28_B_HDD9_TX_-")
	)
	(arc
		(start 33.400746 -65.1637)
		(mid 33.327275 -65.533066)
		(end 33.118044 -65.846198)
		(width 0.09525)
		(layer "B.Cu")
		(net "SAS2X28_B_HDD9_TX_-")
	)
	(arc
		(start 8.14451 -108.006896)
		(mid 7.965612 -108.126339)
		(end 7.75462 -108.168186)
		(width 0.09525)
		(layer "B.Cu")
		(net "SAS2X28_B_HDD9_TX_-")
	)
	(arc
		(start 38.099746 -61.850016)
		(mid 37.915735 -61.727064)
		(end 37.69868 -61.6839)
		(width 0.09525)
		(layer "B.Cu")
		(net "SAS2X28_B_HDD9_TX_-")
	)
	(arc
		(start 33.621472 -63.553848)
		(mid 33.457547 -63.84788)
		(end 33.400746 -64.179704)
		(width 0.09525)
		(layer "B.Cu")
		(net "SAS2X28_B_HDD9_TX_-")
	)
	(arc
		(start 20.268946 -95.48241)
		(mid 20.195475 -95.851776)
		(end 19.986244 -96.164908)
		(width 0.09525)
		(layer "B.Cu")
		(net "SAS2X28_B_HDD9_TX_-")
	)
	(arc
		(start 20.595844 -78.368398)
		(mid 20.353911 -78.730476)
		(end 20.268946 -79.157576)
		(width 0.09525)
		(layer "B.Cu")
		(net "SAS2X28_B_HDD9_TX_-")
	)
	(arc
		(start 35.64509 -61.6839)
		(mid 35.495788 -61.713598)
		(end 35.369246 -61.7982)
		(width 0.09525)
		(layer "B.Cu")
		(net "SAS2X28_B_HDD9_TX_-")
	)
	(arc
		(start 7.238746 -108.168186)
		(mid 6.977425 -108.22026)
		(end 6.755892 -108.368338)
		(width 0.09525)
		(layer "B.Cu")
		(net "SAS2X28_B_HDD9_TX_-")
	)
	(arc
		(start 33.692846 -63.4746)
		(mid 33.656099 -63.513269)
		(end 33.621472 -63.553848)
		(width 0.09525)
		(layer "B.Cu")
		(net "SAS2X28_B_HDD9_TX_-")
	)
	(segment
		(start 210.975448 -455.064368)
		(end 210.975448 -455.659998)
		(width 0.111252)
		(layer "F.Cu")
		(net "I2C_B_TMP3_A0")
	)
	(segment
		(start 211.391246 -454.64857)
		(end 210.975448 -455.064368)
		(width 0.111252)
		(layer "F.Cu")
		(net "I2C_B_TMP3_A0")
	)
	(segment
		(start 210.934808 -455.700638)
		(end 210.934808 -456.944984)
		(width 0.111252)
		(layer "F.Cu")
		(net "I2C_B_TMP3_A0")
	)
	(segment
		(start 210.934808 -456.944984)
		(end 210.935062 -456.945238)
		(width 0.111252)
		(layer "F.Cu")
		(net "I2C_B_TMP3_A0")
	)
	(segment
		(start 210.616546 -453.0725)
		(end 210.616546 -453.39)
		(width 0.111252)
		(layer "F.Cu")
		(net "I2C_B_TMP3_A0")
	)
	(segment
		(start 211.391246 -454.1647)
		(end 211.391246 -454.64857)
		(width 0.111252)
		(layer "F.Cu")
		(net "I2C_B_TMP3_A0")
	)
	(segment
		(start 210.616546 -453.39)
		(end 211.391246 -454.1647)
		(width 0.111252)
		(layer "F.Cu")
		(net "I2C_B_TMP3_A0")
	)
	(segment
		(start 210.756246 -453.0725)
		(end 210.616546 -453.0725)
		(width 0.111252)
		(layer "F.Cu")
		(net "I2C_B_TMP3_A0")
	)
	(segment
		(start 210.768946 -453.0852)
		(end 210.756246 -453.0725)
		(width 0.111252)
		(layer "F.Cu")
		(net "I2C_B_TMP3_A0")
	)
	(segment
		(start 210.975448 -455.659998)
		(end 210.934808 -455.700638)
		(width 0.111252)
		(layer "F.Cu")
		(net "I2C_B_TMP3_A0")
	)
	(segment
		(start 211.708746 -453.0852)
		(end 210.768946 -453.0852)
		(width 0.111252)
		(layer "F.Cu")
		(net "I2C_B_TMP3_A0")
	)
	(via
		(at 210.616546 -453.0725)
		(size 0.7112)
		(drill 0.3556)
		(layers "F.Cu" "B.Cu")
		(net "I2C_B_TMP3_A0")
	)
	(segment
		(start 47.332646 -41.021)
		(end 50.406046 -41.021)
		(width 0.111252)
		(layer "F.Cu")
		(net "DRIVE_ACT_9")
	)
	(segment
		(start 47.218346 -40.9067)
		(end 47.256446 -40.9448)
		(width 0.111252)
		(layer "F.Cu")
		(net "DRIVE_ACT_9")
	)
	(segment
		(start 47.256446 -40.9448)
		(end 47.332646 -41.021)
		(width 0.111252)
		(layer "F.Cu")
		(net "DRIVE_ACT_9")
	)
	(segment
		(start 50.406046 -41.021)
		(end 51.17846 -41.793414)
		(width 0.111252)
		(layer "F.Cu")
		(net "DRIVE_ACT_9")
	)
	(segment
		(start 51.17846 -41.793414)
		(end 51.196494 -41.793414)
		(width 0.111252)
		(layer "F.Cu")
		(net "DRIVE_ACT_9")
	)
	(segment
		(start 45.783246 -40.9067)
		(end 47.218346 -40.9067)
		(width 0.111252)
		(layer "F.Cu")
		(net "DRIVE_ACT_9")
	)
	(segment
		(start 45.783246 -41.9227)
		(end 45.783246 -40.9067)
		(width 0.111252)
		(layer "F.Cu")
		(net "DRIVE_ACT_9")
	)
	(via
		(at 51.196494 -41.793414)
		(size 0.7112)
		(drill 0.3556)
		(layers "F.Cu" "B.Cu")
		(net "DRIVE_ACT_9")
	)
	(segment
		(start 40.500046 -133.3119)
		(end 41.624504 -134.436358)
		(width 0.111252)
		(layer "F.Cu")
		(net "I2C_B_TMP2_A2")
	)
	(segment
		(start 41.624504 -134.436358)
		(end 41.624504 -135.454898)
		(width 0.111252)
		(layer "F.Cu")
		(net "I2C_B_TMP2_A2")
	)
	(segment
		(start 38.531546 -133.2611)
		(end 38.582346 -133.2611)
		(width 0.111252)
		(layer "F.Cu")
		(net "I2C_B_TMP2_A2")
	)
	(segment
		(start 40.436546 -132.2324)
		(end 40.436546 -133.2484)
		(width 0.111252)
		(layer "F.Cu")
		(net "I2C_B_TMP2_A2")
	)
	(segment
		(start 41.624504 -135.454898)
		(end 41.624758 -135.455152)
		(width 0.111252)
		(layer "F.Cu")
		(net "I2C_B_TMP2_A2")
	)
	(segment
		(start 39.611046 -132.2324)
		(end 40.436546 -132.2324)
		(width 0.111252)
		(layer "F.Cu")
		(net "I2C_B_TMP2_A2")
	)
	(segment
		(start 38.582346 -133.2611)
		(end 39.611046 -132.2324)
		(width 0.111252)
		(layer "F.Cu")
		(net "I2C_B_TMP2_A2")
	)
	(segment
		(start 40.436546 -133.2484)
		(end 40.500046 -133.3119)
		(width 0.111252)
		(layer "F.Cu")
		(net "I2C_B_TMP2_A2")
	)
	(via
		(at 38.531546 -133.2611)
		(size 0.7112)
		(drill 0.3556)
		(layers "F.Cu" "B.Cu")
		(net "I2C_B_TMP2_A2")
	)
	(segment
		(start 71.246746 -86.8172)
		(end 71.500746 -86.5632)
		(width 0.111252)
		(layer "F.Cu")
		(net "SAS2X28_A_HDD9_FLT")
	)
	(segment
		(start 71.500746 -85.9917)
		(end 71.500746 -84.7852)
		(width 0.111252)
		(layer "F.Cu")
		(net "SAS2X28_A_HDD9_FLT")
	)
	(segment
		(start 71.500746 -86.5632)
		(end 71.500746 -85.9917)
		(width 0.111252)
		(layer "F.Cu")
		(net "SAS2X28_A_HDD9_FLT")
	)
	(via
		(at 71.500746 -85.9917)
		(size 0.5588)
		(drill 0.3048)
		(layers "F.Cu" "B.Cu")
		(net "SAS2X28_A_HDD9_FLT")
	)
	(via
		(at 23.215346 -393.5857)
		(size 0.7112)
		(drill 0.3556)
		(layers "F.Cu" "B.Cu")
		(net "SAS2X28_A_HDD9_FLT")
	)
	(via
		(at 24.4348 -393.7254)
		(size 0.5588)
		(drill 0.3048)
		(layers "F.Cu" "B.Cu")
		(net "SAS2X28_A_HDD9_FLT")
	)
	(via
		(at 99.313746 -384.657092)
		(size 0.5588)
		(drill 0.3048)
		(layers "F.Cu" "B.Cu")
		(net "SAS2X28_A_HDD9_FLT")
	)
	(segment
		(start 8.203184 -392.423396)
		(end 7.862062 -392.082274)
		(width 0.111252)
		(layer "B.Cu")
		(net "SAS2X28_A_HDD9_FLT")
	)
	(segment
		(start 2.81305 -391.50036)
		(end 2.811526 -391.498836)
		(width 0.111252)
		(layer "B.Cu")
		(net "SAS2X28_A_HDD9_FLT")
	)
	(segment
		(start 16.357346 -393.5857)
		(end 15.195042 -392.423396)
		(width 0.111252)
		(layer "B.Cu")
		(net "SAS2X28_A_HDD9_FLT")
	)
	(segment
		(start 7.862062 -392.082274)
		(end 6.408674 -392.082274)
		(width 0.111252)
		(layer "B.Cu")
		(net "SAS2X28_A_HDD9_FLT")
	)
	(segment
		(start 15.195042 -392.423396)
		(end 8.203184 -392.423396)
		(width 0.111252)
		(layer "B.Cu")
		(net "SAS2X28_A_HDD9_FLT")
	)
	(segment
		(start 6.408674 -392.082274)
		(end 5.82676 -391.50036)
		(width 0.111252)
		(layer "B.Cu")
		(net "SAS2X28_A_HDD9_FLT")
	)
	(segment
		(start 23.215346 -393.5857)
		(end 16.357346 -393.5857)
		(width 0.111252)
		(layer "B.Cu")
		(net "SAS2X28_A_HDD9_FLT")
	)
	(segment
		(start 5.82676 -391.50036)
		(end 2.81305 -391.50036)
		(width 0.111252)
		(layer "B.Cu")
		(net "SAS2X28_A_HDD9_FLT")
	)
	(segment
		(start 24.2951 -393.5857)
		(end 23.215346 -393.5857)
		(width 0.111252)
		(layer "B.Cu")
		(net "SAS2X28_A_HDD9_FLT")
	)
	(segment
		(start 24.4348 -393.7254)
		(end 24.2951 -393.5857)
		(width 0.111252)
		(layer "B.Cu")
		(net "SAS2X28_A_HDD9_FLT")
	)
	(segment
		(start 38.608 -388.747)
		(end 40.767 -390.906)
		(width 0.14605)
		(layer "In2.Cu")
		(net "SAS2X28_A_HDD9_FLT")
	)
	(segment
		(start 24.4348 -393.7254)
		(end 24.3586 -393.6492)
		(width 0.14605)
		(layer "In2.Cu")
		(net "SAS2X28_A_HDD9_FLT")
	)
	(segment
		(start 87.287608 -384.657092)
		(end 99.313746 -384.657092)
		(width 0.14605)
		(layer "In2.Cu")
		(net "SAS2X28_A_HDD9_FLT")
	)
	(segment
		(start 24.3586 -393.6492)
		(end 24.3586 -389.2804)
		(width 0.14605)
		(layer "In2.Cu")
		(net "SAS2X28_A_HDD9_FLT")
	)
	(segment
		(start 81.0387 -390.906)
		(end 87.287608 -384.657092)
		(width 0.14605)
		(layer "In2.Cu")
		(net "SAS2X28_A_HDD9_FLT")
	)
	(segment
		(start 40.767 -390.906)
		(end 81.0387 -390.906)
		(width 0.14605)
		(layer "In2.Cu")
		(net "SAS2X28_A_HDD9_FLT")
	)
	(segment
		(start 24.892 -388.747)
		(end 38.608 -388.747)
		(width 0.14605)
		(layer "In2.Cu")
		(net "SAS2X28_A_HDD9_FLT")
	)
	(segment
		(start 24.3586 -389.2804)
		(end 24.892 -388.747)
		(width 0.14605)
		(layer "In2.Cu")
		(net "SAS2X28_A_HDD9_FLT")
	)
	(segment
		(start 71.954898 -85.537548)
		(end 71.500746 -85.9917)
		(width 0.14605)
		(layer "In5.Cu")
		(net "SAS2X28_A_HDD9_FLT")
	)
	(segment
		(start 99.313746 -160.561274)
		(end 99.310444 -160.557972)
		(width 0.14605)
		(layer "In5.Cu")
		(net "SAS2X28_A_HDD9_FLT")
	)
	(segment
		(start 99.313746 -384.657092)
		(end 99.313746 -160.561274)
		(width 0.14605)
		(layer "In5.Cu")
		(net "SAS2X28_A_HDD9_FLT")
	)
	(segment
		(start 78.456536 -85.537548)
		(end 71.954898 -85.537548)
		(width 0.14605)
		(layer "In5.Cu")
		(net "SAS2X28_A_HDD9_FLT")
	)
	(segment
		(start 99.310444 -106.391456)
		(end 78.456536 -85.537548)
		(width 0.14605)
		(layer "In5.Cu")
		(net "SAS2X28_A_HDD9_FLT")
	)
	(segment
		(start 99.310444 -160.557972)
		(end 99.310444 -106.391456)
		(width 0.14605)
		(layer "In5.Cu")
		(net "SAS2X28_A_HDD9_FLT")
	)
	(segment
		(start 42.274744 -136.254744)
		(end 42.274744 -135.455406)
		(width 0.111252)
		(layer "F.Cu")
		(net "I2C_B_TMP2_A1")
	)
	(segment
		(start 43.04665 -137.02665)
		(end 42.274744 -136.254744)
		(width 0.111252)
		(layer "F.Cu")
		(net "I2C_B_TMP2_A1")
	)
	(segment
		(start 44.811696 -137.02665)
		(end 43.04665 -137.02665)
		(width 0.111252)
		(layer "F.Cu")
		(net "I2C_B_TMP2_A1")
	)
	(segment
		(start 42.274744 -135.454898)
		(end 42.274998 -135.455152)
		(width 0.111252)
		(layer "F.Cu")
		(net "I2C_B_TMP2_A1")
	)
	(segment
		(start 42.274744 -134.449058)
		(end 42.274744 -135.454898)
		(width 0.111252)
		(layer "F.Cu")
		(net "I2C_B_TMP2_A1")
	)
	(segment
		(start 42.468546 -132.2324)
		(end 42.468546 -133.2484)
		(width 0.111252)
		(layer "F.Cu")
		(net "I2C_B_TMP2_A1")
	)
	(segment
		(start 45.592746 -137.8077)
		(end 44.811696 -137.02665)
		(width 0.111252)
		(layer "F.Cu")
		(net "I2C_B_TMP2_A1")
	)
	(segment
		(start 42.177462 -133.539484)
		(end 42.177462 -134.351776)
		(width 0.111252)
		(layer "F.Cu")
		(net "I2C_B_TMP2_A1")
	)
	(segment
		(start 42.405046 -133.3119)
		(end 42.177462 -133.539484)
		(width 0.111252)
		(layer "F.Cu")
		(net "I2C_B_TMP2_A1")
	)
	(segment
		(start 42.468546 -133.2484)
		(end 42.405046 -133.3119)
		(width 0.111252)
		(layer "F.Cu")
		(net "I2C_B_TMP2_A1")
	)
	(segment
		(start 42.177462 -134.351776)
		(end 42.274744 -134.449058)
		(width 0.111252)
		(layer "F.Cu")
		(net "I2C_B_TMP2_A1")
	)
	(segment
		(start 42.274744 -135.455406)
		(end 42.274998 -135.455152)
		(width 0.111252)
		(layer "F.Cu")
		(net "I2C_B_TMP2_A1")
	)
	(via
		(at 45.592746 -137.8077)
		(size 0.7112)
		(drill 0.3556)
		(layers "F.Cu" "B.Cu")
		(net "I2C_B_TMP2_A1")
	)
	(segment
		(start 72.389746 -85.8647)
		(end 72.150986 -85.62594)
		(width 0.111252)
		(layer "F.Cu")
		(net "SAS2X28_B_HDD9_FLT")
	)
	(segment
		(start 72.150986 -85.62594)
		(end 72.150986 -84.7852)
		(width 0.111252)
		(layer "F.Cu")
		(net "SAS2X28_B_HDD9_FLT")
	)
	(segment
		(start 72.389746 -86.0171)
		(end 72.389746 -85.8647)
		(width 0.111252)
		(layer "F.Cu")
		(net "SAS2X28_B_HDD9_FLT")
	)
	(segment
		(start 72.389746 -86.8172)
		(end 72.389746 -86.0171)
		(width 0.111252)
		(layer "F.Cu")
		(net "SAS2X28_B_HDD9_FLT")
	)
	(via
		(at 72.389746 -87.0585)
		(size 0.7112)
		(drill 0.3556)
		(layers "F.Cu" "B.Cu")
		(net "SAS2X28_B_HDD9_FLT")
	)
	(via
		(at 6.654546 -138.982704)
		(size 0.5588)
		(drill 0.3048)
		(layers "F.Cu" "B.Cu")
		(net "SAS2X28_B_HDD9_FLT")
	)
	(via
		(at 72.389746 -86.0171)
		(size 0.5588)
		(drill 0.3048)
		(layers "F.Cu" "B.Cu")
		(net "SAS2X28_B_HDD9_FLT")
	)
	(segment
		(start 5.67309 -139.500356)
		(end 2.81305 -139.500356)
		(width 0.111252)
		(layer "B.Cu")
		(net "SAS2X28_B_HDD9_FLT")
	)
	(segment
		(start 6.654546 -138.982704)
		(end 6.609842 -138.938)
		(width 0.111252)
		(layer "B.Cu")
		(net "SAS2X28_B_HDD9_FLT")
	)
	(segment
		(start 2.81305 -139.500356)
		(end 2.811526 -139.498832)
		(width 0.111252)
		(layer "B.Cu")
		(net "SAS2X28_B_HDD9_FLT")
	)
	(segment
		(start 72.389746 -86.0171)
		(end 72.389746 -87.0585)
		(width 0.111252)
		(layer "B.Cu")
		(net "SAS2X28_B_HDD9_FLT")
	)
	(segment
		(start 6.235446 -138.938)
		(end 5.67309 -139.500356)
		(width 0.111252)
		(layer "B.Cu")
		(net "SAS2X28_B_HDD9_FLT")
	)
	(segment
		(start 6.609842 -138.938)
		(end 6.235446 -138.938)
		(width 0.111252)
		(layer "B.Cu")
		(net "SAS2X28_B_HDD9_FLT")
	)
	(segment
		(start 6.654546 -138.982704)
		(end 6.654546 -137.48258)
		(width 0.14605)
		(layer "In5.Cu")
		(net "SAS2X28_B_HDD9_FLT")
	)
	(segment
		(start 7.531354 -135.757412)
		(end 7.531354 -133.332474)
		(width 0.14605)
		(layer "In5.Cu")
		(net "SAS2X28_B_HDD9_FLT")
	)
	(segment
		(start 8.423402 -108.121958)
		(end 20.31746 -96.2279)
		(width 0.14605)
		(layer "In5.Cu")
		(net "SAS2X28_B_HDD9_FLT")
	)
	(segment
		(start 20.31746 -96.2279)
		(end 62.178946 -96.2279)
		(width 0.14605)
		(layer "In5.Cu")
		(net "SAS2X28_B_HDD9_FLT")
	)
	(segment
		(start 62.178946 -96.2279)
		(end 72.389746 -86.0171)
		(width 0.14605)
		(layer "In5.Cu")
		(net "SAS2X28_B_HDD9_FLT")
	)
	(segment
		(start 7.59841 -130.82651)
		(end 8.423402 -130.001518)
		(width 0.14605)
		(layer "In5.Cu")
		(net "SAS2X28_B_HDD9_FLT")
	)
	(segment
		(start 8.423402 -130.001518)
		(end 8.423402 -108.121958)
		(width 0.14605)
		(layer "In5.Cu")
		(net "SAS2X28_B_HDD9_FLT")
	)
	(segment
		(start 7.59841 -132.73786)
		(end 7.59841 -130.82651)
		(width 0.14605)
		(layer "In5.Cu")
		(net "SAS2X28_B_HDD9_FLT")
	)
	(segment
		(start 6.428994 -137.257028)
		(end 6.428994 -136.859772)
		(width 0.14605)
		(layer "In5.Cu")
		(net "SAS2X28_B_HDD9_FLT")
	)
	(segment
		(start 6.428994 -136.859772)
		(end 7.531354 -135.757412)
		(width 0.14605)
		(layer "In5.Cu")
		(net "SAS2X28_B_HDD9_FLT")
	)
	(segment
		(start 7.531354 -133.332474)
		(end 7.547356 -133.316218)
		(width 0.14605)
		(layer "In5.Cu")
		(net "SAS2X28_B_HDD9_FLT")
	)
	(segment
		(start 7.547356 -133.316218)
		(end 7.59841 -132.73786)
		(width 0.14605)
		(layer "In5.Cu")
		(net "SAS2X28_B_HDD9_FLT")
	)
	(segment
		(start 6.654546 -137.48258)
		(end 6.428994 -137.257028)
		(width 0.14605)
		(layer "In5.Cu")
		(net "SAS2X28_B_HDD9_FLT")
	)
	(segment
		(start 44.310046 -132.2959)
		(end 44.310046 -133.3119)
		(width 0.111252)
		(layer "F.Cu")
		(net "I2C_B_TMP2_A0")
	)
	(segment
		(start 44.246546 -132.2324)
		(end 44.310046 -132.2959)
		(width 0.111252)
		(layer "F.Cu")
		(net "I2C_B_TMP2_A0")
	)
	(segment
		(start 44.310046 -133.3119)
		(end 44.310046 -133.4516)
		(width 0.111252)
		(layer "F.Cu")
		(net "I2C_B_TMP2_A0")
	)
	(segment
		(start 43.2435 -136.5377)
		(end 45.211746 -136.5377)
		(width 0.111252)
		(layer "F.Cu")
		(net "I2C_B_TMP2_A0")
	)
	(segment
		(start 44.310046 -133.4516)
		(end 42.925238 -134.836408)
		(width 0.111252)
		(layer "F.Cu")
		(net "I2C_B_TMP2_A0")
	)
	(segment
		(start 45.466 -136.283446)
		(end 45.466 -136.017)
		(width 0.111252)
		(layer "F.Cu")
		(net "I2C_B_TMP2_A0")
	)
	(segment
		(start 45.211746 -136.5377)
		(end 45.466 -136.283446)
		(width 0.111252)
		(layer "F.Cu")
		(net "I2C_B_TMP2_A0")
	)
	(segment
		(start 42.925238 -134.836408)
		(end 42.925238 -135.455152)
		(width 0.111252)
		(layer "F.Cu")
		(net "I2C_B_TMP2_A0")
	)
	(segment
		(start 42.925238 -136.219438)
		(end 43.2435 -136.5377)
		(width 0.111252)
		(layer "F.Cu")
		(net "I2C_B_TMP2_A0")
	)
	(segment
		(start 42.925238 -135.455152)
		(end 42.925238 -136.219438)
		(width 0.111252)
		(layer "F.Cu")
		(net "I2C_B_TMP2_A0")
	)
	(via
		(at 45.466 -136.017)
		(size 0.7112)
		(drill 0.3556)
		(layers "F.Cu" "B.Cu")
		(net "I2C_B_TMP2_A0")
	)
	(via
		(at 203.04379 -193.404744)
		(size 0.7112)
		(drill 0.4064)
		(layers "F.Cu" "B.Cu")
		(net "P12V_HDD3")
	)
	(via
		(at 203.04379 -192.388744)
		(size 0.7112)
		(drill 0.3556)
		(layers "F.Cu" "B.Cu")
		(net "P12V_HDD3")
	)
	(via
		(at 219.1258 -186.7662)
		(size 0.7112)
		(drill 0.3556)
		(layers "F.Cu" "B.Cu")
		(net "P12V_HDD3")
	)
	(segment
		(start 203.04379 -192.388744)
		(end 203.04379 -193.404744)
		(width 0.508)
		(layer "B.Cu")
		(net "P12V_HDD3")
	)
	(segment
		(start 26.415746 -374.9167)
		(end 26.415746 -373.9007)
		(width 0.111252)
		(layer "F.Cu")
		(net "I2C_B_TMP1_A2")
	)
	(segment
		(start 25.830022 -374.256554)
		(end 24.916638 -374.256554)
		(width 0.111252)
		(layer "F.Cu")
		(net "I2C_B_TMP1_A2")
	)
	(segment
		(start 24.916638 -374.256554)
		(end 24.434546 -374.7389)
		(width 0.111252)
		(layer "F.Cu")
		(net "I2C_B_TMP1_A2")
	)
	(segment
		(start 27.52471 -377.185174)
		(end 27.524456 -377.18492)
		(width 0.111252)
		(layer "F.Cu")
		(net "I2C_B_TMP1_A2")
	)
	(segment
		(start 24.434546 -374.7389)
		(end 24.358346 -374.7389)
		(width 0.111252)
		(layer "F.Cu")
		(net "I2C_B_TMP1_A2")
	)
	(segment
		(start 26.185876 -373.9007)
		(end 25.830022 -374.256554)
		(width 0.111252)
		(layer "F.Cu")
		(net "I2C_B_TMP1_A2")
	)
	(segment
		(start 26.415746 -373.9007)
		(end 26.185876 -373.9007)
		(width 0.111252)
		(layer "F.Cu")
		(net "I2C_B_TMP1_A2")
	)
	(segment
		(start 27.524456 -377.18492)
		(end 27.524456 -376.02541)
		(width 0.111252)
		(layer "F.Cu")
		(net "I2C_B_TMP1_A2")
	)
	(segment
		(start 27.524456 -376.02541)
		(end 26.415746 -374.9167)
		(width 0.111252)
		(layer "F.Cu")
		(net "I2C_B_TMP1_A2")
	)
	(via
		(at 24.358346 -374.7389)
		(size 0.7112)
		(drill 0.3556)
		(layers "F.Cu" "B.Cu")
		(net "I2C_B_TMP1_A2")
	)
	(via
		(at 217.296746 -177.9397)
		(size 0.7112)
		(drill 0.3556)
		(layers "F.Cu" "B.Cu")
		(net "P5V_HDD3")
	)
	(via
		(at 207.01 -174.625)
		(size 0.7112)
		(drill 0.3556)
		(layers "F.Cu" "B.Cu")
		(net "P5V_HDD3")
	)
	(segment
		(start 7.86384 -215.224614)
		(end 7.619238 -215.224614)
		(width 0.111252)
		(layer "F.Cu")
		(net "SAS_EXP_B_PWR12")
	)
	(segment
		(start 42.290746 -206.8957)
		(end 42.036746 -207.1497)
		(width 0.111252)
		(layer "F.Cu")
		(net "SAS_EXP_B_PWR12")
	)
	(segment
		(start 27.050746 -211.9757)
		(end 25.641046 -210.566)
		(width 0.111252)
		(layer "F.Cu")
		(net "SAS_EXP_B_PWR12")
	)
	(segment
		(start 25.641046 -210.566)
		(end 20.137882 -210.566)
		(width 0.111252)
		(layer "F.Cu")
		(net "SAS_EXP_B_PWR12")
	)
	(segment
		(start 7.480046 -215.085422)
		(end 7.052056 -215.085422)
		(width 0.111252)
		(layer "F.Cu")
		(net "SAS_EXP_B_PWR12")
	)
	(segment
		(start 7.878826 -215.2396)
		(end 7.86384 -215.224614)
		(width 0.111252)
		(layer "F.Cu")
		(net "SAS_EXP_B_PWR12")
	)
	(segment
		(start 19.410934 -211.292948)
		(end 18.57248 -212.131148)
		(width 0.111252)
		(layer "F.Cu")
		(net "SAS_EXP_B_PWR12")
	)
	(segment
		(start 42.290746 -206.340202)
		(end 42.290746 -206.8957)
		(width 0.111252)
		(layer "F.Cu")
		(net "SAS_EXP_B_PWR12")
	)
	(segment
		(start 28.066746 -211.9757)
		(end 27.050746 -211.9757)
		(width 0.111252)
		(layer "F.Cu")
		(net "SAS_EXP_B_PWR12")
	)
	(segment
		(start 6.471412 -214.504778)
		(end 3.19024 -214.504778)
		(width 0.111252)
		(layer "F.Cu")
		(net "SAS_EXP_B_PWR12")
	)
	(segment
		(start 16.493236 -212.131148)
		(end 13.384784 -215.2396)
		(width 0.111252)
		(layer "F.Cu")
		(net "SAS_EXP_B_PWR12")
	)
	(segment
		(start 7.052056 -215.085422)
		(end 6.471412 -214.504778)
		(width 0.111252)
		(layer "F.Cu")
		(net "SAS_EXP_B_PWR12")
	)
	(segment
		(start 7.619238 -215.224614)
		(end 7.480046 -215.085422)
		(width 0.111252)
		(layer "F.Cu")
		(net "SAS_EXP_B_PWR12")
	)
	(segment
		(start 18.57248 -212.131148)
		(end 16.493236 -212.131148)
		(width 0.111252)
		(layer "F.Cu")
		(net "SAS_EXP_B_PWR12")
	)
	(segment
		(start 42.036746 -207.1497)
		(end 42.529506 -207.64246)
		(width 0.111252)
		(layer "F.Cu")
		(net "SAS_EXP_B_PWR12")
	)
	(segment
		(start 42.529506 -207.64246)
		(end 42.529506 -208.372202)
		(width 0.111252)
		(layer "F.Cu")
		(net "SAS_EXP_B_PWR12")
	)
	(segment
		(start 13.384784 -215.2396)
		(end 7.878826 -215.2396)
		(width 0.111252)
		(layer "F.Cu")
		(net "SAS_EXP_B_PWR12")
	)
	(segment
		(start 20.137882 -210.566)
		(end 19.410934 -211.292948)
		(width 0.111252)
		(layer "F.Cu")
		(net "SAS_EXP_B_PWR12")
	)
	(via
		(at 27.050746 -211.9757)
		(size 0.7112)
		(drill 0.3556)
		(layers "F.Cu" "B.Cu")
		(net "SAS_EXP_B_PWR12")
	)
	(via
		(at 42.036746 -207.1497)
		(size 0.5588)
		(drill 0.3048)
		(layers "F.Cu" "B.Cu")
		(net "SAS_EXP_B_PWR12")
	)
	(via
		(at 28.066746 -211.9757)
		(size 0.5588)
		(drill 0.3048)
		(layers "F.Cu" "B.Cu")
		(net "SAS_EXP_B_PWR12")
	)
	(segment
		(start 37.210746 -211.9757)
		(end 28.066746 -211.9757)
		(width 0.14605)
		(layer "In5.Cu")
		(net "SAS_EXP_B_PWR12")
	)
	(segment
		(start 42.036746 -207.1497)
		(end 37.210746 -211.9757)
		(width 0.14605)
		(layer "In5.Cu")
		(net "SAS_EXP_B_PWR12")
	)
	(segment
		(start 28.320746 -374.9167)
		(end 28.174696 -375.06275)
		(width 0.111252)
		(layer "F.Cu")
		(net "I2C_B_TMP1_A1")
	)
	(segment
		(start 25.653746 -378.3457)
		(end 24.891746 -377.5837)
		(width 0.111252)
		(layer "F.Cu")
		(net "I2C_B_TMP1_A1")
	)
	(segment
		(start 28.174696 -375.06275)
		(end 28.174696 -377.18492)
		(width 0.111252)
		(layer "F.Cu")
		(net "I2C_B_TMP1_A1")
	)
	(segment
		(start 28.174696 -377.18492)
		(end 28.17495 -377.185174)
		(width 0.111252)
		(layer "F.Cu")
		(net "I2C_B_TMP1_A1")
	)
	(segment
		(start 28.320746 -373.9007)
		(end 28.320746 -374.9167)
		(width 0.111252)
		(layer "F.Cu")
		(net "I2C_B_TMP1_A1")
	)
	(segment
		(start 28.174696 -378.23775)
		(end 28.066746 -378.3457)
		(width 0.111252)
		(layer "F.Cu")
		(net "I2C_B_TMP1_A1")
	)
	(segment
		(start 28.17495 -377.185174)
		(end 28.174696 -377.185428)
		(width 0.111252)
		(layer "F.Cu")
		(net "I2C_B_TMP1_A1")
	)
	(segment
		(start 28.174696 -377.185428)
		(end 28.174696 -378.23775)
		(width 0.111252)
		(layer "F.Cu")
		(net "I2C_B_TMP1_A1")
	)
	(segment
		(start 28.066746 -378.3457)
		(end 25.653746 -378.3457)
		(width 0.111252)
		(layer "F.Cu")
		(net "I2C_B_TMP1_A1")
	)
	(via
		(at 24.891746 -377.5837)
		(size 0.7112)
		(drill 0.3556)
		(layers "F.Cu" "B.Cu")
		(net "I2C_B_TMP1_A1")
	)
	(segment
		(start 12.805664 -364.5535)
		(end 12.80541 -364.553246)
		(width 0.09525)
		(layer "F.Cu")
		(net "SAS2X28_A_HDD8_TX_+")
	)
	(segment
		(start 4.878832 -369.500404)
		(end 4.877308 -369.49888)
		(width 0.09525)
		(layer "F.Cu")
		(net "SAS2X28_A_HDD8_TX_+")
	)
	(segment
		(start 36.82746 -156.168344)
		(end 36.82746 -156.435044)
		(width 0.09525)
		(layer "F.Cu")
		(net "SAS2X28_A_HDD8_TX_+")
	)
	(segment
		(start 31.68142 -158.195518)
		(end 31.057342 -158.819596)
		(width 0.09525)
		(layer "F.Cu")
		(net "SAS2X28_A_HDD8_TX_+")
	)
	(segment
		(start 38.250114 -156.070046)
		(end 38.245034 -156.064966)
		(width 0.09525)
		(layer "F.Cu")
		(net "SAS2X28_A_HDD8_TX_+")
	)
	(segment
		(start 36.72586 -156.536644)
		(end 35.687254 -156.536644)
		(width 0.09525)
		(layer "F.Cu")
		(net "SAS2X28_A_HDD8_TX_+")
	)
	(segment
		(start 14.300454 -357.543354)
		(end 13.3223 -358.521508)
		(width 0.09525)
		(layer "F.Cu")
		(net "SAS2X28_A_HDD8_TX_+")
	)
	(segment
		(start 12.805664 -359.769156)
		(end 12.805664 -364.5535)
		(width 0.09525)
		(layer "F.Cu")
		(net "SAS2X28_A_HDD8_TX_+")
	)
	(segment
		(start 29.272992 -160.6042)
		(end 29.273246 -160.604454)
		(width 0.09525)
		(layer "F.Cu")
		(net "SAS2X28_A_HDD8_TX_+")
	)
	(segment
		(start 29.425138 -183.829452)
		(end 35.225482 -189.629796)
		(width 0.09525)
		(layer "F.Cu")
		(net "SAS2X28_A_HDD8_TX_+")
	)
	(segment
		(start 28.879546 -161.554414)
		(end 28.879546 -182.511954)
		(width 0.09525)
		(layer "F.Cu")
		(net "SAS2X28_A_HDD8_TX_+")
	)
	(segment
		(start 7.492746 -369.836446)
		(end 5.690108 -369.836446)
		(width 0.09525)
		(layer "F.Cu")
		(net "SAS2X28_A_HDD8_TX_+")
	)
	(segment
		(start 14.300454 -357.5431)
		(end 14.300454 -357.543354)
		(width 0.09525)
		(layer "F.Cu")
		(net "SAS2X28_A_HDD8_TX_+")
	)
	(segment
		(start 31.057342 -158.819596)
		(end 29.272992 -160.6042)
		(width 0.09525)
		(layer "F.Cu")
		(net "SAS2X28_A_HDD8_TX_+")
	)
	(segment
		(start 36.966144 -156.064966)
		(end 36.92906 -156.066744)
		(width 0.09525)
		(layer "F.Cu")
		(net "SAS2X28_A_HDD8_TX_+")
	)
	(segment
		(start 14.743938 -277.126446)
		(end 14.743938 -356.472744)
		(width 0.09525)
		(layer "F.Cu")
		(net "SAS2X28_A_HDD8_TX_+")
	)
	(segment
		(start 12.467336 -365.37011)
		(end 12.382246 -365.454946)
		(width 0.09525)
		(layer "F.Cu")
		(net "SAS2X28_A_HDD8_TX_+")
	)
	(segment
		(start 16.763492 -274.3327)
		(end 15.291308 -275.805392)
		(width 0.09525)
		(layer "F.Cu")
		(net "SAS2X28_A_HDD8_TX_+")
	)
	(segment
		(start 12.382246 -365.454946)
		(end 8.381492 -369.4557)
		(width 0.09525)
		(layer "F.Cu")
		(net "SAS2X28_A_HDD8_TX_+")
	)
	(segment
		(start 4.877308 -369.49888)
		(end 3.192526 -369.49888)
		(width 0.09525)
		(layer "F.Cu")
		(net "SAS2X28_A_HDD8_TX_+")
	)
	(segment
		(start 8.360664 -369.47729)
		(end 8.36041 -369.477036)
		(width 0.09525)
		(layer "F.Cu")
		(net "SAS2X28_A_HDD8_TX_+")
	)
	(segment
		(start 5.486908 -369.799616)
		(end 5.485638 -369.799108)
		(width 0.09525)
		(layer "F.Cu")
		(net "SAS2X28_A_HDD8_TX_+")
	)
	(segment
		(start 38.245034 -156.064966)
		(end 36.966144 -156.064966)
		(width 0.09525)
		(layer "F.Cu")
		(net "SAS2X28_A_HDD8_TX_+")
	)
	(segment
		(start 35.534346 -190.374778)
		(end 35.534346 -254.6477)
		(width 0.09525)
		(layer "F.Cu")
		(net "SAS2X28_A_HDD8_TX_+")
	)
	(segment
		(start 12.467336 -365.370364)
		(end 12.467336 -365.37011)
		(width 0.09525)
		(layer "F.Cu")
		(net "SAS2X28_A_HDD8_TX_+")
	)
	(segment
		(start 34.887916 -256.208276)
		(end 16.763492 -274.3327)
		(width 0.09525)
		(layer "F.Cu")
		(net "SAS2X28_A_HDD8_TX_+")
	)
	(segment
		(start 13.3223 -358.521508)
		(end 13.322554 -358.521762)
		(width 0.09525)
		(layer "F.Cu")
		(net "SAS2X28_A_HDD8_TX_+")
	)
	(arc
		(start 5.690108 -369.836446)
		(mid 5.58686 -369.827122)
		(end 5.486908 -369.799616)
		(width 0.09525)
		(layer "F.Cu")
		(net "SAS2X28_A_HDD8_TX_+")
	)
	(arc
		(start 13.322554 -358.521762)
		(mid 12.94012 -359.09407)
		(end 12.805664 -359.769156)
		(width 0.09525)
		(layer "F.Cu")
		(net "SAS2X28_A_HDD8_TX_+")
	)
	(arc
		(start 8.36041 -369.477036)
		(mid 7.962322 -369.74303)
		(end 7.492746 -369.836446)
		(width 0.09525)
		(layer "F.Cu")
		(net "SAS2X28_A_HDD8_TX_+")
	)
	(arc
		(start 8.381492 -369.4557)
		(mid 8.371144 -369.466558)
		(end 8.360664 -369.47729)
		(width 0.09525)
		(layer "F.Cu")
		(net "SAS2X28_A_HDD8_TX_+")
	)
	(arc
		(start 36.754054 -156.53258)
		(mid 36.7401 -156.535605)
		(end 36.72586 -156.536644)
		(width 0.09525)
		(layer "F.Cu")
		(net "SAS2X28_A_HDD8_TX_+")
	)
	(arc
		(start 35.225482 -189.629796)
		(mid 35.454003 -189.971567)
		(end 35.534346 -190.374778)
		(width 0.09525)
		(layer "F.Cu")
		(net "SAS2X28_A_HDD8_TX_+")
	)
	(arc
		(start 36.82746 -156.435044)
		(mid 36.807067 -156.496102)
		(end 36.754054 -156.53258)
		(width 0.09525)
		(layer "F.Cu")
		(net "SAS2X28_A_HDD8_TX_+")
	)
	(arc
		(start 15.291308 -275.805392)
		(mid 14.886239 -276.411482)
		(end 14.743938 -277.126446)
		(width 0.09525)
		(layer "F.Cu")
		(net "SAS2X28_A_HDD8_TX_+")
	)
	(arc
		(start 36.92906 -156.066744)
		(mid 36.857218 -156.096502)
		(end 36.82746 -156.168344)
		(width 0.09525)
		(layer "F.Cu")
		(net "SAS2X28_A_HDD8_TX_+")
	)
	(arc
		(start 35.687254 -156.536644)
		(mid 33.519357 -156.967678)
		(end 31.68142 -158.195518)
		(width 0.09525)
		(layer "F.Cu")
		(net "SAS2X28_A_HDD8_TX_+")
	)
	(arc
		(start 35.534346 -254.6477)
		(mid 35.366348 -255.492285)
		(end 34.887916 -256.208276)
		(width 0.09525)
		(layer "F.Cu")
		(net "SAS2X28_A_HDD8_TX_+")
	)
	(arc
		(start 5.278628 -369.666012)
		(mid 5.0952 -369.543449)
		(end 4.878832 -369.500404)
		(width 0.09525)
		(layer "F.Cu")
		(net "SAS2X28_A_HDD8_TX_+")
	)
	(arc
		(start 29.273246 -160.604454)
		(mid 28.981911 -161.040284)
		(end 28.879546 -161.554414)
		(width 0.09525)
		(layer "F.Cu")
		(net "SAS2X28_A_HDD8_TX_+")
	)
	(arc
		(start 12.80541 -364.553246)
		(mid 12.717657 -364.99544)
		(end 12.467336 -365.370364)
		(width 0.09525)
		(layer "F.Cu")
		(net "SAS2X28_A_HDD8_TX_+")
	)
	(arc
		(start 28.879546 -182.511954)
		(mid 29.021335 -183.224956)
		(end 29.425138 -183.829452)
		(width 0.09525)
		(layer "F.Cu")
		(net "SAS2X28_A_HDD8_TX_+")
	)
	(arc
		(start 14.743938 -356.472744)
		(mid 14.628636 -357.052026)
		(end 14.300454 -357.5431)
		(width 0.09525)
		(layer "F.Cu")
		(net "SAS2X28_A_HDD8_TX_+")
	)
	(arc
		(start 5.485638 -369.799108)
		(mid 5.374983 -369.743678)
		(end 5.278628 -369.666012)
		(width 0.09525)
		(layer "F.Cu")
		(net "SAS2X28_A_HDD8_TX_+")
	)
	(segment
		(start 29.336746 -374.9167)
		(end 29.336746 -373.9134)
		(width 0.111252)
		(layer "F.Cu")
		(net "I2C_B_TMP1_A0")
	)
	(segment
		(start 29.362146 -373.888)
		(end 30.238446 -373.888)
		(width 0.111252)
		(layer "F.Cu")
		(net "I2C_B_TMP1_A0")
	)
	(segment
		(start 29.336746 -373.9134)
		(end 29.362146 -373.888)
		(width 0.111252)
		(layer "F.Cu")
		(net "I2C_B_TMP1_A0")
	)
	(segment
		(start 28.82519 -377.185174)
		(end 28.824936 -377.18492)
		(width 0.111252)
		(layer "F.Cu")
		(net "I2C_B_TMP1_A0")
	)
	(segment
		(start 30.238446 -373.888)
		(end 30.606746 -373.5197)
		(width 0.111252)
		(layer "F.Cu")
		(net "I2C_B_TMP1_A0")
	)
	(segment
		(start 28.824936 -375.42851)
		(end 29.336746 -374.9167)
		(width 0.111252)
		(layer "F.Cu")
		(net "I2C_B_TMP1_A0")
	)
	(segment
		(start 28.824936 -377.18492)
		(end 28.824936 -375.42851)
		(width 0.111252)
		(layer "F.Cu")
		(net "I2C_B_TMP1_A0")
	)
	(via
		(at 30.606746 -373.5197)
		(size 0.7112)
		(drill 0.3556)
		(layers "F.Cu" "B.Cu")
		(net "I2C_B_TMP1_A0")
	)
	(via
		(at 62.738 -195.199)
		(size 0.7112)
		(drill 0.3556)
		(layers "F.Cu" "B.Cu")
		(net "P12V_HDD8")
	)
	(via
		(at 62.1538 -188.7474)
		(size 0.7112)
		(drill 0.3556)
		(layers "F.Cu" "B.Cu")
		(net "P12V_HDD8")
	)
	(segment
		(start 14.075664 -360.131106)
		(end 14.075664 -364.131606)
		(width 0.09525)
		(layer "F.Cu")
		(net "SAS2X28_A_HDD8_RX_+")
	)
	(segment
		(start 15.620492 -358.152446)
		(end 15.620746 -358.1527)
		(width 0.09525)
		(layer "F.Cu")
		(net "SAS2X28_A_HDD8_RX_+")
	)
	(segment
		(start 14.075664 -364.40745)
		(end 14.075664 -365.19866)
		(width 0.09525)
		(layer "F.Cu")
		(net "SAS2X28_A_HDD8_RX_+")
	)
	(segment
		(start 36.804346 -190.764414)
		(end 36.804346 -255.175512)
		(width 0.09525)
		(layer "F.Cu")
		(net "SAS2X28_A_HDD8_RX_+")
	)
	(segment
		(start 30.831536 -160.89249)
		(end 30.387036 -161.33699)
		(width 0.09525)
		(layer "F.Cu")
		(net "SAS2X28_A_HDD8_RX_+")
	)
	(segment
		(start 36.8046 -190.76416)
		(end 36.804346 -190.764414)
		(width 0.09525)
		(layer "F.Cu")
		(net "SAS2X28_A_HDD8_RX_+")
	)
	(segment
		(start 15.620746 -358.1527)
		(end 15.620492 -358.152954)
		(width 0.09525)
		(layer "F.Cu")
		(net "SAS2X28_A_HDD8_RX_+")
	)
	(segment
		(start 16.014192 -277.507446)
		(end 16.013938 -277.507192)
		(width 0.09525)
		(layer "F.Cu")
		(net "SAS2X28_A_HDD8_RX_+")
	)
	(segment
		(start 33.448752 -160.92551)
		(end 33.443926 -160.920684)
		(width 0.09525)
		(layer "F.Cu")
		(net "SAS2X28_A_HDD8_RX_+")
	)
	(segment
		(start 32.130746 -184.6707)
		(end 36.351464 -188.891418)
		(width 0.09525)
		(layer "F.Cu")
		(net "SAS2X28_A_HDD8_RX_+")
	)
	(segment
		(start 36.110926 -256.84988)
		(end 17.251426 -275.70938)
		(width 0.09525)
		(layer "F.Cu")
		(net "SAS2X28_A_HDD8_RX_+")
	)
	(segment
		(start 14.076934 -364.132876)
		(end 14.076934 -364.40618)
		(width 0.09525)
		(layer "F.Cu")
		(net "SAS2X28_A_HDD8_RX_+")
	)
	(segment
		(start 13.792708 -365.882174)
		(end 8.856218 -370.81841)
		(width 0.09525)
		(layer "F.Cu")
		(net "SAS2X28_A_HDD8_RX_+")
	)
	(segment
		(start 30.544516 -183.084724)
		(end 32.130746 -184.6707)
		(width 0.09525)
		(layer "F.Cu")
		(net "SAS2X28_A_HDD8_RX_+")
	)
	(segment
		(start 13.792454 -365.88192)
		(end 13.792708 -365.882174)
		(width 0.09525)
		(layer "F.Cu")
		(net "SAS2X28_A_HDD8_RX_+")
	)
	(segment
		(start 36.8046 -189.985396)
		(end 36.8046 -190.76416)
		(width 0.09525)
		(layer "F.Cu")
		(net "SAS2X28_A_HDD8_RX_+")
	)
	(segment
		(start 32.765746 -160.63976)
		(end 31.441644 -160.63976)
		(width 0.09525)
		(layer "F.Cu")
		(net "SAS2X28_A_HDD8_RX_+")
	)
	(segment
		(start 30.149546 -161.910268)
		(end 30.149546 -182.1307)
		(width 0.09525)
		(layer "F.Cu")
		(net "SAS2X28_A_HDD8_RX_+")
	)
	(segment
		(start 8.61441 -371.231414)
		(end 8.61441 -371.520974)
		(width 0.09525)
		(layer "F.Cu")
		(net "SAS2X28_A_HDD8_RX_+")
	)
	(segment
		(start 36.110672 -256.849626)
		(end 36.110926 -256.84988)
		(width 0.09525)
		(layer "F.Cu")
		(net "SAS2X28_A_HDD8_RX_+")
	)
	(segment
		(start 14.076934 -364.40618)
		(end 14.075664 -364.40745)
		(width 0.09525)
		(layer "F.Cu")
		(net "SAS2X28_A_HDD8_RX_+")
	)
	(segment
		(start 8.856218 -370.81841)
		(end 8.735314 -370.939568)
		(width 0.09525)
		(layer "F.Cu")
		(net "SAS2X28_A_HDD8_RX_+")
	)
	(segment
		(start 17.251426 -275.70938)
		(end 16.410686 -276.549866)
		(width 0.09525)
		(layer "F.Cu")
		(net "SAS2X28_A_HDD8_RX_+")
	)
	(segment
		(start 15.620492 -358.152954)
		(end 14.381734 -359.39222)
		(width 0.09525)
		(layer "F.Cu")
		(net "SAS2X28_A_HDD8_RX_+")
	)
	(segment
		(start 14.075664 -364.131606)
		(end 14.076934 -364.132876)
		(width 0.09525)
		(layer "F.Cu")
		(net "SAS2X28_A_HDD8_RX_+")
	)
	(segment
		(start 16.013938 -277.507192)
		(end 16.013938 -357.202486)
		(width 0.09525)
		(layer "F.Cu")
		(net "SAS2X28_A_HDD8_RX_+")
	)
	(via
		(at 8.61441 -371.520974)
		(size 0.5588)
		(drill 0.3048)
		(layers "F.Cu" "B.Cu")
		(net "SAS2X28_A_HDD8_RX_+")
	)
	(arc
		(start 30.149546 -182.1307)
		(mid 30.252149 -182.646991)
		(end 30.544516 -183.084724)
		(width 0.09525)
		(layer "F.Cu")
		(net "SAS2X28_A_HDD8_RX_+")
	)
	(arc
		(start 36.804346 -255.175512)
		(mid 36.623958 -256.081532)
		(end 36.110672 -256.849626)
		(width 0.09525)
		(layer "F.Cu")
		(net "SAS2X28_A_HDD8_RX_+")
	)
	(arc
		(start 16.410686 -276.549866)
		(mid 16.117264 -276.989237)
		(end 16.014192 -277.507446)
		(width 0.09525)
		(layer "F.Cu")
		(net "SAS2X28_A_HDD8_RX_+")
	)
	(arc
		(start 33.443926 -160.920684)
		(mid 33.132774 -160.712779)
		(end 32.765746 -160.63976)
		(width 0.09525)
		(layer "F.Cu")
		(net "SAS2X28_A_HDD8_RX_+")
	)
	(arc
		(start 31.441644 -160.63976)
		(mid 31.11145 -160.70544)
		(end 30.831536 -160.89249)
		(width 0.09525)
		(layer "F.Cu")
		(net "SAS2X28_A_HDD8_RX_+")
	)
	(arc
		(start 8.735314 -370.939568)
		(mid 8.645845 -371.073468)
		(end 8.61441 -371.231414)
		(width 0.09525)
		(layer "F.Cu")
		(net "SAS2X28_A_HDD8_RX_+")
	)
	(arc
		(start 16.013938 -357.202486)
		(mid 15.911745 -357.716625)
		(end 15.620492 -358.152446)
		(width 0.09525)
		(layer "F.Cu")
		(net "SAS2X28_A_HDD8_RX_+")
	)
	(arc
		(start 36.351464 -188.891418)
		(mid 36.686837 -189.393339)
		(end 36.8046 -189.985396)
		(width 0.09525)
		(layer "F.Cu")
		(net "SAS2X28_A_HDD8_RX_+")
	)
	(arc
		(start 14.381734 -359.39222)
		(mid 14.155219 -359.731224)
		(end 14.075664 -360.131106)
		(width 0.09525)
		(layer "F.Cu")
		(net "SAS2X28_A_HDD8_RX_+")
	)
	(arc
		(start 30.387036 -161.33699)
		(mid 30.21129 -161.600012)
		(end 30.149546 -161.910268)
		(width 0.09525)
		(layer "F.Cu")
		(net "SAS2X28_A_HDD8_RX_+")
	)
	(arc
		(start 14.075664 -365.19866)
		(mid 14.002028 -365.568473)
		(end 13.792454 -365.88192)
		(width 0.09525)
		(layer "F.Cu")
		(net "SAS2X28_A_HDD8_RX_+")
	)
	(segment
		(start 6.753098 -368.207798)
		(end 6.65734 -368.111786)
		(width 0.09525)
		(layer "B.Cu")
		(net "SAS2X28_A_HDD8_RX_+")
	)
	(segment
		(start 8.203946 -371.238018)
		(end 8.203946 -370.3447)
		(width 0.09525)
		(layer "B.Cu")
		(net "SAS2X28_A_HDD8_RX_+")
	)
	(segment
		(start 8.27405 -371.380004)
		(end 8.254746 -371.3607)
		(width 0.09525)
		(layer "B.Cu")
		(net "SAS2X28_A_HDD8_RX_+")
	)
	(segment
		(start 7.719314 -369.174014)
		(end 6.753098 -368.207798)
		(width 0.09525)
		(layer "B.Cu")
		(net "SAS2X28_A_HDD8_RX_+")
	)
	(segment
		(start 5.978144 -367.830608)
		(end 5.657342 -367.830608)
		(width 0.09525)
		(layer "B.Cu")
		(net "SAS2X28_A_HDD8_RX_+")
	)
	(segment
		(start 4.858512 -367.498884)
		(end 2.811526 -367.498884)
		(width 0.09525)
		(layer "B.Cu")
		(net "SAS2X28_A_HDD8_RX_+")
	)
	(segment
		(start 4.860036 -367.500408)
		(end 4.858512 -367.498884)
		(width 0.09525)
		(layer "B.Cu")
		(net "SAS2X28_A_HDD8_RX_+")
	)
	(arc
		(start 5.299202 -367.682272)
		(mid 5.097711 -367.54764)
		(end 4.860036 -367.500408)
		(width 0.09525)
		(layer "B.Cu")
		(net "SAS2X28_A_HDD8_RX_+")
	)
	(arc
		(start 8.203946 -370.3447)
		(mid 8.07804 -369.711169)
		(end 7.719314 -369.174014)
		(width 0.09525)
		(layer "B.Cu")
		(net "SAS2X28_A_HDD8_RX_+")
	)
	(arc
		(start 5.657342 -367.830608)
		(mid 5.463522 -367.792055)
		(end 5.299202 -367.682272)
		(width 0.09525)
		(layer "B.Cu")
		(net "SAS2X28_A_HDD8_RX_+")
	)
	(arc
		(start 6.65734 -368.111786)
		(mid 6.345707 -367.903653)
		(end 5.978144 -367.830608)
		(width 0.09525)
		(layer "B.Cu")
		(net "SAS2X28_A_HDD8_RX_+")
	)
	(arc
		(start 8.254746 -371.3607)
		(mid 8.217136 -371.304413)
		(end 8.203946 -371.238018)
		(width 0.09525)
		(layer "B.Cu")
		(net "SAS2X28_A_HDD8_RX_+")
	)
	(arc
		(start 8.61441 -371.520974)
		(mid 8.430213 -371.484335)
		(end 8.27405 -371.380004)
		(width 0.09525)
		(layer "B.Cu")
		(net "SAS2X28_A_HDD8_RX_+")
	)
	(via
		(at 65.5828 -183.4642)
		(size 0.7112)
		(drill 0.3556)
		(layers "F.Cu" "B.Cu")
		(net "P5V_HDD8")
	)
	(via
		(at 55.117746 -181.1147)
		(size 0.7112)
		(drill 0.3556)
		(layers "F.Cu" "B.Cu")
		(net "P5V_HDD8")
	)
	(segment
		(start 82.803746 -175.3997)
		(end 89.026746 -181.6227)
		(width 0.111252)
		(layer "F.Cu")
		(net "HDD_PRSNT8")
	)
	(segment
		(start 56.260746 -174.6377)
		(end 56.260746 -169.646854)
		(width 0.111252)
		(layer "F.Cu")
		(net "HDD_PRSNT8")
	)
	(segment
		(start 56.260746 -169.646854)
		(end 57.8866 -168.021)
		(width 0.111252)
		(layer "F.Cu")
		(net "HDD_PRSNT8")
	)
	(segment
		(start 59.5884 -168.021)
		(end 66.9671 -175.3997)
		(width 0.111252)
		(layer "F.Cu")
		(net "HDD_PRSNT8")
	)
	(segment
		(start 66.9671 -175.3997)
		(end 82.803746 -175.3997)
		(width 0.111252)
		(layer "F.Cu")
		(net "HDD_PRSNT8")
	)
	(segment
		(start 57.8866 -168.021)
		(end 59.5884 -168.021)
		(width 0.111252)
		(layer "F.Cu")
		(net "HDD_PRSNT8")
	)
	(via
		(at 9.988296 -452.278242)
		(size 0.5588)
		(drill 0.3048)
		(layers "F.Cu" "B.Cu")
		(net "HDD_PRSNT8")
	)
	(via
		(at 13.283946 -203.5683)
		(size 0.7112)
		(drill 0.3556)
		(layers "F.Cu" "B.Cu")
		(net "HDD_PRSNT8")
	)
	(via
		(at 14.295374 -203.5429)
		(size 0.5588)
		(drill 0.3048)
		(layers "F.Cu" "B.Cu")
		(net "HDD_PRSNT8")
	)
	(via
		(at 89.026746 -181.6227)
		(size 0.5588)
		(drill 0.3048)
		(layers "F.Cu" "B.Cu")
		(net "HDD_PRSNT8")
	)
	(via
		(at 9.906 -444.7032)
		(size 0.5588)
		(drill 0.3048)
		(layers "F.Cu" "B.Cu")
		(net "HDD_PRSNT8")
	)
	(segment
		(start 6.287262 -203.504546)
		(end 6.3754 -203.416408)
		(width 0.111252)
		(layer "B.Cu")
		(net "HDD_PRSNT8")
	)
	(segment
		(start 14.269974 -203.5683)
		(end 13.283946 -203.5683)
		(width 0.111252)
		(layer "B.Cu")
		(net "HDD_PRSNT8")
	)
	(segment
		(start 9.988296 -452.278242)
		(end 7.746746 -452.278242)
		(width 0.111252)
		(layer "B.Cu")
		(net "HDD_PRSNT8")
	)
	(segment
		(start 6.3754 -203.416408)
		(end 10.188702 -203.416408)
		(width 0.111252)
		(layer "B.Cu")
		(net "HDD_PRSNT8")
	)
	(segment
		(start 14.295374 -203.5429)
		(end 14.269974 -203.5683)
		(width 0.111252)
		(layer "B.Cu")
		(net "HDD_PRSNT8")
	)
	(segment
		(start 2.80924 -203.504546)
		(end 6.287262 -203.504546)
		(width 0.111252)
		(layer "B.Cu")
		(net "HDD_PRSNT8")
	)
	(segment
		(start 6.523736 -453.501252)
		(end 2.812542 -453.501252)
		(width 0.111252)
		(layer "B.Cu")
		(net "HDD_PRSNT8")
	)
	(segment
		(start 10.340594 -203.5683)
		(end 13.283946 -203.5683)
		(width 0.111252)
		(layer "B.Cu")
		(net "HDD_PRSNT8")
	)
	(segment
		(start 7.746746 -452.278242)
		(end 6.523736 -453.501252)
		(width 0.111252)
		(layer "B.Cu")
		(net "HDD_PRSNT8")
	)
	(segment
		(start 10.188702 -203.416408)
		(end 10.340594 -203.5683)
		(width 0.111252)
		(layer "B.Cu")
		(net "HDD_PRSNT8")
	)
	(segment
		(start 2.812542 -453.501252)
		(end 2.80924 -453.504554)
		(width 0.111252)
		(layer "B.Cu")
		(net "HDD_PRSNT8")
	)
	(segment
		(start 10.065766 -444.543434)
		(end 10.362946 -444.543434)
		(width 0.14605)
		(layer "In2.Cu")
		(net "HDD_PRSNT8")
	)
	(segment
		(start 14.014704 -394.676376)
		(end 14.582648 -394.108432)
		(width 0.14605)
		(layer "In2.Cu")
		(net "HDD_PRSNT8")
	)
	(segment
		(start 14.639036 -267.153644)
		(end 14.639036 -266.406376)
		(width 0.14605)
		(layer "In2.Cu")
		(net "HDD_PRSNT8")
	)
	(segment
		(start 9.641332 -451.931278)
		(end 9.988296 -452.278242)
		(width 0.14605)
		(layer "In2.Cu")
		(net "HDD_PRSNT8")
	)
	(segment
		(start 10.362946 -444.543434)
		(end 13.73759 -441.16879)
		(width 0.14605)
		(layer "In2.Cu")
		(net "HDD_PRSNT8")
	)
	(segment
		(start 14.63929 -267.153898)
		(end 14.639036 -267.153644)
		(width 0.14605)
		(layer "In2.Cu")
		(net "HDD_PRSNT8")
	)
	(segment
		(start 14.296644 -217.11285)
		(end 14.296644 -211.94903)
		(width 0.14605)
		(layer "In2.Cu")
		(net "HDD_PRSNT8")
	)
	(segment
		(start 15.1003 -375.728484)
		(end 15.1003 -365.68634)
		(width 0.14605)
		(layer "In2.Cu")
		(net "HDD_PRSNT8")
	)
	(segment
		(start 14.014704 -396.509494)
		(end 14.014704 -394.676376)
		(width 0.14605)
		(layer "In2.Cu")
		(net "HDD_PRSNT8")
	)
	(segment
		(start 14.63929 -365.22533)
		(end 14.63929 -267.153898)
		(width 0.14605)
		(layer "In2.Cu")
		(net "HDD_PRSNT8")
	)
	(segment
		(start 14.296644 -211.94903)
		(end 13.255244 -210.90763)
		(width 0.14605)
		(layer "In2.Cu")
		(net "HDD_PRSNT8")
	)
	(segment
		(start 14.582648 -376.246136)
		(end 15.1003 -375.728484)
		(width 0.14605)
		(layer "In2.Cu")
		(net "HDD_PRSNT8")
	)
	(segment
		(start 14.331188 -255.923288)
		(end 14.331188 -217.147394)
		(width 0.14605)
		(layer "In2.Cu")
		(net "HDD_PRSNT8")
	)
	(segment
		(start 9.906 -444.7032)
		(end 10.065766 -444.543434)
		(width 0.14605)
		(layer "In2.Cu")
		(net "HDD_PRSNT8")
	)
	(segment
		(start 13.255244 -207.001872)
		(end 14.295374 -205.961742)
		(width 0.14605)
		(layer "In2.Cu")
		(net "HDD_PRSNT8")
	)
	(segment
		(start 13.73759 -441.16879)
		(end 13.73759 -414.996884)
		(width 0.14605)
		(layer "In2.Cu")
		(net "HDD_PRSNT8")
	)
	(segment
		(start 14.295374 -205.961742)
		(end 14.295374 -203.5429)
		(width 0.14605)
		(layer "In2.Cu")
		(net "HDD_PRSNT8")
	)
	(segment
		(start 15.5194 -265.526012)
		(end 15.5194 -258.321556)
		(width 0.14605)
		(layer "In2.Cu")
		(net "HDD_PRSNT8")
	)
	(segment
		(start 13.255244 -210.90763)
		(end 13.255244 -207.001872)
		(width 0.14605)
		(layer "In2.Cu")
		(net "HDD_PRSNT8")
	)
	(segment
		(start 14.95425 -257.756406)
		(end 14.95425 -256.54635)
		(width 0.14605)
		(layer "In2.Cu")
		(net "HDD_PRSNT8")
	)
	(segment
		(start 15.5194 -258.321556)
		(end 14.95425 -257.756406)
		(width 0.14605)
		(layer "In2.Cu")
		(net "HDD_PRSNT8")
	)
	(segment
		(start 14.582648 -394.108432)
		(end 14.582648 -376.246136)
		(width 0.14605)
		(layer "In2.Cu")
		(net "HDD_PRSNT8")
	)
	(segment
		(start 15.1003 -365.68634)
		(end 14.63929 -365.22533)
		(width 0.14605)
		(layer "In2.Cu")
		(net "HDD_PRSNT8")
	)
	(segment
		(start 14.331188 -217.147394)
		(end 14.296644 -217.11285)
		(width 0.14605)
		(layer "In2.Cu")
		(net "HDD_PRSNT8")
	)
	(segment
		(start 9.906 -444.7032)
		(end 9.641332 -444.967868)
		(width 0.14605)
		(layer "In2.Cu")
		(net "HDD_PRSNT8")
	)
	(segment
		(start 13.912088 -414.822386)
		(end 13.912088 -396.611856)
		(width 0.14605)
		(layer "In2.Cu")
		(net "HDD_PRSNT8")
	)
	(segment
		(start 9.641332 -444.967868)
		(end 9.641332 -451.931278)
		(width 0.14605)
		(layer "In2.Cu")
		(net "HDD_PRSNT8")
	)
	(segment
		(start 14.95425 -256.54635)
		(end 14.331188 -255.923288)
		(width 0.14605)
		(layer "In2.Cu")
		(net "HDD_PRSNT8")
	)
	(segment
		(start 13.912088 -396.611856)
		(end 14.014704 -396.509494)
		(width 0.14605)
		(layer "In2.Cu")
		(net "HDD_PRSNT8")
	)
	(segment
		(start 14.639036 -266.406376)
		(end 15.5194 -265.526012)
		(width 0.14605)
		(layer "In2.Cu")
		(net "HDD_PRSNT8")
	)
	(segment
		(start 13.73759 -414.996884)
		(end 13.912088 -414.822386)
		(width 0.14605)
		(layer "In2.Cu")
		(net "HDD_PRSNT8")
	)
	(segment
		(start 12.309856 -445.061848)
		(end 11.248898 -445.061848)
		(width 0.14605)
		(layer "In5.Cu")
		(net "HDD_PRSNT8")
	)
	(segment
		(start 90.390726 -436.286402)
		(end 75.750674 -450.926454)
		(width 0.14605)
		(layer "In5.Cu")
		(net "HDD_PRSNT8")
	)
	(segment
		(start 11.11885 -444.9318)
		(end 10.1346 -444.9318)
		(width 0.14605)
		(layer "In5.Cu")
		(net "HDD_PRSNT8")
	)
	(segment
		(start 91.937078 -184.533032)
		(end 91.937078 -434.89753)
		(width 0.14605)
		(layer "In5.Cu")
		(net "HDD_PRSNT8")
	)
	(segment
		(start 11.248898 -445.061848)
		(end 11.11885 -444.9318)
		(width 0.14605)
		(layer "In5.Cu")
		(net "HDD_PRSNT8")
	)
	(segment
		(start 89.026746 -181.6227)
		(end 91.937078 -184.533032)
		(width 0.14605)
		(layer "In5.Cu")
		(net "HDD_PRSNT8")
	)
	(segment
		(start 90.548206 -436.286402)
		(end 90.390726 -436.286402)
		(width 0.14605)
		(layer "In5.Cu")
		(net "HDD_PRSNT8")
	)
	(segment
		(start 18.174462 -450.926454)
		(end 12.309856 -445.061848)
		(width 0.14605)
		(layer "In5.Cu")
		(net "HDD_PRSNT8")
	)
	(segment
		(start 10.1346 -444.9318)
		(end 9.906 -444.7032)
		(width 0.14605)
		(layer "In5.Cu")
		(net "HDD_PRSNT8")
	)
	(segment
		(start 75.750674 -450.926454)
		(end 18.174462 -450.926454)
		(width 0.14605)
		(layer "In5.Cu")
		(net "HDD_PRSNT8")
	)
	(segment
		(start 91.937078 -434.89753)
		(end 90.548206 -436.286402)
		(width 0.14605)
		(layer "In5.Cu")
		(net "HDD_PRSNT8")
	)
	(segment
		(start 39.022782 -164.5539)
		(end 36.961826 -164.5539)
		(width 0.09525)
		(layer "F.Cu")
		(net "SAS2X28_B_HDD8_TX_-")
	)
	(segment
		(start 4.948428 -120.49887)
		(end 3.192526 -120.49887)
		(width 0.09525)
		(layer "F.Cu")
		(net "SAS2X28_B_HDD8_TX_-")
	)
	(segment
		(start 15.51559 -120.160796)
		(end 5.76961 -120.160796)
		(width 0.09525)
		(layer "F.Cu")
		(net "SAS2X28_B_HDD8_TX_-")
	)
	(segment
		(start 40.39997 -164.789866)
		(end 39.587932 -164.789866)
		(width 0.09525)
		(layer "F.Cu")
		(net "SAS2X28_B_HDD8_TX_-")
	)
	(segment
		(start 39.587932 -164.789866)
		(end 39.58463 -164.786564)
		(width 0.09525)
		(layer "F.Cu")
		(net "SAS2X28_B_HDD8_TX_-")
	)
	(segment
		(start 4.949952 -120.500394)
		(end 4.948428 -120.49887)
		(width 0.09525)
		(layer "F.Cu")
		(net "SAS2X28_B_HDD8_TX_-")
	)
	(via
		(at 36.636452 -164.879274)
		(size 0.5588)
		(drill 0.3048)
		(layers "F.Cu" "B.Cu")
		(net "SAS2X28_B_HDD8_TX_-")
	)
	(via
		(at 16.356838 -120.509284)
		(size 0.5588)
		(drill 0.3048)
		(layers "F.Cu" "B.Cu")
		(net "SAS2X28_B_HDD8_TX_-")
	)
	(arc
		(start 39.268146 -164.6555)
		(mid 39.155572 -164.58028)
		(end 39.022782 -164.5539)
		(width 0.09525)
		(layer "F.Cu")
		(net "SAS2X28_B_HDD8_TX_-")
	)
	(arc
		(start 36.961826 -164.5539)
		(mid 36.731752 -164.6492)
		(end 36.636452 -164.879274)
		(width 0.09525)
		(layer "F.Cu")
		(net "SAS2X28_B_HDD8_TX_-")
	)
	(arc
		(start 39.58463 -164.786564)
		(mid 39.413361 -164.752496)
		(end 39.268146 -164.6555)
		(width 0.09525)
		(layer "F.Cu")
		(net "SAS2X28_B_HDD8_TX_-")
	)
	(arc
		(start 5.76961 -120.160796)
		(mid 5.529036 -120.208649)
		(end 5.32511 -120.344946)
		(width 0.09525)
		(layer "F.Cu")
		(net "SAS2X28_B_HDD8_TX_-")
	)
	(arc
		(start 5.32511 -120.344946)
		(mid 5.152986 -120.459956)
		(end 4.949952 -120.500394)
		(width 0.09525)
		(layer "F.Cu")
		(net "SAS2X28_B_HDD8_TX_-")
	)
	(arc
		(start 16.356838 -120.509284)
		(mid 15.97087 -120.251389)
		(end 15.51559 -120.160796)
		(width 0.09525)
		(layer "F.Cu")
		(net "SAS2X28_B_HDD8_TX_-")
	)
	(segment
		(start 33.189418 -159.6771)
		(end 31.356046 -159.6771)
		(width 0.1143)
		(layer "In5.Cu")
		(net "SAS2X28_B_HDD8_TX_-")
	)
	(segment
		(start 33.629346 -162.441636)
		(end 33.629346 -160.18891)
		(width 0.1143)
		(layer "In5.Cu")
		(net "SAS2X28_B_HDD8_TX_-")
	)
	(segment
		(start 34.188146 -147.928584)
		(end 34.188146 -137.4394)
		(width 0.1143)
		(layer "In5.Cu")
		(net "SAS2X28_B_HDD8_TX_-")
	)
	(segment
		(start 36.234878 -164.4777)
		(end 35.66541 -164.4777)
		(width 0.1143)
		(layer "In5.Cu")
		(net "SAS2X28_B_HDD8_TX_-")
	)
	(segment
		(start 30.301946 -158.30042)
		(end 30.301946 -149.3901)
		(width 0.1143)
		(layer "In5.Cu")
		(net "SAS2X28_B_HDD8_TX_-")
	)
	(segment
		(start 16.578834 -120.287288)
		(end 16.356838 -120.509284)
		(width 0.1143)
		(layer "In5.Cu")
		(net "SAS2X28_B_HDD8_TX_-")
	)
	(segment
		(start 32.975296 -135.198104)
		(end 18.160746 -120.3833)
		(width 0.1143)
		(layer "In5.Cu")
		(net "SAS2X28_B_HDD8_TX_-")
	)
	(segment
		(start 31.267146 -148.4249)
		(end 33.170622 -148.4249)
		(width 0.1143)
		(layer "In5.Cu")
		(net "SAS2X28_B_HDD8_TX_-")
	)
	(segment
		(start 17.613376 -120.156478)
		(end 16.894556 -120.156478)
		(width 0.1143)
		(layer "In5.Cu")
		(net "SAS2X28_B_HDD8_TX_-")
	)
	(segment
		(start 34.187892 -147.92833)
		(end 34.188146 -147.928584)
		(width 0.1143)
		(layer "In5.Cu")
		(net "SAS2X28_B_HDD8_TX_-")
	)
	(segment
		(start 35.051746 -164.2237)
		(end 33.883346 -163.0553)
		(width 0.1143)
		(layer "In5.Cu")
		(net "SAS2X28_B_HDD8_TX_-")
	)
	(segment
		(start 33.460944 -135.683752)
		(end 32.975296 -135.198104)
		(width 0.1143)
		(layer "In5.Cu")
		(net "SAS2X28_B_HDD8_TX_-")
	)
	(arc
		(start 33.170622 -148.4249)
		(mid 33.700958 -148.31924)
		(end 34.150554 -148.018754)
		(width 0.1143)
		(layer "In5.Cu")
		(net "SAS2X28_B_HDD8_TX_-")
	)
	(arc
		(start 33.629346 -160.18891)
		(mid 33.586505 -159.973623)
		(end 33.4645 -159.791146)
		(width 0.1143)
		(layer "In5.Cu")
		(net "SAS2X28_B_HDD8_TX_-")
	)
	(arc
		(start 18.160746 -120.3833)
		(mid 17.909625 -120.215443)
		(end 17.613376 -120.156478)
		(width 0.1143)
		(layer "In5.Cu")
		(net "SAS2X28_B_HDD8_TX_-")
	)
	(arc
		(start 16.894556 -120.156478)
		(mid 16.723715 -120.190536)
		(end 16.578834 -120.287288)
		(width 0.1143)
		(layer "In5.Cu")
		(net "SAS2X28_B_HDD8_TX_-")
	)
	(arc
		(start 30.301946 -149.3901)
		(mid 30.584647 -148.707601)
		(end 31.267146 -148.4249)
		(width 0.1143)
		(layer "In5.Cu")
		(net "SAS2X28_B_HDD8_TX_-")
	)
	(arc
		(start 33.883346 -163.0553)
		(mid 33.695302 -162.773734)
		(end 33.629346 -162.441636)
		(width 0.1143)
		(layer "In5.Cu")
		(net "SAS2X28_B_HDD8_TX_-")
	)
	(arc
		(start 34.150554 -148.018754)
		(mid 34.178275 -147.977267)
		(end 34.187892 -147.92833)
		(width 0.1143)
		(layer "In5.Cu")
		(net "SAS2X28_B_HDD8_TX_-")
	)
	(arc
		(start 33.4645 -159.791146)
		(mid 33.338306 -159.706762)
		(end 33.189418 -159.6771)
		(width 0.1143)
		(layer "In5.Cu")
		(net "SAS2X28_B_HDD8_TX_-")
	)
	(arc
		(start 34.188146 -137.4394)
		(mid 33.99915 -136.489254)
		(end 33.460944 -135.683752)
		(width 0.1143)
		(layer "In5.Cu")
		(net "SAS2X28_B_HDD8_TX_-")
	)
	(arc
		(start 36.636452 -164.879274)
		(mid 36.518834 -164.595318)
		(end 36.234878 -164.4777)
		(width 0.1143)
		(layer "In5.Cu")
		(net "SAS2X28_B_HDD8_TX_-")
	)
	(arc
		(start 31.356046 -159.6771)
		(mid 31.040048 -159.614414)
		(end 30.7721 -159.435546)
		(width 0.1143)
		(layer "In5.Cu")
		(net "SAS2X28_B_HDD8_TX_-")
	)
	(arc
		(start 35.66541 -164.4777)
		(mid 35.333316 -164.411736)
		(end 35.051746 -164.2237)
		(width 0.1143)
		(layer "In5.Cu")
		(net "SAS2X28_B_HDD8_TX_-")
	)
	(arc
		(start 30.7721 -159.435546)
		(mid 30.424166 -158.914732)
		(end 30.301946 -158.30042)
		(width 0.1143)
		(layer "In5.Cu")
		(net "SAS2X28_B_HDD8_TX_-")
	)
	(segment
		(start 15.91183 -119.830596)
		(end 5.621782 -119.830596)
		(width 0.09525)
		(layer "F.Cu")
		(net "SAS2X28_B_HDD8_TX_+")
	)
	(segment
		(start 5.377688 -119.729504)
		(end 5.301488 -119.653304)
		(width 0.09525)
		(layer "F.Cu")
		(net "SAS2X28_B_HDD8_TX_+")
	)
	(segment
		(start 39.487602 -163.99002)
		(end 39.4843 -163.986718)
		(width 0.09525)
		(layer "F.Cu")
		(net "SAS2X28_B_HDD8_TX_+")
	)
	(segment
		(start 4.930902 -119.498872)
		(end 3.192526 -119.498872)
		(width 0.09525)
		(layer "F.Cu")
		(net "SAS2X28_B_HDD8_TX_+")
	)
	(segment
		(start 38.912546 -164.2237)
		(end 36.939728 -164.2237)
		(width 0.09525)
		(layer "F.Cu")
		(net "SAS2X28_B_HDD8_TX_+")
	)
	(segment
		(start 4.932426 -119.500396)
		(end 4.930902 -119.498872)
		(width 0.09525)
		(layer "F.Cu")
		(net "SAS2X28_B_HDD8_TX_+")
	)
	(segment
		(start 40.39997 -163.99002)
		(end 39.487602 -163.99002)
		(width 0.09525)
		(layer "F.Cu")
		(net "SAS2X28_B_HDD8_TX_+")
	)
	(via
		(at 16.358362 -119.645684)
		(size 0.5588)
		(drill 0.3048)
		(layers "F.Cu" "B.Cu")
		(net "SAS2X28_B_HDD8_TX_+")
	)
	(via
		(at 36.636452 -163.920424)
		(size 0.5588)
		(drill 0.3048)
		(layers "F.Cu" "B.Cu")
		(net "SAS2X28_B_HDD8_TX_+")
	)
	(arc
		(start 39.4843 -163.986718)
		(mid 39.362506 -164.010944)
		(end 39.259256 -164.079936)
		(width 0.09525)
		(layer "F.Cu")
		(net "SAS2X28_B_HDD8_TX_+")
	)
	(arc
		(start 5.621782 -119.830596)
		(mid 5.489685 -119.80432)
		(end 5.377688 -119.729504)
		(width 0.09525)
		(layer "F.Cu")
		(net "SAS2X28_B_HDD8_TX_+")
	)
	(arc
		(start 16.358362 -119.645684)
		(mid 16.153491 -119.782574)
		(end 15.91183 -119.830596)
		(width 0.09525)
		(layer "F.Cu")
		(net "SAS2X28_B_HDD8_TX_+")
	)
	(arc
		(start 36.939728 -164.2237)
		(mid 36.725279 -164.134873)
		(end 36.636452 -163.920424)
		(width 0.09525)
		(layer "F.Cu")
		(net "SAS2X28_B_HDD8_TX_+")
	)
	(arc
		(start 39.259256 -164.079936)
		(mid 39.100199 -164.186307)
		(end 38.912546 -164.2237)
		(width 0.09525)
		(layer "F.Cu")
		(net "SAS2X28_B_HDD8_TX_+")
	)
	(arc
		(start 5.301488 -119.653304)
		(mid 5.132161 -119.540163)
		(end 4.932426 -119.500396)
		(width 0.09525)
		(layer "F.Cu")
		(net "SAS2X28_B_HDD8_TX_+")
	)
	(segment
		(start 33.934146 -160.188656)
		(end 33.934146 -162.441636)
		(width 0.1143)
		(layer "In5.Cu")
		(net "SAS2X28_B_HDD8_TX_+")
	)
	(segment
		(start 30.606746 -156.341064)
		(end 30.606746 -156.683964)
		(width 0.1143)
		(layer "In5.Cu")
		(net "SAS2X28_B_HDD8_TX_+")
	)
	(segment
		(start 18.376392 -120.167654)
		(end 33.190942 -134.982458)
		(width 0.1143)
		(layer "In5.Cu")
		(net "SAS2X28_B_HDD8_TX_+")
	)
	(segment
		(start 34.492946 -137.4394)
		(end 34.492946 -147.92833)
		(width 0.1143)
		(layer "In5.Cu")
		(net "SAS2X28_B_HDD8_TX_+")
	)
	(segment
		(start 31.355792 -159.3723)
		(end 33.189672 -159.3723)
		(width 0.1143)
		(layer "In5.Cu")
		(net "SAS2X28_B_HDD8_TX_+")
	)
	(segment
		(start 30.794706 -157.059884)
		(end 30.794706 -157.402784)
		(width 0.1143)
		(layer "In5.Cu")
		(net "SAS2X28_B_HDD8_TX_+")
	)
	(segment
		(start 35.66541 -164.1729)
		(end 36.383976 -164.1729)
		(width 0.1143)
		(layer "In5.Cu")
		(net "SAS2X28_B_HDD8_TX_+")
	)
	(segment
		(start 30.606746 -157.778704)
		(end 30.606746 -158.300166)
		(width 0.1143)
		(layer "In5.Cu")
		(net "SAS2X28_B_HDD8_TX_+")
	)
	(segment
		(start 16.855694 -119.851678)
		(end 17.61363 -119.851678)
		(width 0.1143)
		(layer "In5.Cu")
		(net "SAS2X28_B_HDD8_TX_+")
	)
	(segment
		(start 33.190942 -134.982458)
		(end 33.67659 -135.468106)
		(width 0.1143)
		(layer "In5.Cu")
		(net "SAS2X28_B_HDD8_TX_+")
	)
	(segment
		(start 33.170368 -148.7297)
		(end 31.267146 -148.7297)
		(width 0.1143)
		(layer "In5.Cu")
		(net "SAS2X28_B_HDD8_TX_+")
	)
	(segment
		(start 34.098992 -162.839654)
		(end 35.267392 -164.008054)
		(width 0.1143)
		(layer "In5.Cu")
		(net "SAS2X28_B_HDD8_TX_+")
	)
	(segment
		(start 30.606746 -149.3901)
		(end 30.606746 -155.246324)
		(width 0.1143)
		(layer "In5.Cu")
		(net "SAS2X28_B_HDD8_TX_+")
	)
	(segment
		(start 30.794706 -155.622244)
		(end 30.794706 -155.965144)
		(width 0.1143)
		(layer "In5.Cu")
		(net "SAS2X28_B_HDD8_TX_+")
	)
	(arc
		(start 31.267146 -148.7297)
		(mid 30.800173 -148.923127)
		(end 30.606746 -149.3901)
		(width 0.1143)
		(layer "In5.Cu")
		(net "SAS2X28_B_HDD8_TX_+")
	)
	(arc
		(start 30.606746 -158.300166)
		(mid 30.705758 -158.797935)
		(end 30.987746 -159.2199)
		(width 0.1143)
		(layer "In5.Cu")
		(net "SAS2X28_B_HDD8_TX_+")
	)
	(arc
		(start 17.61363 -119.851678)
		(mid 18.026445 -119.933792)
		(end 18.376392 -120.167654)
		(width 0.1143)
		(layer "In5.Cu")
		(net "SAS2X28_B_HDD8_TX_+")
	)
	(arc
		(start 30.794706 -155.965144)
		(mid 30.769551 -156.070054)
		(end 30.700726 -156.153104)
		(width 0.1143)
		(layer "In5.Cu")
		(net "SAS2X28_B_HDD8_TX_+")
	)
	(arc
		(start 30.606746 -155.246324)
		(mid 30.631901 -155.351234)
		(end 30.700726 -155.434284)
		(width 0.1143)
		(layer "In5.Cu")
		(net "SAS2X28_B_HDD8_TX_+")
	)
	(arc
		(start 30.987746 -159.2199)
		(mid 31.156607 -159.332729)
		(end 31.355792 -159.3723)
		(width 0.1143)
		(layer "In5.Cu")
		(net "SAS2X28_B_HDD8_TX_+")
	)
	(arc
		(start 30.700726 -157.590744)
		(mid 30.63199 -157.673838)
		(end 30.606746 -157.778704)
		(width 0.1143)
		(layer "In5.Cu")
		(net "SAS2X28_B_HDD8_TX_+")
	)
	(arc
		(start 36.383976 -164.1729)
		(mid 36.562503 -164.098951)
		(end 36.636452 -163.920424)
		(width 0.1143)
		(layer "In5.Cu")
		(net "SAS2X28_B_HDD8_TX_+")
	)
	(arc
		(start 30.700726 -155.434284)
		(mid 30.769462 -155.517378)
		(end 30.794706 -155.622244)
		(width 0.1143)
		(layer "In5.Cu")
		(net "SAS2X28_B_HDD8_TX_+")
	)
	(arc
		(start 33.189672 -159.3723)
		(mid 33.45513 -159.425103)
		(end 33.680146 -159.5755)
		(width 0.1143)
		(layer "In5.Cu")
		(net "SAS2X28_B_HDD8_TX_+")
	)
	(arc
		(start 30.700726 -156.153104)
		(mid 30.63199 -156.236198)
		(end 30.606746 -156.341064)
		(width 0.1143)
		(layer "In5.Cu")
		(net "SAS2X28_B_HDD8_TX_+")
	)
	(arc
		(start 30.606746 -156.683964)
		(mid 30.63199 -156.788804)
		(end 30.700726 -156.871924)
		(width 0.1143)
		(layer "In5.Cu")
		(net "SAS2X28_B_HDD8_TX_+")
	)
	(arc
		(start 35.267392 -164.008054)
		(mid 35.450004 -164.130072)
		(end 35.66541 -164.1729)
		(width 0.1143)
		(layer "In5.Cu")
		(net "SAS2X28_B_HDD8_TX_+")
	)
	(arc
		(start 16.358362 -119.645684)
		(mid 16.58654 -119.798148)
		(end 16.855694 -119.851678)
		(width 0.1143)
		(layer "In5.Cu")
		(net "SAS2X28_B_HDD8_TX_+")
	)
	(arc
		(start 30.794706 -157.402784)
		(mid 30.769462 -157.507624)
		(end 30.700726 -157.590744)
		(width 0.1143)
		(layer "In5.Cu")
		(net "SAS2X28_B_HDD8_TX_+")
	)
	(arc
		(start 34.492946 -147.92833)
		(mid 34.46 -148.093962)
		(end 34.3662 -148.2344)
		(width 0.1143)
		(layer "In5.Cu")
		(net "SAS2X28_B_HDD8_TX_+")
	)
	(arc
		(start 34.3662 -148.2344)
		(mid 33.817548 -148.600998)
		(end 33.170368 -148.7297)
		(width 0.1143)
		(layer "In5.Cu")
		(net "SAS2X28_B_HDD8_TX_+")
	)
	(arc
		(start 33.934146 -162.441636)
		(mid 33.976991 -162.657035)
		(end 34.098992 -162.839654)
		(width 0.1143)
		(layer "In5.Cu")
		(net "SAS2X28_B_HDD8_TX_+")
	)
	(arc
		(start 33.67659 -135.468106)
		(mid 34.280833 -136.372558)
		(end 34.492946 -137.4394)
		(width 0.1143)
		(layer "In5.Cu")
		(net "SAS2X28_B_HDD8_TX_+")
	)
	(arc
		(start 30.700726 -156.871924)
		(mid 30.769462 -156.955018)
		(end 30.794706 -157.059884)
		(width 0.1143)
		(layer "In5.Cu")
		(net "SAS2X28_B_HDD8_TX_+")
	)
	(arc
		(start 33.680146 -159.5755)
		(mid 33.868117 -159.856818)
		(end 33.934146 -160.188656)
		(width 0.1143)
		(layer "In5.Cu")
		(net "SAS2X28_B_HDD8_TX_+")
	)
	(via
		(at 28.955746 -326.5297)
		(size 0.7112)
		(drill 0.3556)
		(layers "F.Cu" "B.Cu")
		(net "P5V_HDD11")
	)
	(via
		(at 29.717746 -327.1647)
		(size 0.5588)
		(drill 0.3048)
		(layers "F.Cu" "B.Cu")
		(net "P5V_HDD11")
	)
	(via
		(at 37.1602 -324.5866)
		(size 0.7112)
		(drill 0.3556)
		(layers "F.Cu" "B.Cu")
		(net "P5V_HDD11")
	)
	(segment
		(start 29.717746 -327.1647)
		(end 29.590746 -327.1647)
		(width 0.508)
		(layer "B.Cu")
		(net "P5V_HDD11")
	)
	(segment
		(start 29.590746 -327.1647)
		(end 28.955746 -326.5297)
		(width 0.508)
		(layer "B.Cu")
		(net "P5V_HDD11")
	)
	(segment
		(start 33.002474 -164.517832)
		(end 33.17113 -164.34943)
		(width 0.09525)
		(layer "F.Cu")
		(net "SAS2X28_B_HDD8_RX_-")
	)
	(segment
		(start 32.45993 -165.061138)
		(end 32.459676 -165.060884)
		(width 0.09525)
		(layer "F.Cu")
		(net "SAS2X28_B_HDD8_RX_-")
	)
	(segment
		(start 32.892746 -166.5097)
		(end 32.70758 -166.5097)
		(width 0.09525)
		(layer "F.Cu")
		(net "SAS2X28_B_HDD8_RX_-")
	)
	(segment
		(start 32.206946 -165.937692)
		(end 32.206946 -165.620954)
		(width 0.09525)
		(layer "F.Cu")
		(net "SAS2X28_B_HDD8_RX_-")
	)
	(segment
		(start 33.448752 -166.25951)
		(end 33.41497 -166.293546)
		(width 0.09525)
		(layer "F.Cu")
		(net "SAS2X28_B_HDD8_RX_-")
	)
	(segment
		(start 33.3756 -163.855908)
		(end 33.3756 -163.7284)
		(width 0.09525)
		(layer "F.Cu")
		(net "SAS2X28_B_HDD8_RX_-")
	)
	(segment
		(start 32.459676 -165.06063)
		(end 33.002474 -164.517832)
		(width 0.09525)
		(layer "F.Cu")
		(net "SAS2X28_B_HDD8_RX_-")
	)
	(segment
		(start 32.459676 -165.060884)
		(end 32.459676 -165.06063)
		(width 0.09525)
		(layer "F.Cu")
		(net "SAS2X28_B_HDD8_RX_-")
	)
	(segment
		(start 32.42437 -165.096698)
		(end 32.45993 -165.061138)
		(width 0.09525)
		(layer "F.Cu")
		(net "SAS2X28_B_HDD8_RX_-")
	)
	(via
		(at 33.3756 -163.7284)
		(size 0.5588)
		(drill 0.3048)
		(layers "F.Cu" "B.Cu")
		(net "SAS2X28_B_HDD8_RX_-")
	)
	(via
		(at 6.730746 -118.4275)
		(size 0.5588)
		(drill 0.3048)
		(layers "F.Cu" "B.Cu")
		(net "SAS2X28_B_HDD8_RX_-")
	)
	(arc
		(start 32.206946 -165.620954)
		(mid 32.263448 -165.337168)
		(end 32.42437 -165.096698)
		(width 0.09525)
		(layer "F.Cu")
		(net "SAS2X28_B_HDD8_RX_-")
	)
	(arc
		(start 33.41497 -166.293546)
		(mid 33.175357 -166.453558)
		(end 32.892746 -166.5097)
		(width 0.09525)
		(layer "F.Cu")
		(net "SAS2X28_B_HDD8_RX_-")
	)
	(arc
		(start 33.17113 -164.34943)
		(mid 33.322426 -164.123)
		(end 33.3756 -163.855908)
		(width 0.09525)
		(layer "F.Cu")
		(net "SAS2X28_B_HDD8_RX_-")
	)
	(arc
		(start 32.389318 -166.377874)
		(mid 32.254375 -166.175917)
		(end 32.206946 -165.937692)
		(width 0.09525)
		(layer "F.Cu")
		(net "SAS2X28_B_HDD8_RX_-")
	)
	(arc
		(start 32.70758 -166.5097)
		(mid 32.535339 -166.475439)
		(end 32.389318 -166.377874)
		(width 0.09525)
		(layer "F.Cu")
		(net "SAS2X28_B_HDD8_RX_-")
	)
	(segment
		(start 4.8514 -118.500398)
		(end 4.849876 -118.498874)
		(width 0.09525)
		(layer "B.Cu")
		(net "SAS2X28_B_HDD8_RX_-")
	)
	(segment
		(start 6.730746 -118.4275)
		(end 6.730746 -118.1608)
		(width 0.09525)
		(layer "B.Cu")
		(net "SAS2X28_B_HDD8_RX_-")
	)
	(segment
		(start 6.0452 -118.1608)
		(end 5.495544 -118.1608)
		(width 0.09525)
		(layer "B.Cu")
		(net "SAS2X28_B_HDD8_RX_-")
	)
	(segment
		(start 5.209794 -118.279164)
		(end 5.085588 -118.40337)
		(width 0.09525)
		(layer "B.Cu")
		(net "SAS2X28_B_HDD8_RX_-")
	)
	(segment
		(start 4.849876 -118.498874)
		(end 2.811526 -118.498874)
		(width 0.09525)
		(layer "B.Cu")
		(net "SAS2X28_B_HDD8_RX_-")
	)
	(arc
		(start 5.085588 -118.40337)
		(mid 4.978142 -118.475163)
		(end 4.8514 -118.500398)
		(width 0.09525)
		(layer "B.Cu")
		(net "SAS2X28_B_HDD8_RX_-")
	)
	(arc
		(start 6.730746 -118.1608)
		(mid 6.673546 -118.056357)
		(end 6.554724 -118.048278)
		(width 0.09525)
		(layer "B.Cu")
		(net "SAS2X28_B_HDD8_RX_-")
	)
	(arc
		(start 5.495544 -118.1608)
		(mid 5.340896 -118.191561)
		(end 5.209794 -118.279164)
		(width 0.09525)
		(layer "B.Cu")
		(net "SAS2X28_B_HDD8_RX_-")
	)
	(arc
		(start 6.554724 -118.048278)
		(mid 6.306099 -118.132322)
		(end 6.0452 -118.1608)
		(width 0.09525)
		(layer "B.Cu")
		(net "SAS2X28_B_HDD8_RX_-")
	)
	(segment
		(start 36.949126 -138.005058)
		(end 17.55013 -118.606062)
		(width 0.1143)
		(layer "In2.Cu")
		(net "SAS2X28_B_HDD8_RX_-")
	)
	(segment
		(start 37.246306 -144.685258)
		(end 37.246306 -144.342358)
		(width 0.1143)
		(layer "In2.Cu")
		(net "SAS2X28_B_HDD8_RX_-")
	)
	(segment
		(start 37.246306 -140.372338)
		(end 37.246306 -138.7221)
		(width 0.1143)
		(layer "In2.Cu")
		(net "SAS2X28_B_HDD8_RX_-")
	)
	(segment
		(start 37.246306 -148.710396)
		(end 37.246306 -148.367496)
		(width 0.1143)
		(layer "In2.Cu")
		(net "SAS2X28_B_HDD8_RX_-")
	)
	(segment
		(start 37.24656 -151.7777)
		(end 37.246306 -151.7777)
		(width 0.1143)
		(layer "In2.Cu")
		(net "SAS2X28_B_HDD8_RX_-")
	)
	(segment
		(start 35.2552 -167.6146)
		(end 37.3253 -165.5445)
		(width 0.1143)
		(layer "In2.Cu")
		(net "SAS2X28_B_HDD8_RX_-")
	)
	(segment
		(start 37.246306 -143.247618)
		(end 37.246306 -142.904718)
		(width 0.1143)
		(layer "In2.Cu")
		(net "SAS2X28_B_HDD8_RX_-")
	)
	(segment
		(start 37.058346 -141.091158)
		(end 37.058346 -140.748258)
		(width 0.1143)
		(layer "In2.Cu")
		(net "SAS2X28_B_HDD8_RX_-")
	)
	(segment
		(start 37.058346 -143.966438)
		(end 37.058346 -143.623538)
		(width 0.1143)
		(layer "In2.Cu")
		(net "SAS2X28_B_HDD8_RX_-")
	)
	(segment
		(start 37.058346 -149.429216)
		(end 37.058346 -149.086316)
		(width 0.1143)
		(layer "In2.Cu")
		(net "SAS2X28_B_HDD8_RX_-")
	)
	(segment
		(start 38.404546 -162.4203)
		(end 39.21379 -162.4203)
		(width 0.1143)
		(layer "In2.Cu")
		(net "SAS2X28_B_HDD8_RX_-")
	)
	(segment
		(start 37.058346 -147.991576)
		(end 37.058346 -147.648676)
		(width 0.1143)
		(layer "In2.Cu")
		(net "SAS2X28_B_HDD8_RX_-")
	)
	(segment
		(start 32.498792 -167.575992)
		(end 32.6136 -167.6908)
		(width 0.1143)
		(layer "In2.Cu")
		(net "SAS2X28_B_HDD8_RX_-")
	)
	(segment
		(start 37.246306 -151.7777)
		(end 37.246306 -149.805136)
		(width 0.1143)
		(layer "In2.Cu")
		(net "SAS2X28_B_HDD8_RX_-")
	)
	(segment
		(start 37.058346 -145.404078)
		(end 37.058346 -145.061178)
		(width 0.1143)
		(layer "In2.Cu")
		(net "SAS2X28_B_HDD8_RX_-")
	)
	(segment
		(start 40.080946 -161.553144)
		(end 40.080946 -155.491688)
		(width 0.1143)
		(layer "In2.Cu")
		(net "SAS2X28_B_HDD8_RX_-")
	)
	(segment
		(start 39.789354 -154.787092)
		(end 39.7891 -154.787346)
		(width 0.1143)
		(layer "In2.Cu")
		(net "SAS2X28_B_HDD8_RX_-")
	)
	(segment
		(start 32.81934 -165.40226)
		(end 32.4612 -165.7604)
		(width 0.1143)
		(layer "In2.Cu")
		(net "SAS2X28_B_HDD8_RX_-")
	)
	(segment
		(start 32.981646 -167.8432)
		(end 34.703258 -167.8432)
		(width 0.1143)
		(layer "In2.Cu")
		(net "SAS2X28_B_HDD8_RX_-")
	)
	(segment
		(start 33.0708 -164.464238)
		(end 33.0708 -164.7952)
		(width 0.1143)
		(layer "In2.Cu")
		(net "SAS2X28_B_HDD8_RX_-")
	)
	(segment
		(start 6.730746 -118.251986)
		(end 6.730746 -118.4275)
		(width 0.1143)
		(layer "In2.Cu")
		(net "SAS2X28_B_HDD8_RX_-")
	)
	(segment
		(start 37.660834 -164.734494)
		(end 37.660834 -163.164012)
		(width 0.1143)
		(layer "In2.Cu")
		(net "SAS2X28_B_HDD8_RX_-")
	)
	(segment
		(start 37.246306 -147.272756)
		(end 37.246306 -145.779998)
		(width 0.1143)
		(layer "In2.Cu")
		(net "SAS2X28_B_HDD8_RX_-")
	)
	(segment
		(start 16.40332 -118.131082)
		(end 7.659116 -118.131082)
		(width 0.1143)
		(layer "In2.Cu")
		(net "SAS2X28_B_HDD8_RX_-")
	)
	(segment
		(start 37.246306 -141.809978)
		(end 37.246306 -141.467078)
		(width 0.1143)
		(layer "In2.Cu")
		(net "SAS2X28_B_HDD8_RX_-")
	)
	(segment
		(start 32.2834 -166.18966)
		(end 32.2834 -167.0558)
		(width 0.1143)
		(layer "In2.Cu")
		(net "SAS2X28_B_HDD8_RX_-")
	)
	(segment
		(start 39.7891 -154.787346)
		(end 37.576252 -152.574244)
		(width 0.1143)
		(layer "In2.Cu")
		(net "SAS2X28_B_HDD8_RX_-")
	)
	(segment
		(start 37.058346 -142.528798)
		(end 37.058346 -142.185898)
		(width 0.1143)
		(layer "In2.Cu")
		(net "SAS2X28_B_HDD8_RX_-")
	)
	(arc
		(start 33.0708 -164.7952)
		(mid 33.005449 -165.123741)
		(end 32.81934 -165.40226)
		(width 0.1143)
		(layer "In2.Cu")
		(net "SAS2X28_B_HDD8_RX_-")
	)
	(arc
		(start 37.3253 -165.5445)
		(mid 37.573618 -165.172866)
		(end 37.660834 -164.734494)
		(width 0.1143)
		(layer "In2.Cu")
		(net "SAS2X28_B_HDD8_RX_-")
	)
	(arc
		(start 32.4612 -165.7604)
		(mid 32.329605 -165.957346)
		(end 32.2834 -166.18966)
		(width 0.1143)
		(layer "In2.Cu")
		(net "SAS2X28_B_HDD8_RX_-")
	)
	(arc
		(start 17.55013 -118.606062)
		(mid 17.023969 -118.254493)
		(end 16.40332 -118.131082)
		(width 0.1143)
		(layer "In2.Cu")
		(net "SAS2X28_B_HDD8_RX_-")
	)
	(arc
		(start 37.152326 -140.560298)
		(mid 37.221062 -140.477204)
		(end 37.246306 -140.372338)
		(width 0.1143)
		(layer "In2.Cu")
		(net "SAS2X28_B_HDD8_RX_-")
	)
	(arc
		(start 32.2834 -167.0558)
		(mid 32.339378 -167.33731)
		(end 32.498792 -167.575992)
		(width 0.1143)
		(layer "In2.Cu")
		(net "SAS2X28_B_HDD8_RX_-")
	)
	(arc
		(start 37.246306 -141.467078)
		(mid 37.221151 -141.362168)
		(end 37.152326 -141.279118)
		(width 0.1143)
		(layer "In2.Cu")
		(net "SAS2X28_B_HDD8_RX_-")
	)
	(arc
		(start 37.246306 -142.904718)
		(mid 37.221151 -142.799808)
		(end 37.152326 -142.716758)
		(width 0.1143)
		(layer "In2.Cu")
		(net "SAS2X28_B_HDD8_RX_-")
	)
	(arc
		(start 37.152326 -149.617176)
		(mid 37.083501 -149.534101)
		(end 37.058346 -149.429216)
		(width 0.1143)
		(layer "In2.Cu")
		(net "SAS2X28_B_HDD8_RX_-")
	)
	(arc
		(start 37.152326 -144.873218)
		(mid 37.221062 -144.790124)
		(end 37.246306 -144.685258)
		(width 0.1143)
		(layer "In2.Cu")
		(net "SAS2X28_B_HDD8_RX_-")
	)
	(arc
		(start 37.246306 -149.805136)
		(mid 37.221151 -149.700226)
		(end 37.152326 -149.617176)
		(width 0.1143)
		(layer "In2.Cu")
		(net "SAS2X28_B_HDD8_RX_-")
	)
	(arc
		(start 37.152326 -141.997938)
		(mid 37.221151 -141.914863)
		(end 37.246306 -141.809978)
		(width 0.1143)
		(layer "In2.Cu")
		(net "SAS2X28_B_HDD8_RX_-")
	)
	(arc
		(start 33.3756 -163.7284)
		(mid 33.150019 -164.066005)
		(end 33.0708 -164.464238)
		(width 0.1143)
		(layer "In2.Cu")
		(net "SAS2X28_B_HDD8_RX_-")
	)
	(arc
		(start 37.246306 -138.7221)
		(mid 37.16902 -138.334028)
		(end 36.949126 -138.005058)
		(width 0.1143)
		(layer "In2.Cu")
		(net "SAS2X28_B_HDD8_RX_-")
	)
	(arc
		(start 34.703258 -167.8432)
		(mid 35.001958 -167.783785)
		(end 35.2552 -167.6146)
		(width 0.1143)
		(layer "In2.Cu")
		(net "SAS2X28_B_HDD8_RX_-")
	)
	(arc
		(start 37.152326 -148.179536)
		(mid 37.083501 -148.096461)
		(end 37.058346 -147.991576)
		(width 0.1143)
		(layer "In2.Cu")
		(net "SAS2X28_B_HDD8_RX_-")
	)
	(arc
		(start 37.660834 -163.164012)
		(mid 37.878662 -162.638128)
		(end 38.404546 -162.4203)
		(width 0.1143)
		(layer "In2.Cu")
		(net "SAS2X28_B_HDD8_RX_-")
	)
	(arc
		(start 37.058346 -147.648676)
		(mid 37.083501 -147.543766)
		(end 37.152326 -147.460716)
		(width 0.1143)
		(layer "In2.Cu")
		(net "SAS2X28_B_HDD8_RX_-")
	)
	(arc
		(start 37.152326 -145.592038)
		(mid 37.08359 -145.508944)
		(end 37.058346 -145.404078)
		(width 0.1143)
		(layer "In2.Cu")
		(net "SAS2X28_B_HDD8_RX_-")
	)
	(arc
		(start 37.152326 -148.898356)
		(mid 37.221151 -148.815281)
		(end 37.246306 -148.710396)
		(width 0.1143)
		(layer "In2.Cu")
		(net "SAS2X28_B_HDD8_RX_-")
	)
	(arc
		(start 37.058346 -140.748258)
		(mid 37.083501 -140.643348)
		(end 37.152326 -140.560298)
		(width 0.1143)
		(layer "In2.Cu")
		(net "SAS2X28_B_HDD8_RX_-")
	)
	(arc
		(start 37.058346 -143.623538)
		(mid 37.083501 -143.518628)
		(end 37.152326 -143.435578)
		(width 0.1143)
		(layer "In2.Cu")
		(net "SAS2X28_B_HDD8_RX_-")
	)
	(arc
		(start 7.659116 -118.131082)
		(mid 7.484542 -118.096357)
		(end 7.336536 -117.997478)
		(width 0.1143)
		(layer "In2.Cu")
		(net "SAS2X28_B_HDD8_RX_-")
	)
	(arc
		(start 39.21379 -162.4203)
		(mid 39.545636 -162.354292)
		(end 39.826946 -162.1663)
		(width 0.1143)
		(layer "In2.Cu")
		(net "SAS2X28_B_HDD8_RX_-")
	)
	(arc
		(start 37.152326 -142.716758)
		(mid 37.083501 -142.633683)
		(end 37.058346 -142.528798)
		(width 0.1143)
		(layer "In2.Cu")
		(net "SAS2X28_B_HDD8_RX_-")
	)
	(arc
		(start 40.080946 -155.491688)
		(mid 40.005267 -155.11037)
		(end 39.789354 -154.787092)
		(width 0.1143)
		(layer "In2.Cu")
		(net "SAS2X28_B_HDD8_RX_-")
	)
	(arc
		(start 37.058346 -142.185898)
		(mid 37.083501 -142.080988)
		(end 37.152326 -141.997938)
		(width 0.1143)
		(layer "In2.Cu")
		(net "SAS2X28_B_HDD8_RX_-")
	)
	(arc
		(start 37.152326 -147.460716)
		(mid 37.221151 -147.377641)
		(end 37.246306 -147.272756)
		(width 0.1143)
		(layer "In2.Cu")
		(net "SAS2X28_B_HDD8_RX_-")
	)
	(arc
		(start 37.576252 -152.574244)
		(mid 37.332144 -152.208771)
		(end 37.24656 -151.7777)
		(width 0.1143)
		(layer "In2.Cu")
		(net "SAS2X28_B_HDD8_RX_-")
	)
	(arc
		(start 6.836156 -117.997478)
		(mid 6.758133 -118.114247)
		(end 6.730746 -118.251986)
		(width 0.1143)
		(layer "In2.Cu")
		(net "SAS2X28_B_HDD8_RX_-")
	)
	(arc
		(start 37.058346 -149.086316)
		(mid 37.083501 -148.981406)
		(end 37.152326 -148.898356)
		(width 0.1143)
		(layer "In2.Cu")
		(net "SAS2X28_B_HDD8_RX_-")
	)
	(arc
		(start 37.246306 -148.367496)
		(mid 37.221151 -148.262586)
		(end 37.152326 -148.179536)
		(width 0.1143)
		(layer "In2.Cu")
		(net "SAS2X28_B_HDD8_RX_-")
	)
	(arc
		(start 37.152326 -143.435578)
		(mid 37.221151 -143.352503)
		(end 37.246306 -143.247618)
		(width 0.1143)
		(layer "In2.Cu")
		(net "SAS2X28_B_HDD8_RX_-")
	)
	(arc
		(start 7.336536 -117.997478)
		(mid 7.086346 -117.893846)
		(end 6.836156 -117.997478)
		(width 0.1143)
		(layer "In2.Cu")
		(net "SAS2X28_B_HDD8_RX_-")
	)
	(arc
		(start 37.152326 -144.154398)
		(mid 37.083501 -144.071323)
		(end 37.058346 -143.966438)
		(width 0.1143)
		(layer "In2.Cu")
		(net "SAS2X28_B_HDD8_RX_-")
	)
	(arc
		(start 37.152326 -141.279118)
		(mid 37.08359 -141.196024)
		(end 37.058346 -141.091158)
		(width 0.1143)
		(layer "In2.Cu")
		(net "SAS2X28_B_HDD8_RX_-")
	)
	(arc
		(start 37.058346 -145.061178)
		(mid 37.083501 -144.956268)
		(end 37.152326 -144.873218)
		(width 0.1143)
		(layer "In2.Cu")
		(net "SAS2X28_B_HDD8_RX_-")
	)
	(arc
		(start 37.246306 -144.342358)
		(mid 37.221151 -144.237448)
		(end 37.152326 -144.154398)
		(width 0.1143)
		(layer "In2.Cu")
		(net "SAS2X28_B_HDD8_RX_-")
	)
	(arc
		(start 39.826946 -162.1663)
		(mid 40.014917 -161.884982)
		(end 40.080946 -161.553144)
		(width 0.1143)
		(layer "In2.Cu")
		(net "SAS2X28_B_HDD8_RX_-")
	)
	(arc
		(start 32.6136 -167.6908)
		(mid 32.782461 -167.803629)
		(end 32.981646 -167.8432)
		(width 0.1143)
		(layer "In2.Cu")
		(net "SAS2X28_B_HDD8_RX_-")
	)
	(arc
		(start 37.246306 -145.779998)
		(mid 37.221151 -145.675088)
		(end 37.152326 -145.592038)
		(width 0.1143)
		(layer "In2.Cu")
		(net "SAS2X28_B_HDD8_RX_-")
	)
	(via
		(at 36.5506 -320.7004)
		(size 0.7112)
		(drill 0.3556)
		(layers "F.Cu" "B.Cu")
		(net "P12V_HDD11")
	)
	(via
		(at 44.068746 -309.1307)
		(size 0.7112)
		(drill 0.3556)
		(layers "F.Cu" "B.Cu")
		(net "P12V_HDD11")
	)
	(segment
		(start 32.22625 -164.827458)
		(end 32.225996 -164.82695)
		(width 0.09525)
		(layer "F.Cu")
		(net "SAS2X28_B_HDD8_RX_+")
	)
	(segment
		(start 33.448752 -167.14851)
		(end 33.314894 -167.014906)
		(width 0.09525)
		(layer "F.Cu")
		(net "SAS2X28_B_HDD8_RX_+")
	)
	(segment
		(start 32.606996 -164.06495)
		(end 32.511746 -163.9697)
		(width 0.09525)
		(layer "F.Cu")
		(net "SAS2X28_B_HDD8_RX_+")
	)
	(segment
		(start 32.892746 -166.8399)
		(end 32.707834 -166.8399)
		(width 0.09525)
		(layer "F.Cu")
		(net "SAS2X28_B_HDD8_RX_+")
	)
	(segment
		(start 32.225996 -164.82695)
		(end 32.606996 -164.44595)
		(width 0.09525)
		(layer "F.Cu")
		(net "SAS2X28_B_HDD8_RX_+")
	)
	(segment
		(start 31.876746 -165.937946)
		(end 31.876746 -165.6207)
		(width 0.09525)
		(layer "F.Cu")
		(net "SAS2X28_B_HDD8_RX_+")
	)
	(segment
		(start 32.155892 -166.6113)
		(end 32.155638 -166.6113)
		(width 0.09525)
		(layer "F.Cu")
		(net "SAS2X28_B_HDD8_RX_+")
	)
	(segment
		(start 32.19069 -164.863018)
		(end 32.22625 -164.827458)
		(width 0.09525)
		(layer "F.Cu")
		(net "SAS2X28_B_HDD8_RX_+")
	)
	(via
		(at 6.727444 -117.512592)
		(size 0.5588)
		(drill 0.3048)
		(layers "F.Cu" "B.Cu")
		(net "SAS2X28_B_HDD8_RX_+")
	)
	(via
		(at 32.511746 -163.9697)
		(size 0.5588)
		(drill 0.3048)
		(layers "F.Cu" "B.Cu")
		(net "SAS2X28_B_HDD8_RX_+")
	)
	(arc
		(start 32.155638 -166.6113)
		(mid 31.949237 -166.302349)
		(end 31.876746 -165.937946)
		(width 0.09525)
		(layer "F.Cu")
		(net "SAS2X28_B_HDD8_RX_+")
	)
	(arc
		(start 32.662114 -164.365432)
		(mid 32.662241 -164.365051)
		(end 32.662368 -164.36467)
		(width 0.09525)
		(layer "F.Cu")
		(net "SAS2X28_B_HDD8_RX_+")
	)
	(arc
		(start 32.707834 -166.8399)
		(mid 32.409094 -166.780553)
		(end 32.155892 -166.6113)
		(width 0.09525)
		(layer "F.Cu")
		(net "SAS2X28_B_HDD8_RX_+")
	)
	(arc
		(start 32.675322 -164.329872)
		(mid 32.685789 -164.262157)
		(end 32.678878 -164.193982)
		(width 0.09525)
		(layer "F.Cu")
		(net "SAS2X28_B_HDD8_RX_+")
	)
	(arc
		(start 32.606996 -164.44595)
		(mid 32.638215 -164.408198)
		(end 32.662114 -164.365432)
		(width 0.09525)
		(layer "F.Cu")
		(net "SAS2X28_B_HDD8_RX_+")
	)
	(arc
		(start 32.662368 -164.36467)
		(mid 32.669442 -164.347494)
		(end 32.675322 -164.329872)
		(width 0.09525)
		(layer "F.Cu")
		(net "SAS2X28_B_HDD8_RX_+")
	)
	(arc
		(start 31.876746 -165.6207)
		(mid 31.958334 -165.210621)
		(end 32.19069 -164.863018)
		(width 0.09525)
		(layer "F.Cu")
		(net "SAS2X28_B_HDD8_RX_+")
	)
	(arc
		(start 32.678878 -164.193982)
		(mid 32.651983 -164.124421)
		(end 32.606996 -164.06495)
		(width 0.09525)
		(layer "F.Cu")
		(net "SAS2X28_B_HDD8_RX_+")
	)
	(arc
		(start 33.314894 -167.014906)
		(mid 33.121226 -166.885408)
		(end 32.892746 -166.8399)
		(width 0.09525)
		(layer "F.Cu")
		(net "SAS2X28_B_HDD8_RX_+")
	)
	(segment
		(start 4.9276 -117.5004)
		(end 4.926076 -117.498876)
		(width 0.09525)
		(layer "B.Cu")
		(net "SAS2X28_B_HDD8_RX_+")
	)
	(segment
		(start 4.926076 -117.498876)
		(end 2.811526 -117.498876)
		(width 0.09525)
		(layer "B.Cu")
		(net "SAS2X28_B_HDD8_RX_+")
	)
	(segment
		(start 5.241036 -117.738144)
		(end 5.056632 -117.553994)
		(width 0.09525)
		(layer "B.Cu")
		(net "SAS2X28_B_HDD8_RX_+")
	)
	(segment
		(start 6.727444 -117.512592)
		(end 6.666992 -117.57279)
		(width 0.09525)
		(layer "B.Cu")
		(net "SAS2X28_B_HDD8_RX_+")
	)
	(segment
		(start 6.044946 -117.8306)
		(end 5.464302 -117.8306)
		(width 0.09525)
		(layer "B.Cu")
		(net "SAS2X28_B_HDD8_RX_+")
	)
	(arc
		(start 5.056632 -117.553994)
		(mid 4.997447 -117.514355)
		(end 4.9276 -117.5004)
		(width 0.09525)
		(layer "B.Cu")
		(net "SAS2X28_B_HDD8_RX_+")
	)
	(arc
		(start 5.464302 -117.8306)
		(mid 5.34348 -117.806567)
		(end 5.241036 -117.738144)
		(width 0.09525)
		(layer "B.Cu")
		(net "SAS2X28_B_HDD8_RX_+")
	)
	(arc
		(start 6.666992 -117.57279)
		(mid 6.38161 -117.763569)
		(end 6.044946 -117.8306)
		(width 0.09525)
		(layer "B.Cu")
		(net "SAS2X28_B_HDD8_RX_+")
	)
	(segment
		(start 32.397954 -167.906446)
		(end 32.398208 -167.906192)
		(width 0.1143)
		(layer "In2.Cu")
		(net "SAS2X28_B_HDD8_RX_+")
	)
	(segment
		(start 40.004746 -154.5717)
		(end 37.791898 -152.358598)
		(width 0.1143)
		(layer "In2.Cu")
		(net "SAS2X28_B_HDD8_RX_+")
	)
	(segment
		(start 32.766 -164.583618)
		(end 32.766 -164.794946)
		(width 0.1143)
		(layer "In2.Cu")
		(net "SAS2X28_B_HDD8_RX_+")
	)
	(segment
		(start 32.283146 -167.791638)
		(end 32.397954 -167.906446)
		(width 0.1143)
		(layer "In2.Cu")
		(net "SAS2X28_B_HDD8_RX_+")
	)
	(segment
		(start 31.9786 -166.18966)
		(end 31.9786 -167.055546)
		(width 0.1143)
		(layer "In2.Cu")
		(net "SAS2X28_B_HDD8_RX_+")
	)
	(segment
		(start 37.551106 -151.7777)
		(end 37.551106 -138.721846)
		(width 0.1143)
		(layer "In2.Cu")
		(net "SAS2X28_B_HDD8_RX_+")
	)
	(segment
		(start 7.071614 -117.588792)
		(end 6.92531 -117.592094)
		(width 0.1143)
		(layer "In2.Cu")
		(net "SAS2X28_B_HDD8_RX_+")
	)
	(segment
		(start 38.404546 -162.7251)
		(end 39.214044 -162.7251)
		(width 0.1143)
		(layer "In2.Cu")
		(net "SAS2X28_B_HDD8_RX_+")
	)
	(segment
		(start 35.470592 -167.829992)
		(end 35.470846 -167.830246)
		(width 0.1143)
		(layer "In2.Cu")
		(net "SAS2X28_B_HDD8_RX_+")
	)
	(segment
		(start 37.164772 -137.789412)
		(end 17.765776 -118.390416)
		(width 0.1143)
		(layer "In2.Cu")
		(net "SAS2X28_B_HDD8_RX_+")
	)
	(segment
		(start 37.540946 -165.760146)
		(end 37.540692 -165.759892)
		(width 0.1143)
		(layer "In2.Cu")
		(net "SAS2X28_B_HDD8_RX_+")
	)
	(segment
		(start 35.470846 -167.830246)
		(end 37.540946 -165.760146)
		(width 0.1143)
		(layer "In2.Cu")
		(net "SAS2X28_B_HDD8_RX_+")
	)
	(segment
		(start 37.965634 -164.734748)
		(end 37.965634 -163.164012)
		(width 0.1143)
		(layer "In2.Cu")
		(net "SAS2X28_B_HDD8_RX_+")
	)
	(segment
		(start 40.385746 -161.553398)
		(end 40.385746 -155.491434)
		(width 0.1143)
		(layer "In2.Cu")
		(net "SAS2X28_B_HDD8_RX_+")
	)
	(segment
		(start 32.603694 -165.186614)
		(end 32.245554 -165.544754)
		(width 0.1143)
		(layer "In2.Cu")
		(net "SAS2X28_B_HDD8_RX_+")
	)
	(segment
		(start 32.9819 -168.148)
		(end 34.703004 -168.148)
		(width 0.1143)
		(layer "In2.Cu")
		(net "SAS2X28_B_HDD8_RX_+")
	)
	(segment
		(start 16.403828 -117.826282)
		(end 7.658862 -117.826282)
		(width 0.1143)
		(layer "In2.Cu")
		(net "SAS2X28_B_HDD8_RX_+")
	)
	(arc
		(start 32.511746 -163.9697)
		(mid 32.699951 -164.251368)
		(end 32.766 -164.583618)
		(width 0.1143)
		(layer "In2.Cu")
		(net "SAS2X28_B_HDD8_RX_+")
	)
	(arc
		(start 7.658862 -117.826282)
		(mid 7.60112 -117.814627)
		(end 7.552182 -117.781832)
		(width 0.1143)
		(layer "In2.Cu")
		(net "SAS2X28_B_HDD8_RX_+")
	)
	(arc
		(start 32.766 -164.794946)
		(mid 32.723816 -165.006928)
		(end 32.603694 -165.186614)
		(width 0.1143)
		(layer "In2.Cu")
		(net "SAS2X28_B_HDD8_RX_+")
	)
	(arc
		(start 34.703004 -168.148)
		(mid 35.118429 -168.065349)
		(end 35.470592 -167.829992)
		(width 0.1143)
		(layer "In2.Cu")
		(net "SAS2X28_B_HDD8_RX_+")
	)
	(arc
		(start 7.552182 -117.781832)
		(mid 7.331664 -117.636103)
		(end 7.071614 -117.588792)
		(width 0.1143)
		(layer "In2.Cu")
		(net "SAS2X28_B_HDD8_RX_+")
	)
	(arc
		(start 6.92531 -117.592094)
		(mid 6.818254 -117.572573)
		(end 6.727444 -117.512592)
		(width 0.1143)
		(layer "In2.Cu")
		(net "SAS2X28_B_HDD8_RX_+")
	)
	(arc
		(start 17.765776 -118.390416)
		(mid 17.140909 -117.972893)
		(end 16.403828 -117.826282)
		(width 0.1143)
		(layer "In2.Cu")
		(net "SAS2X28_B_HDD8_RX_+")
	)
	(arc
		(start 37.965634 -163.164012)
		(mid 38.094188 -162.853654)
		(end 38.404546 -162.7251)
		(width 0.1143)
		(layer "In2.Cu")
		(net "SAS2X28_B_HDD8_RX_+")
	)
	(arc
		(start 40.042592 -162.381946)
		(mid 40.29654 -162.001791)
		(end 40.385746 -161.553398)
		(width 0.1143)
		(layer "In2.Cu")
		(net "SAS2X28_B_HDD8_RX_+")
	)
	(arc
		(start 40.385746 -155.491434)
		(mid 40.286734 -154.993665)
		(end 40.004746 -154.5717)
		(width 0.1143)
		(layer "In2.Cu")
		(net "SAS2X28_B_HDD8_RX_+")
	)
	(arc
		(start 37.551106 -138.721846)
		(mid 37.450653 -138.217215)
		(end 37.164772 -137.789412)
		(width 0.1143)
		(layer "In2.Cu")
		(net "SAS2X28_B_HDD8_RX_+")
	)
	(arc
		(start 37.791898 -152.358598)
		(mid 37.613733 -152.092095)
		(end 37.551106 -151.7777)
		(width 0.1143)
		(layer "In2.Cu")
		(net "SAS2X28_B_HDD8_RX_+")
	)
	(arc
		(start 31.9786 -167.055546)
		(mid 32.057648 -167.453888)
		(end 32.283146 -167.791638)
		(width 0.1143)
		(layer "In2.Cu")
		(net "SAS2X28_B_HDD8_RX_+")
	)
	(arc
		(start 32.245554 -165.544754)
		(mid 32.047933 -165.840654)
		(end 31.9786 -166.18966)
		(width 0.1143)
		(layer "In2.Cu")
		(net "SAS2X28_B_HDD8_RX_+")
	)
	(arc
		(start 37.540692 -165.759892)
		(mid 37.855075 -165.289568)
		(end 37.965634 -164.734748)
		(width 0.1143)
		(layer "In2.Cu")
		(net "SAS2X28_B_HDD8_RX_+")
	)
	(arc
		(start 32.398208 -167.906192)
		(mid 32.665994 -168.085184)
		(end 32.9819 -168.148)
		(width 0.1143)
		(layer "In2.Cu")
		(net "SAS2X28_B_HDD8_RX_+")
	)
	(arc
		(start 39.214044 -162.7251)
		(mid 39.662449 -162.635925)
		(end 40.042592 -162.381946)
		(width 0.1143)
		(layer "In2.Cu")
		(net "SAS2X28_B_HDD8_RX_+")
	)
	(segment
		(start 31.897066 -184.90438)
		(end 30.310836 -183.318404)
		(width 0.09525)
		(layer "F.Cu")
		(net "SAS2X28_A_HDD8_RX_-")
	)
	(segment
		(start 15.683738 -357.20274)
		(end 15.683738 -277.507446)
		(width 0.09525)
		(layer "F.Cu")
		(net "SAS2X28_A_HDD8_RX_-")
	)
	(segment
		(start 16.177006 -276.316186)
		(end 17.017746 -275.4757)
		(width 0.09525)
		(layer "F.Cu")
		(net "SAS2X28_A_HDD8_RX_-")
	)
	(segment
		(start 7.716012 -371.479572)
		(end 7.72795 -371.479572)
		(width 0.09525)
		(layer "F.Cu")
		(net "SAS2X28_A_HDD8_RX_-")
	)
	(segment
		(start 30.15361 -161.103564)
		(end 30.15361 -161.10331)
		(width 0.09525)
		(layer "F.Cu")
		(net "SAS2X28_A_HDD8_RX_-")
	)
	(segment
		(start 29.819346 -182.130446)
		(end 29.819346 -161.910014)
		(width 0.09525)
		(layer "F.Cu")
		(net "SAS2X28_A_HDD8_RX_-")
	)
	(segment
		(start 30.153356 -161.103056)
		(end 30.597856 -160.658556)
		(width 0.09525)
		(layer "F.Cu")
		(net "SAS2X28_A_HDD8_RX_-")
	)
	(segment
		(start 30.597856 -160.658556)
		(end 30.59811 -160.65881)
		(width 0.09525)
		(layer "F.Cu")
		(net "SAS2X28_A_HDD8_RX_-")
	)
	(segment
		(start 17.017746 -275.4757)
		(end 35.877246 -256.6162)
		(width 0.09525)
		(layer "F.Cu")
		(net "SAS2X28_A_HDD8_RX_-")
	)
	(segment
		(start 36.474146 -190.627508)
		(end 36.4744 -190.627254)
		(width 0.09525)
		(layer "F.Cu")
		(net "SAS2X28_A_HDD8_RX_-")
	)
	(segment
		(start 36.4744 -190.627254)
		(end 36.4744 -189.985396)
		(width 0.09525)
		(layer "F.Cu")
		(net "SAS2X28_A_HDD8_RX_-")
	)
	(segment
		(start 36.474146 -255.175258)
		(end 36.474146 -190.627508)
		(width 0.09525)
		(layer "F.Cu")
		(net "SAS2X28_A_HDD8_RX_-")
	)
	(segment
		(start 14.150848 -359.155238)
		(end 15.387066 -357.91902)
		(width 0.09525)
		(layer "F.Cu")
		(net "SAS2X28_A_HDD8_RX_-")
	)
	(segment
		(start 30.15361 -161.10331)
		(end 30.153356 -161.103056)
		(width 0.09525)
		(layer "F.Cu")
		(net "SAS2X28_A_HDD8_RX_-")
	)
	(segment
		(start 36.117784 -189.125098)
		(end 31.897066 -184.90438)
		(width 0.09525)
		(layer "F.Cu")
		(net "SAS2X28_A_HDD8_RX_-")
	)
	(segment
		(start 30.59811 -160.65881)
		(end 30.59811 -160.659064)
		(width 0.09525)
		(layer "F.Cu")
		(net "SAS2X28_A_HDD8_RX_-")
	)
	(segment
		(start 31.44139 -160.30956)
		(end 32.789622 -160.30956)
		(width 0.09525)
		(layer "F.Cu")
		(net "SAS2X28_A_HDD8_RX_-")
	)
	(segment
		(start 13.745464 -365.198406)
		(end 13.745464 -360.131106)
		(width 0.09525)
		(layer "F.Cu")
		(net "SAS2X28_A_HDD8_RX_-")
	)
	(segment
		(start 7.72795 -371.479572)
		(end 13.559028 -365.648494)
		(width 0.09525)
		(layer "F.Cu")
		(net "SAS2X28_A_HDD8_RX_-")
	)
	(via
		(at 7.716012 -371.479572)
		(size 0.5588)
		(drill 0.3048)
		(layers "F.Cu" "B.Cu")
		(net "SAS2X28_A_HDD8_RX_-")
	)
	(arc
		(start 32.789622 -160.30956)
		(mid 33.146352 -160.238602)
		(end 33.448752 -160.03651)
		(width 0.09525)
		(layer "F.Cu")
		(net "SAS2X28_A_HDD8_RX_-")
	)
	(arc
		(start 35.877246 -256.6162)
		(mid 36.318985 -255.95509)
		(end 36.474146 -255.175258)
		(width 0.09525)
		(layer "F.Cu")
		(net "SAS2X28_A_HDD8_RX_-")
	)
	(arc
		(start 15.683738 -277.507446)
		(mid 15.811882 -276.862751)
		(end 16.177006 -276.316186)
		(width 0.09525)
		(layer "F.Cu")
		(net "SAS2X28_A_HDD8_RX_-")
	)
	(arc
		(start 29.819346 -161.910014)
		(mid 29.906329 -161.473575)
		(end 30.15361 -161.103564)
		(width 0.09525)
		(layer "F.Cu")
		(net "SAS2X28_A_HDD8_RX_-")
	)
	(arc
		(start 30.59811 -160.659064)
		(mid 30.984994 -160.400433)
		(end 31.44139 -160.30956)
		(width 0.09525)
		(layer "F.Cu")
		(net "SAS2X28_A_HDD8_RX_-")
	)
	(arc
		(start 36.4744 -189.985396)
		(mid 36.381685 -189.519757)
		(end 36.117784 -189.125098)
		(width 0.09525)
		(layer "F.Cu")
		(net "SAS2X28_A_HDD8_RX_-")
	)
	(arc
		(start 15.387066 -357.91902)
		(mid 15.606651 -357.590388)
		(end 15.683738 -357.20274)
		(width 0.09525)
		(layer "F.Cu")
		(net "SAS2X28_A_HDD8_RX_-")
	)
	(arc
		(start 30.310836 -183.318404)
		(mid 29.946901 -182.773319)
		(end 29.819346 -182.130446)
		(width 0.09525)
		(layer "F.Cu")
		(net "SAS2X28_A_HDD8_RX_-")
	)
	(arc
		(start 13.559028 -365.648494)
		(mid 13.697008 -365.441992)
		(end 13.745464 -365.198406)
		(width 0.09525)
		(layer "F.Cu")
		(net "SAS2X28_A_HDD8_RX_-")
	)
	(arc
		(start 13.745464 -360.131106)
		(mid 13.828338 -359.660381)
		(end 14.067282 -359.246424)
		(width 0.09525)
		(layer "F.Cu")
		(net "SAS2X28_A_HDD8_RX_-")
	)
	(arc
		(start 14.067282 -359.246424)
		(mid 14.108068 -359.199917)
		(end 14.150848 -359.155238)
		(width 0.09525)
		(layer "F.Cu")
		(net "SAS2X28_A_HDD8_RX_-")
	)
	(segment
		(start 6.519418 -368.441224)
		(end 6.42366 -368.345212)
		(width 0.09525)
		(layer "B.Cu")
		(net "SAS2X28_A_HDD8_RX_-")
	)
	(segment
		(start 7.873746 -371.098826)
		(end 7.873746 -370.3447)
		(width 0.09525)
		(layer "B.Cu")
		(net "SAS2X28_A_HDD8_RX_-")
	)
	(segment
		(start 5.978144 -368.160808)
		(end 5.700522 -368.160808)
		(width 0.09525)
		(layer "B.Cu")
		(net "SAS2X28_A_HDD8_RX_-")
	)
	(segment
		(start 4.88061 -368.500406)
		(end 4.879086 -368.498882)
		(width 0.09525)
		(layer "B.Cu")
		(net "SAS2X28_A_HDD8_RX_-")
	)
	(segment
		(start 4.879086 -368.498882)
		(end 2.811526 -368.498882)
		(width 0.09525)
		(layer "B.Cu")
		(net "SAS2X28_A_HDD8_RX_-")
	)
	(segment
		(start 6.687566 -368.609626)
		(end 6.519418 -368.441224)
		(width 0.09525)
		(layer "B.Cu")
		(net "SAS2X28_A_HDD8_RX_-")
	)
	(segment
		(start 7.485634 -369.407694)
		(end 6.687566 -368.609626)
		(width 0.09525)
		(layer "B.Cu")
		(net "SAS2X28_A_HDD8_RX_-")
	)
	(arc
		(start 7.716012 -371.479572)
		(mid 7.81675 -371.339628)
		(end 7.868158 -371.175026)
		(width 0.09525)
		(layer "B.Cu")
		(net "SAS2X28_A_HDD8_RX_-")
	)
	(arc
		(start 6.42366 -368.345212)
		(mid 6.219241 -368.208687)
		(end 5.978144 -368.160808)
		(width 0.09525)
		(layer "B.Cu")
		(net "SAS2X28_A_HDD8_RX_-")
	)
	(arc
		(start 5.632196 -368.165126)
		(mid 5.470823 -368.214336)
		(end 5.333746 -368.3127)
		(width 0.09525)
		(layer "B.Cu")
		(net "SAS2X28_A_HDD8_RX_-")
	)
	(arc
		(start 7.868158 -371.175026)
		(mid 7.872311 -371.137025)
		(end 7.873746 -371.098826)
		(width 0.09525)
		(layer "B.Cu")
		(net "SAS2X28_A_HDD8_RX_-")
	)
	(arc
		(start 5.700522 -368.160808)
		(mid 5.666288 -368.161838)
		(end 5.632196 -368.165126)
		(width 0.09525)
		(layer "B.Cu")
		(net "SAS2X28_A_HDD8_RX_-")
	)
	(arc
		(start 7.873746 -370.3447)
		(mid 7.772877 -369.837599)
		(end 7.485634 -369.407694)
		(width 0.09525)
		(layer "B.Cu")
		(net "SAS2X28_A_HDD8_RX_-")
	)
	(arc
		(start 5.333746 -368.3127)
		(mid 5.125845 -368.451615)
		(end 4.88061 -368.500406)
		(width 0.09525)
		(layer "B.Cu")
		(net "SAS2X28_A_HDD8_RX_-")
	)
	(segment
		(start 26.796746 -305.273202)
		(end 25.574244 -305.273202)
		(width 0.111252)
		(layer "F.Cu")
		(net "SAS_EXP_B_PWR11")
	)
	(segment
		(start 26.965148 -306.248308)
		(end 27.162506 -306.445666)
		(width 0.111252)
		(layer "F.Cu")
		(net "SAS_EXP_B_PWR11")
	)
	(segment
		(start 3.193542 -213.501478)
		(end 3.19024 -213.50478)
		(width 0.111252)
		(layer "F.Cu")
		(net "SAS_EXP_B_PWR11")
	)
	(segment
		(start 25.399746 -305.9557)
		(end 25.653746 -306.2097)
		(width 0.111252)
		(layer "F.Cu")
		(net "SAS_EXP_B_PWR11")
	)
	(segment
		(start 6.148324 -213.501478)
		(end 3.193542 -213.501478)
		(width 0.111252)
		(layer "F.Cu")
		(net "SAS_EXP_B_PWR11")
	)
	(segment
		(start 25.399746 -305.4477)
		(end 25.399746 -305.9557)
		(width 0.111252)
		(layer "F.Cu")
		(net "SAS_EXP_B_PWR11")
	)
	(segment
		(start 26.92654 -306.2097)
		(end 26.965148 -306.248308)
		(width 0.111252)
		(layer "F.Cu")
		(net "SAS_EXP_B_PWR11")
	)
	(segment
		(start 12.279884 -214.510366)
		(end 7.157212 -214.510366)
		(width 0.111252)
		(layer "F.Cu")
		(net "SAS_EXP_B_PWR11")
	)
	(segment
		(start 7.157212 -214.510366)
		(end 6.148324 -213.501478)
		(width 0.111252)
		(layer "F.Cu")
		(net "SAS_EXP_B_PWR11")
	)
	(segment
		(start 25.653746 -306.2097)
		(end 26.92654 -306.2097)
		(width 0.111252)
		(layer "F.Cu")
		(net "SAS_EXP_B_PWR11")
	)
	(segment
		(start 25.574244 -305.273202)
		(end 25.399746 -305.4477)
		(width 0.111252)
		(layer "F.Cu")
		(net "SAS_EXP_B_PWR11")
	)
	(segment
		(start 27.162506 -306.445666)
		(end 27.162506 -307.432202)
		(width 0.111252)
		(layer "F.Cu")
		(net "SAS_EXP_B_PWR11")
	)
	(via
		(at 25.399746 -305.4477)
		(size 0.7112)
		(drill 0.3556)
		(layers "F.Cu" "B.Cu")
		(net "SAS_EXP_B_PWR11")
	)
	(via
		(at 26.965148 -306.248308)
		(size 0.5588)
		(drill 0.3048)
		(layers "F.Cu" "B.Cu")
		(net "SAS_EXP_B_PWR11")
	)
	(via
		(at 12.279884 -214.510366)
		(size 0.5588)
		(drill 0.3048)
		(layers "F.Cu" "B.Cu")
		(net "SAS_EXP_B_PWR11")
	)
	(segment
		(start 14.515592 -263.36244)
		(end 14.515846 -263.362186)
		(width 0.14605)
		(layer "In5.Cu")
		(net "SAS_EXP_B_PWR11")
	)
	(segment
		(start 14.515846 -264.109962)
		(end 14.515592 -264.109708)
		(width 0.14605)
		(layer "In5.Cu")
		(net "SAS_EXP_B_PWR11")
	)
	(segment
		(start 26.965148 -306.248308)
		(end 14.515846 -293.799006)
		(width 0.14605)
		(layer "In5.Cu")
		(net "SAS_EXP_B_PWR11")
	)
	(segment
		(start 14.515846 -216.746328)
		(end 12.279884 -214.510366)
		(width 0.14605)
		(layer "In5.Cu")
		(net "SAS_EXP_B_PWR11")
	)
	(segment
		(start 14.515846 -293.799006)
		(end 14.515846 -264.109962)
		(width 0.14605)
		(layer "In5.Cu")
		(net "SAS_EXP_B_PWR11")
	)
	(segment
		(start 14.515846 -263.362186)
		(end 14.515846 -216.746328)
		(width 0.14605)
		(layer "In5.Cu")
		(net "SAS_EXP_B_PWR11")
	)
	(segment
		(start 14.515592 -264.109708)
		(end 14.515592 -263.36244)
		(width 0.14605)
		(layer "In5.Cu")
		(net "SAS_EXP_B_PWR11")
	)
	(segment
		(start 12.700762 -365.60379)
		(end 12.615672 -365.688626)
		(width 0.09525)
		(layer "F.Cu")
		(net "SAS2X28_A_HDD8_TX_-")
	)
	(segment
		(start 35.121596 -256.441956)
		(end 16.997172 -274.56638)
		(width 0.09525)
		(layer "F.Cu")
		(net "SAS2X28_A_HDD8_TX_-")
	)
	(segment
		(start 38.250114 -157.340046)
		(end 38.245034 -157.334966)
		(width 0.09525)
		(layer "F.Cu")
		(net "SAS2X28_A_HDD8_TX_-")
	)
	(segment
		(start 14.53388 -357.77678)
		(end 14.534134 -357.777034)
		(width 0.09525)
		(layer "F.Cu")
		(net "SAS2X28_A_HDD8_TX_-")
	)
	(segment
		(start 15.074138 -277.1267)
		(end 15.074138 -356.472998)
		(width 0.09525)
		(layer "F.Cu")
		(net "SAS2X28_A_HDD8_TX_-")
	)
	(segment
		(start 8.615426 -369.68938)
		(end 8.59409 -369.710716)
		(width 0.09525)
		(layer "F.Cu")
		(net "SAS2X28_A_HDD8_TX_-")
	)
	(segment
		(start 4.894834 -370.500402)
		(end 4.89331 -370.498878)
		(width 0.09525)
		(layer "F.Cu")
		(net "SAS2X28_A_HDD8_TX_-")
	)
	(segment
		(start 12.615672 -365.688626)
		(end 8.615172 -369.689126)
		(width 0.09525)
		(layer "F.Cu")
		(net "SAS2X28_A_HDD8_TX_-")
	)
	(segment
		(start 14.534134 -357.777034)
		(end 13.789406 -358.521508)
		(width 0.09525)
		(layer "F.Cu")
		(net "SAS2X28_A_HDD8_TX_-")
	)
	(segment
		(start 35.864546 -190.374778)
		(end 35.864546 -254.647954)
		(width 0.09525)
		(layer "F.Cu")
		(net "SAS2X28_A_HDD8_TX_-")
	)
	(segment
		(start 38.245034 -157.334966)
		(end 37.09035 -157.334966)
		(width 0.09525)
		(layer "F.Cu")
		(net "SAS2X28_A_HDD8_TX_-")
	)
	(segment
		(start 13.135864 -359.76941)
		(end 13.135864 -364.553246)
		(width 0.09525)
		(layer "F.Cu")
		(net "SAS2X28_A_HDD8_TX_-")
	)
	(segment
		(start 7.493 -370.166646)
		(end 5.763514 -370.166646)
		(width 0.09525)
		(layer "F.Cu")
		(net "SAS2X28_A_HDD8_TX_-")
	)
	(segment
		(start 36.949126 -157.294326)
		(end 36.923726 -157.278324)
		(width 0.09525)
		(layer "F.Cu")
		(net "SAS2X28_A_HDD8_TX_-")
	)
	(segment
		(start 16.997172 -274.56638)
		(end 15.524988 -276.039072)
		(width 0.09525)
		(layer "F.Cu")
		(net "SAS2X28_A_HDD8_TX_-")
	)
	(segment
		(start 31.126176 -159.218122)
		(end 31.126176 -159.218376)
		(width 0.09525)
		(layer "F.Cu")
		(net "SAS2X28_A_HDD8_TX_-")
	)
	(segment
		(start 36.72586 -156.866844)
		(end 35.687 -156.866844)
		(width 0.09525)
		(layer "F.Cu")
		(net "SAS2X28_A_HDD8_TX_-")
	)
	(segment
		(start 4.89331 -370.498878)
		(end 3.192526 -370.498878)
		(width 0.09525)
		(layer "F.Cu")
		(net "SAS2X28_A_HDD8_TX_-")
	)
	(segment
		(start 13.78966 -358.521762)
		(end 13.556234 -358.755442)
		(width 0.09525)
		(layer "F.Cu")
		(net "SAS2X28_A_HDD8_TX_-")
	)
	(segment
		(start 31.9151 -158.429198)
		(end 31.126176 -159.218122)
		(width 0.09525)
		(layer "F.Cu")
		(net "SAS2X28_A_HDD8_TX_-")
	)
	(segment
		(start 29.658818 -183.595772)
		(end 35.459162 -189.396116)
		(width 0.09525)
		(layer "F.Cu")
		(net "SAS2X28_A_HDD8_TX_-")
	)
	(segment
		(start 29.209746 -161.554668)
		(end 29.209746 -182.512208)
		(width 0.09525)
		(layer "F.Cu")
		(net "SAS2X28_A_HDD8_TX_-")
	)
	(segment
		(start 13.556234 -358.755442)
		(end 13.55598 -358.755188)
		(width 0.09525)
		(layer "F.Cu")
		(net "SAS2X28_A_HDD8_TX_-")
	)
	(segment
		(start 13.789406 -358.521508)
		(end 13.78966 -358.521762)
		(width 0.09525)
		(layer "F.Cu")
		(net "SAS2X28_A_HDD8_TX_-")
	)
	(segment
		(start 31.126176 -159.218376)
		(end 29.506672 -160.83788)
		(width 0.09525)
		(layer "F.Cu")
		(net "SAS2X28_A_HDD8_TX_-")
	)
	(segment
		(start 8.615172 -369.689126)
		(end 8.615426 -369.68938)
		(width 0.09525)
		(layer "F.Cu")
		(net "SAS2X28_A_HDD8_TX_-")
	)
	(segment
		(start 36.82746 -157.10408)
		(end 36.82746 -156.968444)
		(width 0.09525)
		(layer "F.Cu")
		(net "SAS2X28_A_HDD8_TX_-")
	)
	(arc
		(start 8.59409 -369.710716)
		(mid 8.088877 -370.048162)
		(end 7.493 -370.166646)
		(width 0.09525)
		(layer "F.Cu")
		(net "SAS2X28_A_HDD8_TX_-")
	)
	(arc
		(start 35.864546 -254.647954)
		(mid 35.671462 -255.618832)
		(end 35.121596 -256.441956)
		(width 0.09525)
		(layer "F.Cu")
		(net "SAS2X28_A_HDD8_TX_-")
	)
	(arc
		(start 36.82746 -156.968444)
		(mid 36.808562 -156.909346)
		(end 36.75888 -156.872178)
		(width 0.09525)
		(layer "F.Cu")
		(net "SAS2X28_A_HDD8_TX_-")
	)
	(arc
		(start 5.716016 -370.168424)
		(mid 5.543196 -370.207972)
		(end 5.389118 -370.295678)
		(width 0.09525)
		(layer "F.Cu")
		(net "SAS2X28_A_HDD8_TX_-")
	)
	(arc
		(start 15.074138 -356.472998)
		(mid 14.933618 -357.178588)
		(end 14.53388 -357.77678)
		(width 0.09525)
		(layer "F.Cu")
		(net "SAS2X28_A_HDD8_TX_-")
	)
	(arc
		(start 36.75888 -156.872178)
		(mid 36.742591 -156.86814)
		(end 36.72586 -156.866844)
		(width 0.09525)
		(layer "F.Cu")
		(net "SAS2X28_A_HDD8_TX_-")
	)
	(arc
		(start 13.135864 -364.553246)
		(mid 13.022776 -365.121778)
		(end 12.700762 -365.60379)
		(width 0.09525)
		(layer "F.Cu")
		(net "SAS2X28_A_HDD8_TX_-")
	)
	(arc
		(start 29.209746 -182.512208)
		(mid 29.326547 -183.098643)
		(end 29.658818 -183.595772)
		(width 0.09525)
		(layer "F.Cu")
		(net "SAS2X28_A_HDD8_TX_-")
	)
	(arc
		(start 35.459162 -189.396116)
		(mid 35.759184 -189.84513)
		(end 35.864546 -190.374778)
		(width 0.09525)
		(layer "F.Cu")
		(net "SAS2X28_A_HDD8_TX_-")
	)
	(arc
		(start 29.506672 -160.83788)
		(mid 29.286931 -161.166745)
		(end 29.209746 -161.554668)
		(width 0.09525)
		(layer "F.Cu")
		(net "SAS2X28_A_HDD8_TX_-")
	)
	(arc
		(start 35.687 -156.866844)
		(mid 33.645669 -157.27289)
		(end 31.9151 -158.429198)
		(width 0.09525)
		(layer "F.Cu")
		(net "SAS2X28_A_HDD8_TX_-")
	)
	(arc
		(start 5.389118 -370.295678)
		(mid 5.162339 -370.447207)
		(end 4.894834 -370.500402)
		(width 0.09525)
		(layer "F.Cu")
		(net "SAS2X28_A_HDD8_TX_-")
	)
	(arc
		(start 5.763514 -370.166646)
		(mid 5.739748 -370.167071)
		(end 5.716016 -370.168424)
		(width 0.09525)
		(layer "F.Cu")
		(net "SAS2X28_A_HDD8_TX_-")
	)
	(arc
		(start 37.09035 -157.334966)
		(mid 37.016873 -157.324604)
		(end 36.949126 -157.294326)
		(width 0.09525)
		(layer "F.Cu")
		(net "SAS2X28_A_HDD8_TX_-")
	)
	(arc
		(start 15.524988 -276.039072)
		(mid 15.191371 -276.538036)
		(end 15.074138 -277.1267)
		(width 0.09525)
		(layer "F.Cu")
		(net "SAS2X28_A_HDD8_TX_-")
	)
	(arc
		(start 13.55598 -358.755188)
		(mid 13.245057 -359.220517)
		(end 13.135864 -359.76941)
		(width 0.09525)
		(layer "F.Cu")
		(net "SAS2X28_A_HDD8_TX_-")
	)
	(arc
		(start 36.923726 -157.278324)
		(mid 36.853098 -157.203624)
		(end 36.82746 -157.10408)
		(width 0.09525)
		(layer "F.Cu")
		(net "SAS2X28_A_HDD8_TX_-")
	)
	(segment
		(start 189.738 -293.5605)
		(end 189.738 -294.386)
		(width 0.508)
		(layer "F.Cu")
		(net "P12V")
	)
	(segment
		(start 58.674 -478.5233)
		(end 58.674 -479.1202)
		(width 0.508)
		(layer "F.Cu")
		(net "P12V")
	)
	(segment
		(start 36.1061 -339.2932)
		(end 36.4998 -338.8995)
		(width 0.508)
		(layer "F.Cu")
		(net "P12V")
	)
	(segment
		(start 210.439 -477.7105)
		(end 210.439 -476.9612)
		(width 0.508)
		(layer "F.Cu")
		(net "P12V")
	)
	(segment
		(start 37.4015 -138.43)
		(end 38.227 -138.43)
		(width 0.508)
		(layer "F.Cu")
		(net "P12V")
	)
	(segment
		(start 44.2595 -429.5648)
		(end 44.2595 -430.403)
		(width 0.508)
		(layer "F.Cu")
		(net "P12V")
	)
	(segment
		(start 210.312 -477.8375)
		(end 210.439 -477.7105)
		(width 0.508)
		(layer "F.Cu")
		(net "P12V")
	)
	(segment
		(start 191.7065 -190.754)
		(end 190.6905 -190.754)
		(width 0.508)
		(layer "F.Cu")
		(net "P12V")
	)
	(segment
		(start 182.0418 -460.269336)
		(end 182.118 -460.345536)
		(width 0.508)
		(layer "F.Cu")
		(net "P12V")
	)
	(segment
		(start 209.7278 -274.1295)
		(end 209.7278 -275.1074)
		(width 0.508)
		(layer "F.Cu")
		(net "P12V")
	)
	(segment
		(start 37.592 -306.324)
		(end 36.3855 -306.324)
		(width 0.508)
		(layer "F.Cu")
		(net "P12V")
	)
	(segment
		(start 190.373 -89.3445)
		(end 190.373 -90.424)
		(width 0.508)
		(layer "F.Cu")
		(net "P12V")
	)
	(segment
		(start 210.185 -68.8213)
		(end 210.185 -69.723)
		(width 0.508)
		(layer "F.Cu")
		(net "P12V")
	)
	(segment
		(start 53.721 -208.9785)
		(end 52.705 -208.9785)
		(width 0.508)
		(layer "F.Cu")
		(net "P12V")
	)
	(segment
		(start 92.202 -10.8585)
		(end 93.218 -10.8585)
		(width 0.508)
		(layer "F.Cu")
		(net "P12V")
	)
	(segment
		(start 45.8089 -236.6264)
		(end 43.688 -236.6264)
		(width 0.508)
		(layer "F.Cu")
		(net "P12V")
	)
	(segment
		(start 61.9887 -68.5038)
		(end 62.9412 -68.5038)
		(width 0.508)
		(layer "F.Cu")
		(net "P12V")
	)
	(segment
		(start 58.674 -479.1202)
		(end 58.8772 -479.3234)
		(width 0.508)
		(layer "F.Cu")
		(net "P12V")
	)
	(segment
		(start 93.218 -8.763)
		(end 93.218 -10.8585)
		(width 0.508)
		(layer "F.Cu")
		(net "P12V")
	)
	(segment
		(start 190.627 -190.8175)
		(end 190.627 -191.77)
		(width 0.508)
		(layer "F.Cu")
		(net "P12V")
	)
	(segment
		(start 36.3855 -306.324)
		(end 36.3855 -305.308)
		(width 0.508)
		(layer "F.Cu")
		(net "P12V")
	)
	(segment
		(start 191.4525 -498.094)
		(end 190.5635 -498.094)
		(width 0.508)
		(layer "F.Cu")
		(net "P12V")
	)
	(segment
		(start 46.736 -110.109)
		(end 46.736 -107.7595)
		(width 0.508)
		(layer "F.Cu")
		(net "P12V")
	)
	(segment
		(start 190.373 -499.11)
		(end 190.5 -499.237)
		(width 0.508)
		(layer "F.Cu")
		(net "P12V")
	)
	(segment
		(start 93.853 -8.128)
		(end 93.218 -8.763)
		(width 0.508)
		(layer "F.Cu")
		(net "P12V")
	)
	(segment
		(start 209.8294 -169.3291)
		(end 210.7692 -169.3291)
		(width 0.508)
		(layer "F.Cu")
		(net "P12V")
	)
	(segment
		(start 190.373 -90.424)
		(end 189.992 -90.805)
		(width 0.508)
		(layer "F.Cu")
		(net "P12V")
	)
	(segment
		(start 80.8355 -403.098)
		(end 82.55 -403.098)
		(width 0.508)
		(layer "F.Cu")
		(net "P12V")
	)
	(segment
		(start 62.865 -274.828)
		(end 62.865 -275.717)
		(width 0.508)
		(layer "F.Cu")
		(net "P12V")
	)
	(segment
		(start 190.5635 -498.094)
		(end 190.373 -498.2845)
		(width 0.508)
		(layer "F.Cu")
		(net "P12V")
	)
	(segment
		(start 180.987446 -460.269336)
		(end 182.0418 -460.269336)
		(width 0.508)
		(layer "F.Cu")
		(net "P12V")
	)
	(segment
		(start 50.4825 -417.957)
		(end 49.53 -417.957)
		(width 0.508)
		(layer "F.Cu")
		(net "P12V")
	)
	(segment
		(start 78.994 -94.0435)
		(end 77.978 -94.0435)
		(width 0.508)
		(layer "F.Cu")
		(net "P12V")
	)
	(segment
		(start 190.373 -498.2845)
		(end 190.373 -499.11)
		(width 0.508)
		(layer "F.Cu")
		(net "P12V")
	)
	(segment
		(start 190.754 -395.5415)
		(end 190.754 -396.113)
		(width 0.508)
		(layer "F.Cu")
		(net "P12V")
	)
	(segment
		(start 84.582 -401.066)
		(end 84.582 -400.812)
		(width 0.508)
		(layer "F.Cu")
		(net "P12V")
	)
	(segment
		(start 42.3545 -106.1085)
		(end 42.037 -105.791)
		(width 0.508)
		(layer "F.Cu")
		(net "P12V")
	)
	(segment
		(start 190.627 -191.77)
		(end 190.5 -191.897)
		(width 0.508)
		(layer "F.Cu")
		(net "P12V")
	)
	(segment
		(start 190.6905 -190.754)
		(end 190.627 -190.8175)
		(width 0.508)
		(layer "F.Cu")
		(net "P12V")
	)
	(segment
		(start 47.752 -107.7595)
		(end 46.736 -107.7595)
		(width 0.508)
		(layer "F.Cu")
		(net "P12V")
	)
	(segment
		(start 190.9445 -293.243)
		(end 190.0555 -293.243)
		(width 0.508)
		(layer "F.Cu")
		(net "P12V")
	)
	(segment
		(start 191.8335 -395.351)
		(end 190.9445 -395.351)
		(width 0.508)
		(layer "F.Cu")
		(net "P12V")
	)
	(segment
		(start 57.0865 -375.9454)
		(end 57.0865 -376.9233)
		(width 0.508)
		(layer "F.Cu")
		(net "P12V")
	)
	(segment
		(start 42.3545 -106.7308)
		(end 42.3545 -106.1085)
		(width 0.508)
		(layer "F.Cu")
		(net "P12V")
	)
	(segment
		(start 42.3799 -106.7562)
		(end 42.3545 -106.7308)
		(width 0.508)
		(layer "F.Cu")
		(net "P12V")
	)
	(segment
		(start 52.705 -208.9785)
		(end 52.705 -211.582)
		(width 0.508)
		(layer "F.Cu")
		(net "P12V")
	)
	(segment
		(start 82.55 -403.098)
		(end 84.582 -401.066)
		(width 0.508)
		(layer "F.Cu")
		(net "P12V")
	)
	(segment
		(start 46.482 -110.363)
		(end 46.736 -110.109)
		(width 0.508)
		(layer "F.Cu")
		(net "P12V")
	)
	(segment
		(start 83.82 -499.618)
		(end 83.947 -499.491)
		(width 0.508)
		(layer "F.Cu")
		(net "P12V")
	)
	(segment
		(start 81.1911 -26.7208)
		(end 82.1436 -26.7208)
		(width 0.508)
		(layer "F.Cu")
		(net "P12V")
	)
	(segment
		(start 189.865 -293.4335)
		(end 189.738 -293.5605)
		(width 0.508)
		(layer "F.Cu")
		(net "P12V")
	)
	(segment
		(start 77.978 -94.0435)
		(end 77.978 -92.964)
		(width 0.508)
		(layer "F.Cu")
		(net "P12V")
	)
	(segment
		(start 190.0555 -293.243)
		(end 189.865 -293.4335)
		(width 0.508)
		(layer "F.Cu")
		(net "P12V")
	)
	(segment
		(start 190.64732 -89.281)
		(end 190.58382 -89.3445)
		(width 0.508)
		(layer "F.Cu")
		(net "P12V")
	)
	(segment
		(start 190.9445 -395.351)
		(end 190.754 -395.5415)
		(width 0.508)
		(layer "F.Cu")
		(net "P12V")
	)
	(segment
		(start 190.754 -396.113)
		(end 190.5 -396.367)
		(width 0.508)
		(layer "F.Cu")
		(net "P12V")
	)
	(segment
		(start 210.2358 -376.9741)
		(end 210.2358 -377.8504)
		(width 0.508)
		(layer "F.Cu")
		(net "P12V")
	)
	(segment
		(start 36.4998 -338.8995)
		(end 36.4998 -338.455)
		(width 0.508)
		(layer "F.Cu")
		(net "P12V")
	)
	(segment
		(start 83.82 -500.3165)
		(end 83.82 -499.618)
		(width 0.508)
		(layer "F.Cu")
		(net "P12V")
	)
	(segment
		(start 33.3375 -305.308)
		(end 32.258 -305.308)
		(width 0.508)
		(layer "F.Cu")
		(net "P12V")
	)
	(segment
		(start 190.58382 -89.3445)
		(end 190.373 -89.3445)
		(width 0.508)
		(layer "F.Cu")
		(net "P12V")
	)
	(segment
		(start 61.8363 -171.9834)
		(end 62.6872 -171.9834)
		(width 0.508)
		(layer "F.Cu")
		(net "P12V")
	)
	(segment
		(start 191.4525 -89.281)
		(end 190.64732 -89.281)
		(width 0.508)
		(layer "F.Cu")
		(net "P12V")
	)
	(via
		(at 9.3472 -34.7218)
		(size 0.7112)
		(drill 0.4064)
		(layers "F.Cu" "B.Cu")
		(net "P12V")
	)
	(via
		(at 19.049746 -405.9047)
		(size 0.7112)
		(drill 0.4064)
		(layers "F.Cu" "B.Cu")
		(net "P12V")
	)
	(via
		(at 224.0788 -443.1792)
		(size 0.7112)
		(drill 0.4064)
		(layers "F.Cu" "B.Cu")
		(net "P12V")
	)
	(via
		(at 199.140064 -501.829832)
		(size 0.7112)
		(drill 0.4064)
		(layers "F.Cu" "B.Cu")
		(net "P12V")
	)
	(via
		(at 244.475 -366.014)
		(size 0.7112)
		(drill 0.4064)
		(layers "F.Cu" "B.Cu")
		(net "P12V")
	)
	(via
		(at 189.992 -90.805)
		(size 0.7112)
		(drill 0.4064)
		(layers "F.Cu" "B.Cu")
		(net "P12V")
	)
	(via
		(at 45.719746 -112.4077)
		(size 0.7112)
		(drill 0.4064)
		(layers "F.Cu" "B.Cu")
		(net "P12V")
	)
	(via
		(at 46.735746 -111.3917)
		(size 0.7112)
		(drill 0.4064)
		(layers "F.Cu" "B.Cu")
		(net "P12V")
	)
	(via
		(at 243.852446 -381.0762)
		(size 0.7112)
		(drill 0.4064)
		(layers "F.Cu" "B.Cu")
		(net "P12V")
	)
	(via
		(at 53.085746 -212.8647)
		(size 0.7112)
		(drill 0.4064)
		(layers "F.Cu" "B.Cu")
		(net "P12V")
	)
	(via
		(at 74.675746 -498.3607)
		(size 0.7112)
		(drill 0.4064)
		(layers "F.Cu" "B.Cu")
		(net "P12V")
	)
	(via
		(at 199.257412 -90.277696)
		(size 0.7112)
		(drill 0.4064)
		(layers "F.Cu" "B.Cu")
		(net "P12V")
	)
	(via
		(at 46.735746 -113.5507)
		(size 0.7112)
		(drill 0.4064)
		(layers "F.Cu" "B.Cu")
		(net "P12V")
	)
	(via
		(at 9.271 -47.879)
		(size 0.7112)
		(drill 0.4064)
		(layers "F.Cu" "B.Cu")
		(net "P12V")
	)
	(via
		(at 245.364 -374.65)
		(size 0.7112)
		(drill 0.4064)
		(layers "F.Cu" "B.Cu")
		(net "P12V")
	)
	(via
		(at 246.8118 -370.2812)
		(size 0.7112)
		(drill 0.4064)
		(layers "F.Cu" "B.Cu")
		(net "P12V")
	)
	(via
		(at 229.361746 -5.6007)
		(size 0.7112)
		(drill 0.4064)
		(layers "F.Cu" "B.Cu")
		(net "P12V")
	)
	(via
		(at 21.208746 -404.8887)
		(size 0.7112)
		(drill 0.4064)
		(layers "F.Cu" "B.Cu")
		(net "P12V")
	)
	(via
		(at 8.1534 -34.6964)
		(size 0.7112)
		(drill 0.4064)
		(layers "F.Cu" "B.Cu")
		(net "P12V")
	)
	(via
		(at 74.929746 -192.5447)
		(size 0.7112)
		(drill 0.4064)
		(layers "F.Cu" "B.Cu")
		(net "P12V")
	)
	(via
		(at 199.088756 -500.815102)
		(size 0.7112)
		(drill 0.4064)
		(layers "F.Cu" "B.Cu")
		(net "P12V")
	)
	(via
		(at 73.913746 -194.8307)
		(size 0.7112)
		(drill 0.4064)
		(layers "F.Cu" "B.Cu")
		(net "P12V")
	)
	(via
		(at 8.2042 -30.734)
		(size 0.7112)
		(drill 0.4064)
		(layers "F.Cu" "B.Cu")
		(net "P12V")
	)
	(via
		(at 229.234746 -8.9027)
		(size 0.7112)
		(drill 0.4064)
		(layers "F.Cu" "B.Cu")
		(net "P12V")
	)
	(via
		(at 74.675492 -91.722956)
		(size 0.7112)
		(drill 0.4064)
		(layers "F.Cu" "B.Cu")
		(net "P12V")
	)
	(via
		(at 51.941984 -214.912194)
		(size 0.7112)
		(drill 0.4064)
		(layers "F.Cu" "B.Cu")
		(net "P12V")
	)
	(via
		(at 243.459 -377.6472)
		(size 0.7112)
		(drill 0.4064)
		(layers "F.Cu" "B.Cu")
		(net "P12V")
	)
	(via
		(at 5.969 -50.292)
		(size 0.7112)
		(drill 0.4064)
		(layers "F.Cu" "B.Cu")
		(net "P12V")
	)
	(via
		(at 11.175746 -187.3377)
		(size 0.7112)
		(drill 0.4064)
		(layers "F.Cu" "B.Cu")
		(net "P12V")
	)
	(via
		(at 46.735746 -112.4077)
		(size 0.7112)
		(drill 0.4064)
		(layers "F.Cu" "B.Cu")
		(net "P12V")
	)
	(via
		(at 196.552058 -398.728184)
		(size 0.7112)
		(drill 0.4064)
		(layers "F.Cu" "B.Cu")
		(net "P12V")
	)
	(via
		(at 195.918582 -296.136568)
		(size 0.7112)
		(drill 0.4064)
		(layers "F.Cu" "B.Cu")
		(net "P12V")
	)
	(via
		(at 95.630746 -3.9497)
		(size 0.7112)
		(drill 0.4064)
		(layers "F.Cu" "B.Cu")
		(net "P12V")
	)
	(via
		(at 1.651 -283.591)
		(size 0.7112)
		(drill 0.4064)
		(layers "F.Cu" "B.Cu")
		(net "P12V")
	)
	(via
		(at 73.659492 -90.579956)
		(size 0.7112)
		(drill 0.4064)
		(layers "F.Cu" "B.Cu")
		(net "P12V")
	)
	(via
		(at 198.931784 -193.137028)
		(size 0.7112)
		(drill 0.4064)
		(layers "F.Cu" "B.Cu")
		(net "P12V")
	)
	(via
		(at 189.738 -294.386)
		(size 0.7112)
		(drill 0.4064)
		(layers "F.Cu" "B.Cu")
		(net "P12V")
	)
	(via
		(at 74.675492 -89.436956)
		(size 0.7112)
		(drill 0.4064)
		(layers "F.Cu" "B.Cu")
		(net "P12V")
	)
	(via
		(at 32.258 -305.308)
		(size 0.5588)
		(drill 0.3048)
		(layers "F.Cu" "B.Cu")
		(net "P12V")
	)
	(via
		(at 246.888 -366.268)
		(size 0.7112)
		(drill 0.4064)
		(layers "F.Cu" "B.Cu")
		(net "P12V")
	)
	(via
		(at 7.366 -50.292)
		(size 0.7112)
		(drill 0.4064)
		(layers "F.Cu" "B.Cu")
		(net "P12V")
	)
	(via
		(at 57.0865 -376.9233)
		(size 0.5588)
		(drill 0.3048)
		(layers "F.Cu" "B.Cu")
		(net "P12V")
	)
	(via
		(at 10.16 -185.166)
		(size 0.7112)
		(drill 0.4064)
		(layers "F.Cu" "B.Cu")
		(net "P12V")
	)
	(via
		(at 49.53 -417.957)
		(size 0.5588)
		(drill 0.3048)
		(layers "F.Cu" "B.Cu")
		(net "P12V")
	)
	(via
		(at 29.2608 -287.0962)
		(size 0.7112)
		(drill 0.4064)
		(layers "F.Cu" "B.Cu")
		(net "P12V")
	)
	(via
		(at 5.969 -45.466)
		(size 0.7112)
		(drill 0.4064)
		(layers "F.Cu" "B.Cu")
		(net "P12V")
	)
	(via
		(at 51.980846 -212.8647)
		(size 0.7112)
		(drill 0.4064)
		(layers "F.Cu" "B.Cu")
		(net "P12V")
	)
	(via
		(at 5.715 -298.831)
		(size 0.7112)
		(drill 0.4064)
		(layers "F.Cu" "B.Cu")
		(net "P12V")
	)
	(via
		(at 30.352746 -501.0277)
		(size 0.7112)
		(drill 0.4064)
		(layers "F.Cu" "B.Cu")
		(net "P12V")
	)
	(via
		(at 247.269 -374.396)
		(size 0.7112)
		(drill 0.4064)
		(layers "F.Cu" "B.Cu")
		(net "P12V")
	)
	(via
		(at 52.958746 -11.5951)
		(size 0.7112)
		(drill 0.4064)
		(layers "F.Cu" "B.Cu")
		(net "P12V")
	)
	(via
		(at 94.487746 -3.9497)
		(size 0.7112)
		(drill 0.4064)
		(layers "F.Cu" "B.Cu")
		(net "P12V")
	)
	(via
		(at 77.723492 -89.436956)
		(size 0.7112)
		(drill 0.4064)
		(layers "F.Cu" "B.Cu")
		(net "P12V")
	)
	(via
		(at 77.723492 -398.554956)
		(size 0.7112)
		(drill 0.4064)
		(layers "F.Cu" "B.Cu")
		(net "P12V")
	)
	(via
		(at 233.044746 -5.4737)
		(size 0.7112)
		(drill 0.4064)
		(layers "F.Cu" "B.Cu")
		(net "P12V")
	)
	(via
		(at 36.4998 -338.455)
		(size 0.5588)
		(drill 0.3048)
		(layers "F.Cu" "B.Cu")
		(net "P12V")
	)
	(via
		(at 5.715 -300.482)
		(size 0.7112)
		(drill 0.4064)
		(layers "F.Cu" "B.Cu")
		(net "P12V")
	)
	(via
		(at 33.7058 -500.9896)
		(size 0.7112)
		(drill 0.4064)
		(layers "F.Cu" "B.Cu")
		(net "P12V")
	)
	(via
		(at 45.719746 -113.5507)
		(size 0.7112)
		(drill 0.4064)
		(layers "F.Cu" "B.Cu")
		(net "P12V")
	)
	(via
		(at 73.532746 -499.5037)
		(size 0.7112)
		(drill 0.4064)
		(layers "F.Cu" "B.Cu")
		(net "P12V")
	)
	(via
		(at 77.724 -498.221)
		(size 0.7112)
		(drill 0.4064)
		(layers "F.Cu" "B.Cu")
		(net "P12V")
	)
	(via
		(at 1.651 -280.289)
		(size 0.7112)
		(drill 0.4064)
		(layers "F.Cu" "B.Cu")
		(net "P12V")
	)
	(via
		(at 30.479746 -502.5517)
		(size 0.7112)
		(drill 0.4064)
		(layers "F.Cu" "B.Cu")
		(net "P12V")
	)
	(via
		(at 51.980846 -213.896702)
		(size 0.7112)
		(drill 0.4064)
		(layers "F.Cu" "B.Cu")
		(net "P12V")
	)
	(via
		(at 74.675746 -500.6467)
		(size 0.7112)
		(drill 0.4064)
		(layers "F.Cu" "B.Cu")
		(net "P12V")
	)
	(via
		(at 198.838058 -398.728184)
		(size 0.7112)
		(drill 0.4064)
		(layers "F.Cu" "B.Cu")
		(net "P12V")
	)
	(via
		(at 32.1564 -502.539)
		(size 0.7112)
		(drill 0.4064)
		(layers "F.Cu" "B.Cu")
		(net "P12V")
	)
	(via
		(at 243.8908 -379.8062)
		(size 0.7112)
		(drill 0.4064)
		(layers "F.Cu" "B.Cu")
		(net "P12V")
	)
	(via
		(at 45.72 -411.3784)
		(size 0.7112)
		(drill 0.4064)
		(layers "F.Cu" "B.Cu")
		(net "P12V")
	)
	(via
		(at 49.275746 -10.1346)
		(size 0.7112)
		(drill 0.4064)
		(layers "F.Cu" "B.Cu")
		(net "P12V")
	)
	(via
		(at 196.425058 -397.712184)
		(size 0.7112)
		(drill 0.4064)
		(layers "F.Cu" "B.Cu")
		(net "P12V")
	)
	(via
		(at 14.351 -184.023)
		(size 0.7112)
		(drill 0.3556)
		(layers "F.Cu" "B.Cu")
		(net "P12V")
	)
	(via
		(at 62.9412 -68.5038)
		(size 0.5588)
		(drill 0.3048)
		(layers "F.Cu" "B.Cu")
		(net "P12V")
	)
	(via
		(at 197.026784 -194.153028)
		(size 0.7112)
		(drill 0.4064)
		(layers "F.Cu" "B.Cu")
		(net "P12V")
	)
	(via
		(at 190.5 -396.367)
		(size 0.5588)
		(drill 0.3048)
		(layers "F.Cu" "B.Cu")
		(net "P12V")
	)
	(via
		(at 73.659492 -89.436956)
		(size 0.7112)
		(drill 0.4064)
		(layers "F.Cu" "B.Cu")
		(net "P12V")
	)
	(via
		(at 42.037 -105.791)
		(size 0.5588)
		(drill 0.3048)
		(layers "F.Cu" "B.Cu")
		(net "P12V")
	)
	(via
		(at 198.204582 -296.136568)
		(size 0.7112)
		(drill 0.4064)
		(layers "F.Cu" "B.Cu")
		(net "P12V")
	)
	(via
		(at 243.5352 -374.015)
		(size 0.7112)
		(drill 0.4064)
		(layers "F.Cu" "B.Cu")
		(net "P12V")
	)
	(via
		(at 73.532746 -500.6467)
		(size 0.7112)
		(drill 0.4064)
		(layers "F.Cu" "B.Cu")
		(net "P12V")
	)
	(via
		(at 247.027446 -381.5842)
		(size 0.7112)
		(drill 0.4064)
		(layers "F.Cu" "B.Cu")
		(net "P12V")
	)
	(via
		(at 241.935 -367.8682)
		(size 0.7112)
		(drill 0.4064)
		(layers "F.Cu" "B.Cu")
		(net "P12V")
	)
	(via
		(at 37.718746 -310.416702)
		(size 0.7112)
		(drill 0.4064)
		(layers "F.Cu" "B.Cu")
		(net "P12V")
	)
	(via
		(at 96.773746 -3.9497)
		(size 0.7112)
		(drill 0.4064)
		(layers "F.Cu" "B.Cu")
		(net "P12V")
	)
	(via
		(at 198.169784 -194.153028)
		(size 0.7112)
		(drill 0.4064)
		(layers "F.Cu" "B.Cu")
		(net "P12V")
	)
	(via
		(at 10.159746 -188.4807)
		(size 0.7112)
		(drill 0.4064)
		(layers "F.Cu" "B.Cu")
		(net "P12V")
	)
	(via
		(at 36.613846 -311.432702)
		(size 0.7112)
		(drill 0.4064)
		(layers "F.Cu" "B.Cu")
		(net "P12V")
	)
	(via
		(at 62.865 -275.717)
		(size 0.5588)
		(drill 0.3048)
		(layers "F.Cu" "B.Cu")
		(net "P12V")
	)
	(via
		(at 45.795946 -415.1757)
		(size 0.7112)
		(drill 0.4064)
		(layers "F.Cu" "B.Cu")
		(net "P12V")
	)
	(via
		(at 29.209746 -285.0007)
		(size 0.7112)
		(drill 0.4064)
		(layers "F.Cu" "B.Cu")
		(net "P12V")
	)
	(via
		(at 29.209746 -286.0167)
		(size 0.7112)
		(drill 0.4064)
		(layers "F.Cu" "B.Cu")
		(net "P12V")
	)
	(via
		(at 21.208746 -405.9047)
		(size 0.7112)
		(drill 0.4064)
		(layers "F.Cu" "B.Cu")
		(net "P12V")
	)
	(via
		(at 197.056756 -501.827546)
		(size 0.7112)
		(drill 0.4064)
		(layers "F.Cu" "B.Cu")
		(net "P12V")
	)
	(via
		(at 28.193746 -283.9847)
		(size 0.7112)
		(drill 0.4064)
		(layers "F.Cu" "B.Cu")
		(net "P12V")
	)
	(via
		(at 241.935 -370.2812)
		(size 0.7112)
		(drill 0.4064)
		(layers "F.Cu" "B.Cu")
		(net "P12V")
	)
	(via
		(at 44.2595 -430.403)
		(size 0.5588)
		(drill 0.3048)
		(layers "F.Cu" "B.Cu")
		(net "P12V")
	)
	(via
		(at 7.62 -45.466)
		(size 0.7112)
		(drill 0.4064)
		(layers "F.Cu" "B.Cu")
		(net "P12V")
	)
	(via
		(at 73.659492 -399.697956)
		(size 0.7112)
		(drill 0.4064)
		(layers "F.Cu" "B.Cu")
		(net "P12V")
	)
	(via
		(at 48.132746 -9.9441)
		(size 0.7112)
		(drill 0.4064)
		(layers "F.Cu" "B.Cu")
		(net "P12V")
	)
	(via
		(at 190.5 -499.237)
		(size 0.7112)
		(drill 0.4064)
		(layers "F.Cu" "B.Cu")
		(net "P12V")
	)
	(via
		(at 20.065746 -404.7617)
		(size 0.7112)
		(drill 0.4064)
		(layers "F.Cu" "B.Cu")
		(net "P12V")
	)
	(via
		(at 244.475 -364.871)
		(size 0.7112)
		(drill 0.4064)
		(layers "F.Cu" "B.Cu")
		(net "P12V")
	)
	(via
		(at 199.257412 -91.420696)
		(size 0.7112)
		(drill 0.4064)
		(layers "F.Cu" "B.Cu")
		(net "P12V")
	)
	(via
		(at 245.364 -375.793)
		(size 0.7112)
		(drill 0.4064)
		(layers "F.Cu" "B.Cu")
		(net "P12V")
	)
	(via
		(at 196.209412 -92.436696)
		(size 0.7112)
		(drill 0.4064)
		(layers "F.Cu" "B.Cu")
		(net "P12V")
	)
	(via
		(at 29.209746 -283.9847)
		(size 0.7112)
		(drill 0.4064)
		(layers "F.Cu" "B.Cu")
		(net "P12V")
	)
	(via
		(at 196.209412 -91.420696)
		(size 0.7112)
		(drill 0.4064)
		(layers "F.Cu" "B.Cu")
		(net "P12V")
	)
	(via
		(at 50.291746 -10.1346)
		(size 0.7112)
		(drill 0.4064)
		(layers "F.Cu" "B.Cu")
		(net "P12V")
	)
	(via
		(at 37.592 -306.324)
		(size 0.5588)
		(drill 0.3048)
		(layers "F.Cu" "B.Cu")
		(net "P12V")
	)
	(via
		(at 38.227 -138.43)
		(size 0.5588)
		(drill 0.3048)
		(layers "F.Cu" "B.Cu")
		(net "P12V")
	)
	(via
		(at 8.89 -50.419)
		(size 0.7112)
		(drill 0.4064)
		(layers "F.Cu" "B.Cu")
		(net "P12V")
	)
	(via
		(at 199.600058 -396.569184)
		(size 0.7112)
		(drill 0.4064)
		(layers "F.Cu" "B.Cu")
		(net "P12V")
	)
	(via
		(at 35.0266 -500.9388)
		(size 0.7112)
		(drill 0.4064)
		(layers "F.Cu" "B.Cu")
		(net "P12V")
	)
	(via
		(at 23.494746 -403.6187)
		(size 0.7112)
		(drill 0.4064)
		(layers "F.Cu" "B.Cu")
		(net "P12V")
	)
	(via
		(at 241.681 -379.8062)
		(size 0.7112)
		(drill 0.4064)
		(layers "F.Cu" "B.Cu")
		(net "P12V")
	)
	(via
		(at 195.883784 -193.137028)
		(size 0.7112)
		(drill 0.4064)
		(layers "F.Cu" "B.Cu")
		(net "P12V")
	)
	(via
		(at 241.935 -369.0112)
		(size 0.7112)
		(drill 0.4064)
		(layers "F.Cu" "B.Cu")
		(net "P12V")
	)
	(via
		(at 231.139746 -9.0297)
		(size 0.7112)
		(drill 0.4064)
		(layers "F.Cu" "B.Cu")
		(net "P12V")
	)
	(via
		(at 93.979746 -4.8387)
		(size 0.7112)
		(drill 0.4064)
		(layers "F.Cu" "B.Cu")
		(net "P12V")
	)
	(via
		(at 243.5352 -375.158)
		(size 0.7112)
		(drill 0.4064)
		(layers "F.Cu" "B.Cu")
		(net "P12V")
	)
	(via
		(at 7.62 -47.879)
		(size 0.7112)
		(drill 0.4064)
		(layers "F.Cu" "B.Cu")
		(net "P12V")
	)
	(via
		(at 36.613846 -310.416702)
		(size 0.7112)
		(drill 0.4064)
		(layers "F.Cu" "B.Cu")
		(net "P12V")
	)
	(via
		(at 5.715 -295.783)
		(size 0.7112)
		(drill 0.4064)
		(layers "F.Cu" "B.Cu")
		(net "P12V")
	)
	(via
		(at 231.012746 -5.4737)
		(size 0.7112)
		(drill 0.4064)
		(layers "F.Cu" "B.Cu")
		(net "P12V")
	)
	(via
		(at 49.402746 -11.1887)
		(size 0.7112)
		(drill 0.4064)
		(layers "F.Cu" "B.Cu")
		(net "P12V")
	)
	(via
		(at 247.269 -375.539)
		(size 0.7112)
		(drill 0.4064)
		(layers "F.Cu" "B.Cu")
		(net "P12V")
	)
	(via
		(at 73.659492 -91.722956)
		(size 0.7112)
		(drill 0.4064)
		(layers "F.Cu" "B.Cu")
		(net "P12V")
	)
	(via
		(at 232.790746 -9.1567)
		(size 0.7112)
		(drill 0.4064)
		(layers "F.Cu" "B.Cu")
		(net "P12V")
	)
	(via
		(at 73.532746 -498.2337)
		(size 0.7112)
		(drill 0.4064)
		(layers "F.Cu" "B.Cu")
		(net "P12V")
	)
	(via
		(at 77.977746 -192.5447)
		(size 0.7112)
		(drill 0.4064)
		(layers "F.Cu" "B.Cu")
		(net "P12V")
	)
	(via
		(at 241.8842 -372.745)
		(size 0.7112)
		(drill 0.4064)
		(layers "F.Cu" "B.Cu")
		(net "P12V")
	)
	(via
		(at 9.398 -29.2862)
		(size 0.7112)
		(drill 0.4064)
		(layers "F.Cu" "B.Cu")
		(net "P12V")
	)
	(via
		(at 242.0112 -365.125)
		(size 0.7112)
		(drill 0.4064)
		(layers "F.Cu" "B.Cu")
		(net "P12V")
	)
	(via
		(at 14.351 -405.511)
		(size 0.7112)
		(drill 0.3556)
		(layers "F.Cu" "B.Cu")
		(net "P12V")
	)
	(via
		(at 83.947 -499.491)
		(size 0.5588)
		(drill 0.3048)
		(layers "F.Cu" "B.Cu")
		(net "P12V")
	)
	(via
		(at 8.1534 -33.1978)
		(size 0.7112)
		(drill 0.4064)
		(layers "F.Cu" "B.Cu")
		(net "P12V")
	)
	(via
		(at 243.5352 -376.301)
		(size 0.7112)
		(drill 0.4064)
		(layers "F.Cu" "B.Cu")
		(net "P12V")
	)
	(via
		(at 11.176 -185.039)
		(size 0.7112)
		(drill 0.4064)
		(layers "F.Cu" "B.Cu")
		(net "P12V")
	)
	(via
		(at 244.3988 -370.0272)
		(size 0.7112)
		(drill 0.4064)
		(layers "F.Cu" "B.Cu")
		(net "P12V")
	)
	(via
		(at 198.966582 -293.977568)
		(size 0.7112)
		(drill 0.4064)
		(layers "F.Cu" "B.Cu")
		(net "P12V")
	)
	(via
		(at 190.5 -191.897)
		(size 0.7112)
		(drill 0.4064)
		(layers "F.Cu" "B.Cu")
		(net "P12V")
	)
	(via
		(at 49.7078 -411.2514)
		(size 0.7112)
		(drill 0.4064)
		(layers "F.Cu" "B.Cu")
		(net "P12V")
	)
	(via
		(at 199.088756 -499.672102)
		(size 0.7112)
		(drill 0.4064)
		(layers "F.Cu" "B.Cu")
		(net "P12V")
	)
	(via
		(at 198.931784 -191.994028)
		(size 0.7112)
		(drill 0.4064)
		(layers "F.Cu" "B.Cu")
		(net "P12V")
	)
	(via
		(at 32.131 -500.9896)
		(size 0.7112)
		(drill 0.4064)
		(layers "F.Cu" "B.Cu")
		(net "P12V")
	)
	(via
		(at 20.065746 -406.9207)
		(size 0.7112)
		(drill 0.4064)
		(layers "F.Cu" "B.Cu")
		(net "P12V")
	)
	(via
		(at 13.588746 -187.824872)
		(size 0.7112)
		(drill 0.3556)
		(layers "F.Cu" "B.Cu")
		(net "P12V")
	)
	(via
		(at 13.715746 -185.9407)
		(size 0.7112)
		(drill 0.3556)
		(layers "F.Cu" "B.Cu")
		(net "P12V")
	)
	(via
		(at 82.1436 -26.7208)
		(size 0.5588)
		(drill 0.3048)
		(layers "F.Cu" "B.Cu")
		(net "P12V")
	)
	(via
		(at 6.096 -47.879)
		(size 0.7112)
		(drill 0.4064)
		(layers "F.Cu" "B.Cu")
		(net "P12V")
	)
	(via
		(at 74.675492 -399.697956)
		(size 0.7112)
		(drill 0.4064)
		(layers "F.Cu" "B.Cu")
		(net "P12V")
	)
	(via
		(at 97.154746 -5.0927)
		(size 0.7112)
		(drill 0.4064)
		(layers "F.Cu" "B.Cu")
		(net "P12V")
	)
	(via
		(at 28.193746 -285.0007)
		(size 0.7112)
		(drill 0.4064)
		(layers "F.Cu" "B.Cu")
		(net "P12V")
	)
	(via
		(at 247.1928 -378.0282)
		(size 0.7112)
		(drill 0.4064)
		(layers "F.Cu" "B.Cu")
		(net "P12V")
	)
	(via
		(at 246.8118 -369.0112)
		(size 0.7112)
		(drill 0.4064)
		(layers "F.Cu" "B.Cu")
		(net "P12V")
	)
	(via
		(at 197.061582 -296.136568)
		(size 0.7112)
		(drill 0.4064)
		(layers "F.Cu" "B.Cu")
		(net "P12V")
	)
	(via
		(at 11.302746 -188.4807)
		(size 0.7112)
		(drill 0.4064)
		(layers "F.Cu" "B.Cu")
		(net "P12V")
	)
	(via
		(at 74.675492 -398.554956)
		(size 0.7112)
		(drill 0.4064)
		(layers "F.Cu" "B.Cu")
		(net "P12V")
	)
	(via
		(at 58.8772 -479.3234)
		(size 0.5588)
		(drill 0.3048)
		(layers "F.Cu" "B.Cu")
		(net "P12V")
	)
	(via
		(at 210.439 -476.9612)
		(size 0.5588)
		(drill 0.3048)
		(layers "F.Cu" "B.Cu")
		(net "P12V")
	)
	(via
		(at 53.086 -214.912702)
		(size 0.7112)
		(drill 0.4064)
		(layers "F.Cu" "B.Cu")
		(net "P12V")
	)
	(via
		(at 196.040756 -501.831102)
		(size 0.7112)
		(drill 0.4064)
		(layers "F.Cu" "B.Cu")
		(net "P12V")
	)
	(via
		(at 74.929746 -193.6877)
		(size 0.7112)
		(drill 0.4064)
		(layers "F.Cu" "B.Cu")
		(net "P12V")
	)
	(via
		(at 242.0112 -366.268)
		(size 0.7112)
		(drill 0.4064)
		(layers "F.Cu" "B.Cu")
		(net "P12V")
	)
	(via
		(at 244.348 -372.491)
		(size 0.7112)
		(drill 0.4064)
		(layers "F.Cu" "B.Cu")
		(net "P12V")
	)
	(via
		(at 243.852446 -382.2192)
		(size 0.7112)
		(drill 0.4064)
		(layers "F.Cu" "B.Cu")
		(net "P12V")
	)
	(via
		(at 197.695058 -398.728184)
		(size 0.7112)
		(drill 0.4064)
		(layers "F.Cu" "B.Cu")
		(net "P12V")
	)
	(via
		(at 9.3726 -30.7086)
		(size 0.7112)
		(drill 0.4064)
		(layers "F.Cu" "B.Cu")
		(net "P12V")
	)
	(via
		(at 244.3988 -368.7572)
		(size 0.7112)
		(drill 0.4064)
		(layers "F.Cu" "B.Cu")
		(net "P12V")
	)
	(via
		(at 74.675492 -90.579956)
		(size 0.7112)
		(drill 0.4064)
		(layers "F.Cu" "B.Cu")
		(net "P12V")
	)
	(via
		(at 11.303 -186.182)
		(size 0.7112)
		(drill 0.4064)
		(layers "F.Cu" "B.Cu")
		(net "P12V")
	)
	(via
		(at 74.675746 -499.5037)
		(size 0.7112)
		(drill 0.4064)
		(layers "F.Cu" "B.Cu")
		(net "P12V")
	)
	(via
		(at 245.2878 -378.2822)
		(size 0.7112)
		(drill 0.4064)
		(layers "F.Cu" "B.Cu")
		(net "P12V")
	)
	(via
		(at 246.8118 -371.4242)
		(size 0.7112)
		(drill 0.4064)
		(layers "F.Cu" "B.Cu")
		(net "P12V")
	)
	(via
		(at 245.364 -376.936)
		(size 0.7112)
		(drill 0.4064)
		(layers "F.Cu" "B.Cu")
		(net "P12V")
	)
	(via
		(at 49.6824 -412.4198)
		(size 0.7112)
		(drill 0.4064)
		(layers "F.Cu" "B.Cu")
		(net "P12V")
	)
	(via
		(at 45.630846 -111.3917)
		(size 0.7112)
		(drill 0.4064)
		(layers "F.Cu" "B.Cu")
		(net "P12V")
	)
	(via
		(at 73.659492 -400.840956)
		(size 0.7112)
		(drill 0.4064)
		(layers "F.Cu" "B.Cu")
		(net "P12V")
	)
	(via
		(at 244.3988 -371.1702)
		(size 0.7112)
		(drill 0.4064)
		(layers "F.Cu" "B.Cu")
		(net "P12V")
	)
	(via
		(at 247.269 -376.682)
		(size 0.7112)
		(drill 0.4064)
		(layers "F.Cu" "B.Cu")
		(net "P12V")
	)
	(via
		(at 198.966582 -295.120568)
		(size 0.7112)
		(drill 0.4064)
		(layers "F.Cu" "B.Cu")
		(net "P12V")
	)
	(via
		(at 1.651 -278.892)
		(size 0.7112)
		(drill 0.4064)
		(layers "F.Cu" "B.Cu")
		(net "P12V")
	)
	(via
		(at 182.118 -460.345536)
		(size 0.7112)
		(drill 0.4064)
		(layers "F.Cu" "B.Cu")
		(net "P12V")
	)
	(via
		(at 73.913746 -192.5447)
		(size 0.7112)
		(drill 0.4064)
		(layers "F.Cu" "B.Cu")
		(net "P12V")
	)
	(via
		(at 21.208746 -406.9207)
		(size 0.7112)
		(drill 0.4064)
		(layers "F.Cu" "B.Cu")
		(net "P12V")
	)
	(via
		(at 241.642646 -382.2192)
		(size 0.7112)
		(drill 0.4064)
		(layers "F.Cu" "B.Cu")
		(net "P12V")
	)
	(via
		(at 9.398 -33.1978)
		(size 0.7112)
		(drill 0.4064)
		(layers "F.Cu" "B.Cu")
		(net "P12V")
	)
	(via
		(at 244.3988 -367.6142)
		(size 0.7112)
		(drill 0.4064)
		(layers "F.Cu" "B.Cu")
		(net "P12V")
	)
	(via
		(at 10.16 -186.182)
		(size 0.7112)
		(drill 0.4064)
		(layers "F.Cu" "B.Cu")
		(net "P12V")
	)
	(via
		(at 1.651 -281.94)
		(size 0.7112)
		(drill 0.4064)
		(layers "F.Cu" "B.Cu")
		(net "P12V")
	)
	(via
		(at 20.065746 -405.9047)
		(size 0.7112)
		(drill 0.4064)
		(layers "F.Cu" "B.Cu")
		(net "P12V")
	)
	(via
		(at 9.271 -45.466)
		(size 0.7112)
		(drill 0.4064)
		(layers "F.Cu" "B.Cu")
		(net "P12V")
	)
	(via
		(at 73.659492 -398.554956)
		(size 0.7112)
		(drill 0.4064)
		(layers "F.Cu" "B.Cu")
		(net "P12V")
	)
	(via
		(at 50.799746 -11.6967)
		(size 0.7112)
		(drill 0.4064)
		(layers "F.Cu" "B.Cu")
		(net "P12V")
	)
	(via
		(at 8.2296 -29.3116)
		(size 0.7112)
		(drill 0.4064)
		(layers "F.Cu" "B.Cu")
		(net "P12V")
	)
	(via
		(at 77.597 -499.237)
		(size 0.7112)
		(drill 0.4064)
		(layers "F.Cu" "B.Cu")
		(net "P12V")
	)
	(via
		(at 246.888 -365.125)
		(size 0.7112)
		(drill 0.4064)
		(layers "F.Cu" "B.Cu")
		(net "P12V")
	)
	(via
		(at 199.600058 -397.712184)
		(size 0.7112)
		(drill 0.4064)
		(layers "F.Cu" "B.Cu")
		(net "P12V")
	)
	(via
		(at 10.159746 -187.4647)
		(size 0.7112)
		(drill 0.4064)
		(layers "F.Cu" "B.Cu")
		(net "P12V")
	)
	(via
		(at 35.0266 -502.5136)
		(size 0.7112)
		(drill 0.4064)
		(layers "F.Cu" "B.Cu")
		(net "P12V")
	)
	(via
		(at 5.715 -297.18)
		(size 0.7112)
		(drill 0.4064)
		(layers "F.Cu" "B.Cu")
		(net "P12V")
	)
	(via
		(at 37.715444 -312.448702)
		(size 0.7112)
		(drill 0.4064)
		(layers "F.Cu" "B.Cu")
		(net "P12V")
	)
	(via
		(at 20.700746 -403.6187)
		(size 0.7112)
		(drill 0.4064)
		(layers "F.Cu" "B.Cu")
		(net "P12V")
	)
	(via
		(at 36.613846 -312.448702)
		(size 0.7112)
		(drill 0.4064)
		(layers "F.Cu" "B.Cu")
		(net "P12V")
	)
	(via
		(at 37.718746 -311.432702)
		(size 0.7112)
		(drill 0.4064)
		(layers "F.Cu" "B.Cu")
		(net "P12V")
	)
	(via
		(at 33.7058 -502.5644)
		(size 0.7112)
		(drill 0.4064)
		(layers "F.Cu" "B.Cu")
		(net "P12V")
	)
	(via
		(at 197.352412 -92.436696)
		(size 0.7112)
		(drill 0.4064)
		(layers "F.Cu" "B.Cu")
		(net "P12V")
	)
	(via
		(at 195.883784 -194.153028)
		(size 0.7112)
		(drill 0.4064)
		(layers "F.Cu" "B.Cu")
		(net "P12V")
	)
	(via
		(at 93.979746 -5.9817)
		(size 0.7112)
		(drill 0.4064)
		(layers "F.Cu" "B.Cu")
		(net "P12V")
	)
	(via
		(at 84.582 -400.812)
		(size 0.5588)
		(drill 0.3048)
		(layers "F.Cu" "B.Cu")
		(net "P12V")
	)
	(via
		(at 74.929746 -194.8307)
		(size 0.7112)
		(drill 0.4064)
		(layers "F.Cu" "B.Cu")
		(net "P12V")
	)
	(via
		(at 247.0658 -380.3142)
		(size 0.7112)
		(drill 0.4064)
		(layers "F.Cu" "B.Cu")
		(net "P12V")
	)
	(via
		(at 19.049746 -406.9207)
		(size 0.7112)
		(drill 0.4064)
		(layers "F.Cu" "B.Cu")
		(net "P12V")
	)
	(via
		(at 210.2358 -377.8504)
		(size 0.5588)
		(drill 0.3048)
		(layers "F.Cu" "B.Cu")
		(net "P12V")
	)
	(via
		(at 210.185 -69.723)
		(size 0.5588)
		(drill 0.3048)
		(layers "F.Cu" "B.Cu")
		(net "P12V")
	)
	(via
		(at 45.795946 -413.1437)
		(size 0.7112)
		(drill 0.4064)
		(layers "F.Cu" "B.Cu")
		(net "P12V")
	)
	(via
		(at 74.675492 -400.840956)
		(size 0.7112)
		(drill 0.4064)
		(layers "F.Cu" "B.Cu")
		(net "P12V")
	)
	(via
		(at 73.913746 -193.6877)
		(size 0.7112)
		(drill 0.4064)
		(layers "F.Cu" "B.Cu")
		(net "P12V")
	)
	(via
		(at 45.652182 -414.16986)
		(size 0.7112)
		(drill 0.4064)
		(layers "F.Cu" "B.Cu")
		(net "P12V")
	)
	(via
		(at 28.193746 -287.1597)
		(size 0.7112)
		(drill 0.4064)
		(layers "F.Cu" "B.Cu")
		(net "P12V")
	)
	(via
		(at 225.1456 -443.0776)
		(size 0.7112)
		(drill 0.4064)
		(layers "F.Cu" "B.Cu")
		(net "P12V")
	)
	(via
		(at 198.12 -501.904)
		(size 0.7112)
		(drill 0.3556)
		(layers "F.Cu" "B.Cu")
		(net "P12V")
	)
	(via
		(at 22.097746 -403.6187)
		(size 0.7112)
		(drill 0.4064)
		(layers "F.Cu" "B.Cu")
		(net "P12V")
	)
	(via
		(at 209.7278 -275.1074)
		(size 0.5588)
		(drill 0.3048)
		(layers "F.Cu" "B.Cu")
		(net "P12V")
	)
	(via
		(at 18.669 -409.702)
		(size 0.7112)
		(drill 0.3556)
		(layers "F.Cu" "B.Cu")
		(net "P12V")
	)
	(via
		(at 28.193746 -286.0167)
		(size 0.7112)
		(drill 0.4064)
		(layers "F.Cu" "B.Cu")
		(net "P12V")
	)
	(via
		(at 19.049746 -404.7617)
		(size 0.7112)
		(drill 0.4064)
		(layers "F.Cu" "B.Cu")
		(net "P12V")
	)
	(via
		(at 241.642646 -381.0762)
		(size 0.7112)
		(drill 0.4064)
		(layers "F.Cu" "B.Cu")
		(net "P12V")
	)
	(via
		(at 241.935 -371.4242)
		(size 0.7112)
		(drill 0.4064)
		(layers "F.Cu" "B.Cu")
		(net "P12V")
	)
	(via
		(at 246.761 -372.745)
		(size 0.7112)
		(drill 0.4064)
		(layers "F.Cu" "B.Cu")
		(net "P12V")
	)
	(via
		(at 53.082444 -213.896702)
		(size 0.7112)
		(drill 0.4064)
		(layers "F.Cu" "B.Cu")
		(net "P12V")
	)
	(via
		(at 247.027446 -382.7272)
		(size 0.7112)
		(drill 0.4064)
		(layers "F.Cu" "B.Cu")
		(net "P12V")
	)
	(via
		(at 210.7692 -169.3291)
		(size 0.5588)
		(drill 0.3048)
		(layers "F.Cu" "B.Cu")
		(net "P12V")
	)
	(via
		(at 195.918582 -295.120568)
		(size 0.7112)
		(drill 0.4064)
		(layers "F.Cu" "B.Cu")
		(net "P12V")
	)
	(via
		(at 198.495412 -92.436696)
		(size 0.7112)
		(drill 0.4064)
		(layers "F.Cu" "B.Cu")
		(net "P12V")
	)
	(via
		(at 62.6872 -171.9834)
		(size 0.5588)
		(drill 0.3048)
		(layers "F.Cu" "B.Cu")
		(net "P12V")
	)
	(via
		(at 246.8118 -367.8682)
		(size 0.7112)
		(drill 0.4064)
		(layers "F.Cu" "B.Cu")
		(net "P12V")
	)
	(via
		(at 43.688 -236.6264)
		(size 0.5588)
		(drill 0.3048)
		(layers "F.Cu" "B.Cu")
		(net "P12V")
	)
	(segment
		(start 71.500746 -190.0682)
		(end 71.500746 -189.3951)
		(width 0.111252)
		(layer "F.Cu")
		(net "SAS2X28_A_HDD8_FLT")
	)
	(segment
		(start 71.754746 -189.1411)
		(end 71.754746 -188.0362)
		(width 0.111252)
		(layer "F.Cu")
		(net "SAS2X28_A_HDD8_FLT")
	)
	(segment
		(start 71.500746 -189.3951)
		(end 71.653146 -189.2427)
		(width 0.111252)
		(layer "F.Cu")
		(net "SAS2X28_A_HDD8_FLT")
	)
	(segment
		(start 71.653146 -189.2427)
		(end 71.754746 -189.1411)
		(width 0.111252)
		(layer "F.Cu")
		(net "SAS2X28_A_HDD8_FLT")
	)
	(via
		(at 11.251946 -393.9413)
		(size 0.5588)
		(drill 0.3048)
		(layers "F.Cu" "B.Cu")
		(net "SAS2X28_A_HDD8_FLT")
	)
	(via
		(at 10.49655 -393.381738)
		(size 0.7112)
		(drill 0.3556)
		(layers "F.Cu" "B.Cu")
		(net "SAS2X28_A_HDD8_FLT")
	)
	(via
		(at 71.653146 -189.2427)
		(size 0.5588)
		(drill 0.3048)
		(layers "F.Cu" "B.Cu")
		(net "SAS2X28_A_HDD8_FLT")
	)
	(segment
		(start 10.49655 -393.381738)
		(end 10.692384 -393.381738)
		(width 0.111252)
		(layer "B.Cu")
		(net "SAS2X28_A_HDD8_FLT")
	)
	(segment
		(start 10.49655 -393.381738)
		(end 5.803138 -393.381738)
		(width 0.111252)
		(layer "B.Cu")
		(net "SAS2X28_A_HDD8_FLT")
	)
	(segment
		(start 5.803138 -393.381738)
		(end 4.920234 -392.498834)
		(width 0.111252)
		(layer "B.Cu")
		(net "SAS2X28_A_HDD8_FLT")
	)
	(segment
		(start 10.692384 -393.381738)
		(end 11.251946 -393.9413)
		(width 0.111252)
		(layer "B.Cu")
		(net "SAS2X28_A_HDD8_FLT")
	)
	(segment
		(start 4.920234 -392.498834)
		(end 2.811526 -392.498834)
		(width 0.111252)
		(layer "B.Cu")
		(net "SAS2X28_A_HDD8_FLT")
	)
	(segment
		(start 71.653146 -189.2427)
		(end 71.653146 -193.355976)
		(width 0.14605)
		(layer "In5.Cu")
		(net "SAS2X28_A_HDD8_FLT")
	)
	(segment
		(start 90.522552 -434.398674)
		(end 89.987374 -434.933852)
		(width 0.14605)
		(layer "In5.Cu")
		(net "SAS2X28_A_HDD8_FLT")
	)
	(segment
		(start 14.443202 -396.922498)
		(end 11.723116 -394.202412)
		(width 0.14605)
		(layer "In5.Cu")
		(net "SAS2X28_A_HDD8_FLT")
	)
	(segment
		(start 14.18844 -431.329592)
		(end 14.18844 -401.804886)
		(width 0.14605)
		(layer "In5.Cu")
		(net "SAS2X28_A_HDD8_FLT")
	)
	(segment
		(start 17.75714 -448.59575)
		(end 12.873736 -443.712346)
		(width 0.14605)
		(layer "In5.Cu")
		(net "SAS2X28_A_HDD8_FLT")
	)
	(segment
		(start 74.74077 -196.4436)
		(end 82.208624 -196.4436)
		(width 0.14605)
		(layer "In5.Cu")
		(net "SAS2X28_A_HDD8_FLT")
	)
	(segment
		(start 11.723116 -394.202412)
		(end 11.513058 -394.202412)
		(width 0.14605)
		(layer "In5.Cu")
		(net "SAS2X28_A_HDD8_FLT")
	)
	(segment
		(start 9.689084 -442.223906)
		(end 9.689084 -442.223652)
		(width 0.14605)
		(layer "In5.Cu")
		(net "SAS2X28_A_HDD8_FLT")
	)
	(segment
		(start 82.208624 -196.4436)
		(end 90.522552 -204.757528)
		(width 0.14605)
		(layer "In5.Cu")
		(net "SAS2X28_A_HDD8_FLT")
	)
	(segment
		(start 89.829894 -434.933852)
		(end 76.088494 -448.675252)
		(width 0.14605)
		(layer "In5.Cu")
		(net "SAS2X28_A_HDD8_FLT")
	)
	(segment
		(start 12.873736 -443.712346)
		(end 12.769342 -443.712346)
		(width 0.14605)
		(layer "In5.Cu")
		(net "SAS2X28_A_HDD8_FLT")
	)
	(segment
		(start 14.443202 -401.550124)
		(end 14.443202 -396.922498)
		(width 0.14605)
		(layer "In5.Cu")
		(net "SAS2X28_A_HDD8_FLT")
	)
	(segment
		(start 14.18844 -401.804886)
		(end 14.443202 -401.550124)
		(width 0.14605)
		(layer "In5.Cu")
		(net "SAS2X28_A_HDD8_FLT")
	)
	(segment
		(start 76.088494 -448.675252)
		(end 17.97304 -448.675252)
		(width 0.14605)
		(layer "In5.Cu")
		(net "SAS2X28_A_HDD8_FLT")
	)
	(segment
		(start 11.513058 -394.202412)
		(end 11.251946 -393.9413)
		(width 0.14605)
		(layer "In5.Cu")
		(net "SAS2X28_A_HDD8_FLT")
	)
	(segment
		(start 9.689084 -442.223652)
		(end 8.880348 -441.414916)
		(width 0.14605)
		(layer "In5.Cu")
		(net "SAS2X28_A_HDD8_FLT")
	)
	(segment
		(start 11.063732 -442.9633)
		(end 10.428478 -442.9633)
		(width 0.14605)
		(layer "In5.Cu")
		(net "SAS2X28_A_HDD8_FLT")
	)
	(segment
		(start 10.428478 -442.9633)
		(end 9.689084 -442.223906)
		(width 0.14605)
		(layer "In5.Cu")
		(net "SAS2X28_A_HDD8_FLT")
	)
	(segment
		(start 12.766294 -443.709298)
		(end 11.80973 -443.709298)
		(width 0.14605)
		(layer "In5.Cu")
		(net "SAS2X28_A_HDD8_FLT")
	)
	(segment
		(start 12.769342 -443.712346)
		(end 12.766294 -443.709298)
		(width 0.14605)
		(layer "In5.Cu")
		(net "SAS2X28_A_HDD8_FLT")
	)
	(segment
		(start 89.987374 -434.933852)
		(end 89.829894 -434.933852)
		(width 0.14605)
		(layer "In5.Cu")
		(net "SAS2X28_A_HDD8_FLT")
	)
	(segment
		(start 11.80973 -443.709298)
		(end 11.063732 -442.9633)
		(width 0.14605)
		(layer "In5.Cu")
		(net "SAS2X28_A_HDD8_FLT")
	)
	(segment
		(start 71.653146 -193.355976)
		(end 74.74077 -196.4436)
		(width 0.14605)
		(layer "In5.Cu")
		(net "SAS2X28_A_HDD8_FLT")
	)
	(segment
		(start 90.522552 -204.757528)
		(end 90.522552 -434.398674)
		(width 0.14605)
		(layer "In5.Cu")
		(net "SAS2X28_A_HDD8_FLT")
	)
	(segment
		(start 17.893538 -448.59575)
		(end 17.75714 -448.59575)
		(width 0.14605)
		(layer "In5.Cu")
		(net "SAS2X28_A_HDD8_FLT")
	)
	(segment
		(start 17.97304 -448.675252)
		(end 17.893538 -448.59575)
		(width 0.14605)
		(layer "In5.Cu")
		(net "SAS2X28_A_HDD8_FLT")
	)
	(segment
		(start 8.880348 -441.414916)
		(end 8.880348 -436.637684)
		(width 0.14605)
		(layer "In5.Cu")
		(net "SAS2X28_A_HDD8_FLT")
	)
	(segment
		(start 8.880348 -436.637684)
		(end 14.18844 -431.329592)
		(width 0.14605)
		(layer "In5.Cu")
		(net "SAS2X28_A_HDD8_FLT")
	)
	(segment
		(start 72.404986 -189.13094)
		(end 72.404986 -188.0362)
		(width 0.111252)
		(layer "F.Cu")
		(net "SAS2X28_B_HDD8_FLT")
	)
	(segment
		(start 72.516746 -189.2427)
		(end 72.404986 -189.13094)
		(width 0.111252)
		(layer "F.Cu")
		(net "SAS2X28_B_HDD8_FLT")
	)
	(segment
		(start 72.516746 -190.0682)
		(end 72.516746 -189.2427)
		(width 0.111252)
		(layer "F.Cu")
		(net "SAS2X28_B_HDD8_FLT")
	)
	(via
		(at 72.516746 -189.2427)
		(size 0.5588)
		(drill 0.3048)
		(layers "F.Cu" "B.Cu")
		(net "SAS2X28_B_HDD8_FLT")
	)
	(via
		(at 72.457056 -190.2587)
		(size 0.7112)
		(drill 0.3556)
		(layers "F.Cu" "B.Cu")
		(net "SAS2X28_B_HDD8_FLT")
	)
	(via
		(at 10.820146 -144.2339)
		(size 0.5588)
		(drill 0.3048)
		(layers "F.Cu" "B.Cu")
		(net "SAS2X28_B_HDD8_FLT")
	)
	(segment
		(start 7.498334 -142.50035)
		(end 2.81305 -142.50035)
		(width 0.111252)
		(layer "B.Cu")
		(net "SAS2X28_B_HDD8_FLT")
	)
	(segment
		(start 10.820146 -144.2339)
		(end 9.931146 -143.3449)
		(width 0.111252)
		(layer "B.Cu")
		(net "SAS2X28_B_HDD8_FLT")
	)
	(segment
		(start 8.342884 -143.3449)
		(end 7.498334 -142.50035)
		(width 0.111252)
		(layer "B.Cu")
		(net "SAS2X28_B_HDD8_FLT")
	)
	(segment
		(start 2.81305 -142.50035)
		(end 2.811526 -142.498826)
		(width 0.111252)
		(layer "B.Cu")
		(net "SAS2X28_B_HDD8_FLT")
	)
	(segment
		(start 72.516746 -189.2427)
		(end 72.516746 -190.19901)
		(width 0.111252)
		(layer "B.Cu")
		(net "SAS2X28_B_HDD8_FLT")
	)
	(segment
		(start 9.931146 -143.3449)
		(end 8.342884 -143.3449)
		(width 0.111252)
		(layer "B.Cu")
		(net "SAS2X28_B_HDD8_FLT")
	)
	(segment
		(start 72.516746 -190.19901)
		(end 72.457056 -190.2587)
		(width 0.111252)
		(layer "B.Cu")
		(net "SAS2X28_B_HDD8_FLT")
	)
	(segment
		(start 12.941554 -135.742172)
		(end 14.290802 -134.392924)
		(width 0.14605)
		(layer "In5.Cu")
		(net "SAS2X28_B_HDD8_FLT")
	)
	(segment
		(start 25.377902 -102.728014)
		(end 87.706708 -102.728014)
		(width 0.14605)
		(layer "In5.Cu")
		(net "SAS2X28_B_HDD8_FLT")
	)
	(segment
		(start 87.706708 -102.728014)
		(end 87.987632 -103.008938)
		(width 0.14605)
		(layer "In5.Cu")
		(net "SAS2X28_B_HDD8_FLT")
	)
	(segment
		(start 14.290802 -128.662938)
		(end 13.852398 -128.224534)
		(width 0.14605)
		(layer "In5.Cu")
		(net "SAS2X28_B_HDD8_FLT")
	)
	(segment
		(start 14.290802 -134.392924)
		(end 14.290802 -128.662938)
		(width 0.14605)
		(layer "In5.Cu")
		(net "SAS2X28_B_HDD8_FLT")
	)
	(segment
		(start 12.115546 -142.799054)
		(end 12.115546 -141.645894)
		(width 0.14605)
		(layer "In5.Cu")
		(net "SAS2X28_B_HDD8_FLT")
	)
	(segment
		(start 87.987632 -173.771814)
		(end 72.516746 -189.2427)
		(width 0.14605)
		(layer "In5.Cu")
		(net "SAS2X28_B_HDD8_FLT")
	)
	(segment
		(start 13.852398 -114.253518)
		(end 25.377902 -102.728014)
		(width 0.14605)
		(layer "In5.Cu")
		(net "SAS2X28_B_HDD8_FLT")
	)
	(segment
		(start 10.820146 -144.094454)
		(end 12.115546 -142.799054)
		(width 0.14605)
		(layer "In5.Cu")
		(net "SAS2X28_B_HDD8_FLT")
	)
	(segment
		(start 12.941554 -140.819886)
		(end 12.941554 -135.742172)
		(width 0.14605)
		(layer "In5.Cu")
		(net "SAS2X28_B_HDD8_FLT")
	)
	(segment
		(start 87.987632 -103.008938)
		(end 87.987632 -173.771814)
		(width 0.14605)
		(layer "In5.Cu")
		(net "SAS2X28_B_HDD8_FLT")
	)
	(segment
		(start 12.115546 -141.645894)
		(end 12.941554 -140.819886)
		(width 0.14605)
		(layer "In5.Cu")
		(net "SAS2X28_B_HDD8_FLT")
	)
	(segment
		(start 13.852398 -128.224534)
		(end 13.852398 -114.253518)
		(width 0.14605)
		(layer "In5.Cu")
		(net "SAS2X28_B_HDD8_FLT")
	)
	(segment
		(start 10.820146 -144.2339)
		(end 10.820146 -144.094454)
		(width 0.14605)
		(layer "In5.Cu")
		(net "SAS2X28_B_HDD8_FLT")
	)
	(segment
		(start 202.120246 -287.9852)
		(end 201.580242 -288.525204)
		(width 0.111252)
		(layer "F.Cu")
		(net "SAS2X28_B_HDD2_FLT")
	)
	(segment
		(start 200.75525 -288.525204)
		(end 200.547986 -288.31794)
		(width 0.111252)
		(layer "F.Cu")
		(net "SAS2X28_B_HDD2_FLT")
	)
	(segment
		(start 202.120246 -287.7947)
		(end 202.120246 -287.9852)
		(width 0.111252)
		(layer "F.Cu")
		(net "SAS2X28_B_HDD2_FLT")
	)
	(segment
		(start 201.580242 -288.525204)
		(end 201.207116 -288.525204)
		(width 0.111252)
		(layer "F.Cu")
		(net "SAS2X28_B_HDD2_FLT")
	)
	(segment
		(start 200.547986 -288.31794)
		(end 200.547986 -287.4772)
		(width 0.111252)
		(layer "F.Cu")
		(net "SAS2X28_B_HDD2_FLT")
	)
	(segment
		(start 201.207116 -288.525204)
		(end 200.75525 -288.525204)
		(width 0.111252)
		(layer "F.Cu")
		(net "SAS2X28_B_HDD2_FLT")
	)
	(via
		(at 8.459978 -141.716252)
		(size 0.5588)
		(drill 0.3048)
		(layers "F.Cu" "B.Cu")
		(net "SAS2X28_B_HDD2_FLT")
	)
	(via
		(at 201.207116 -288.525204)
		(size 0.5588)
		(drill 0.3048)
		(layers "F.Cu" "B.Cu")
		(net "SAS2X28_B_HDD2_FLT")
	)
	(via
		(at 202.146916 -288.525204)
		(size 0.7112)
		(drill 0.3556)
		(layers "F.Cu" "B.Cu")
		(net "SAS2X28_B_HDD2_FLT")
	)
	(via
		(at 94.741746 -285.3817)
		(size 0.5588)
		(drill 0.3048)
		(layers "F.Cu" "B.Cu")
		(net "SAS2X28_B_HDD2_FLT")
	)
	(segment
		(start 7.197598 -142.084298)
		(end 6.613652 -141.500352)
		(width 0.111252)
		(layer "B.Cu")
		(net "SAS2X28_B_HDD2_FLT")
	)
	(segment
		(start 8.091932 -142.084298)
		(end 7.197598 -142.084298)
		(width 0.111252)
		(layer "B.Cu")
		(net "SAS2X28_B_HDD2_FLT")
	)
	(segment
		(start 6.613652 -141.500352)
		(end 2.81305 -141.500352)
		(width 0.111252)
		(layer "B.Cu")
		(net "SAS2X28_B_HDD2_FLT")
	)
	(segment
		(start 201.207116 -288.525204)
		(end 202.146916 -288.525204)
		(width 0.111252)
		(layer "B.Cu")
		(net "SAS2X28_B_HDD2_FLT")
	)
	(segment
		(start 2.81305 -141.500352)
		(end 2.811526 -141.498828)
		(width 0.111252)
		(layer "B.Cu")
		(net "SAS2X28_B_HDD2_FLT")
	)
	(segment
		(start 8.459978 -141.716252)
		(end 8.091932 -142.084298)
		(width 0.111252)
		(layer "B.Cu")
		(net "SAS2X28_B_HDD2_FLT")
	)
	(segment
		(start 193.293746 -285.3817)
		(end 94.741746 -285.3817)
		(width 0.14605)
		(layer "In2.Cu")
		(net "SAS2X28_B_HDD2_FLT")
	)
	(segment
		(start 196.087746 -288.1757)
		(end 193.293746 -285.3817)
		(width 0.14605)
		(layer "In2.Cu")
		(net "SAS2X28_B_HDD2_FLT")
	)
	(segment
		(start 200.857612 -288.1757)
		(end 196.087746 -288.1757)
		(width 0.14605)
		(layer "In2.Cu")
		(net "SAS2X28_B_HDD2_FLT")
	)
	(segment
		(start 201.207116 -288.525204)
		(end 200.857612 -288.1757)
		(width 0.14605)
		(layer "In2.Cu")
		(net "SAS2X28_B_HDD2_FLT")
	)
	(segment
		(start 10.245598 -129.960624)
		(end 10.684002 -130.399028)
		(width 0.14605)
		(layer "In5.Cu")
		(net "SAS2X28_B_HDD2_FLT")
	)
	(segment
		(start 9.058402 -136.817608)
		(end 9.058402 -138.544554)
		(width 0.14605)
		(layer "In5.Cu")
		(net "SAS2X28_B_HDD2_FLT")
	)
	(segment
		(start 10.245598 -108.850938)
		(end 10.245598 -129.960624)
		(width 0.14605)
		(layer "In5.Cu")
		(net "SAS2X28_B_HDD2_FLT")
	)
	(segment
		(start 8.686546 -139.7381)
		(end 8.686546 -141.489684)
		(width 0.14605)
		(layer "In5.Cu")
		(net "SAS2X28_B_HDD2_FLT")
	)
	(segment
		(start 20.960588 -98.135948)
		(end 10.245598 -108.850938)
		(width 0.14605)
		(layer "In5.Cu")
		(net "SAS2X28_B_HDD2_FLT")
	)
	(segment
		(start 96.434148 -106.353102)
		(end 88.216994 -98.135948)
		(width 0.14605)
		(layer "In5.Cu")
		(net "SAS2X28_B_HDD2_FLT")
	)
	(segment
		(start 88.216994 -98.135948)
		(end 20.960588 -98.135948)
		(width 0.14605)
		(layer "In5.Cu")
		(net "SAS2X28_B_HDD2_FLT")
	)
	(segment
		(start 10.684002 -132.897372)
		(end 9.334754 -134.24662)
		(width 0.14605)
		(layer "In5.Cu")
		(net "SAS2X28_B_HDD2_FLT")
	)
	(segment
		(start 9.058402 -138.544554)
		(end 9.056116 -138.54684)
		(width 0.14605)
		(layer "In5.Cu")
		(net "SAS2X28_B_HDD2_FLT")
	)
	(segment
		(start 8.686546 -141.489684)
		(end 8.459978 -141.716252)
		(width 0.14605)
		(layer "In5.Cu")
		(net "SAS2X28_B_HDD2_FLT")
	)
	(segment
		(start 9.334754 -134.24662)
		(end 9.334754 -136.541256)
		(width 0.14605)
		(layer "In5.Cu")
		(net "SAS2X28_B_HDD2_FLT")
	)
	(segment
		(start 94.741746 -285.3817)
		(end 96.434148 -283.689298)
		(width 0.14605)
		(layer "In5.Cu")
		(net "SAS2X28_B_HDD2_FLT")
	)
	(segment
		(start 96.434148 -283.689298)
		(end 96.434148 -106.353102)
		(width 0.14605)
		(layer "In5.Cu")
		(net "SAS2X28_B_HDD2_FLT")
	)
	(segment
		(start 9.056116 -139.368784)
		(end 8.686546 -139.7381)
		(width 0.14605)
		(layer "In5.Cu")
		(net "SAS2X28_B_HDD2_FLT")
	)
	(segment
		(start 9.056116 -138.54684)
		(end 9.056116 -139.368784)
		(width 0.14605)
		(layer "In5.Cu")
		(net "SAS2X28_B_HDD2_FLT")
	)
	(segment
		(start 9.334754 -136.541256)
		(end 9.058402 -136.817608)
		(width 0.14605)
		(layer "In5.Cu")
		(net "SAS2X28_B_HDD2_FLT")
	)
	(segment
		(start 10.684002 -130.399028)
		(end 10.684002 -132.897372)
		(width 0.14605)
		(layer "In5.Cu")
		(net "SAS2X28_B_HDD2_FLT")
	)
	(segment
		(start 45.783246 -145.3007)
		(end 45.783246 -144.2847)
		(width 0.111252)
		(layer "F.Cu")
		(net "DRIVE_ACT_8")
	)
	(segment
		(start 47.421546 -144.5387)
		(end 50.711608 -144.5387)
		(width 0.111252)
		(layer "F.Cu")
		(net "DRIVE_ACT_8")
	)
	(segment
		(start 47.167546 -144.2847)
		(end 47.256446 -144.3736)
		(width 0.111252)
		(layer "F.Cu")
		(net "DRIVE_ACT_8")
	)
	(segment
		(start 50.711608 -144.5387)
		(end 50.905918 -144.73301)
		(width 0.111252)
		(layer "F.Cu")
		(net "DRIVE_ACT_8")
	)
	(segment
		(start 45.783246 -144.2847)
		(end 47.167546 -144.2847)
		(width 0.111252)
		(layer "F.Cu")
		(net "DRIVE_ACT_8")
	)
	(segment
		(start 47.256446 -144.3736)
		(end 47.421546 -144.5387)
		(width 0.111252)
		(layer "F.Cu")
		(net "DRIVE_ACT_8")
	)
	(via
		(at 50.905918 -144.73301)
		(size 0.7112)
		(drill 0.3556)
		(layers "F.Cu" "B.Cu")
		(net "DRIVE_ACT_8")
	)
	(via
		(at 73.532746 -9.9187)
		(size 0.7112)
		(drill 0.4064)
		(layers "F.Cu" "B.Cu")
		(net "12V_PRE_14")
	)
	(via
		(at 72.770746 -11.077702)
		(size 0.7112)
		(drill 0.3556)
		(layers "F.Cu" "B.Cu")
		(net "12V_PRE_14")
	)
	(via
		(at 23.621746 -13.2207)
		(size 0.7112)
		(drill 0.4064)
		(layers "F.Cu" "B.Cu")
		(net "12V_PRE_14")
	)
	(via
		(at 24.637746 -12.5857)
		(size 0.7112)
		(drill 0.4064)
		(layers "F.Cu" "B.Cu")
		(net "12V_PRE_14")
	)
	(via
		(at 72.797162 -8.871712)
		(size 0.7112)
		(drill 0.4064)
		(layers "F.Cu" "B.Cu")
		(net "12V_PRE_14")
	)
	(via
		(at 25.527 -116.0018)
		(size 0.7112)
		(drill 0.4064)
		(layers "F.Cu" "B.Cu")
		(net "12V_PRE_13")
	)
	(via
		(at 34.32556 -121.64822)
		(size 0.7112)
		(drill 0.4064)
		(layers "F.Cu" "B.Cu")
		(net "12V_PRE_13")
	)
	(via
		(at 24.003 -116.0272)
		(size 0.7112)
		(drill 0.4064)
		(layers "F.Cu" "B.Cu")
		(net "12V_PRE_13")
	)
	(via
		(at 33.781746 -120.7897)
		(size 0.7112)
		(drill 0.3556)
		(layers "F.Cu" "B.Cu")
		(net "12V_PRE_13")
	)
	(via
		(at 34.543746 -120.0277)
		(size 0.7112)
		(drill 0.4064)
		(layers "F.Cu" "B.Cu")
		(net "12V_PRE_13")
	)
	(segment
		(start 215.409018 -269.830804)
		(end 215.197182 -269.618968)
		(width 0.09525)
		(layer "F.Cu")
		(net "SAS2X28_B_HDD2_RX_+")
	)
	(segment
		(start 216.814146 -270.076168)
		(end 216.001346 -270.076168)
		(width 0.09525)
		(layer "F.Cu")
		(net "SAS2X28_B_HDD2_RX_+")
	)
	(segment
		(start 217.318082 -270.355568)
		(end 217.197432 -270.234918)
		(width 0.09525)
		(layer "F.Cu")
		(net "SAS2X28_B_HDD2_RX_+")
	)
	(via
		(at 215.197182 -269.618968)
		(size 0.5588)
		(drill 0.3048)
		(layers "F.Cu" "B.Cu")
		(net "SAS2X28_B_HDD2_RX_+")
	)
	(arc
		(start 217.197432 -270.234918)
		(mid 217.021579 -270.117417)
		(end 216.814146 -270.076168)
		(width 0.09525)
		(layer "F.Cu")
		(net "SAS2X28_B_HDD2_RX_+")
	)
	(arc
		(start 216.001346 -270.076168)
		(mid 215.680775 -270.012402)
		(end 215.409018 -269.830804)
		(width 0.09525)
		(layer "F.Cu")
		(net "SAS2X28_B_HDD2_RX_+")
	)
	(segment
		(start 45.757338 -117.500146)
		(end 46.373796 -118.116604)
		(width 0.09525)
		(layer "B.Cu")
		(net "SAS2X28_B_HDD2_RX_+")
	)
	(segment
		(start 13.437362 -117.0686)
		(end 44.715684 -117.0686)
		(width 0.09525)
		(layer "B.Cu")
		(net "SAS2X28_B_HDD2_RX_+")
	)
	(segment
		(start 198.449946 -269.745968)
		(end 214.890604 -269.745968)
		(width 0.09525)
		(layer "B.Cu")
		(net "SAS2X28_B_HDD2_RX_+")
	)
	(segment
		(start 5.682488 -113.842546)
		(end 9.127744 -113.842546)
		(width 0.09525)
		(layer "B.Cu")
		(net "SAS2X28_B_HDD2_RX_+")
	)
	(segment
		(start 2.81305 -113.500408)
		(end 5.036058 -113.500408)
		(width 0.09525)
		(layer "B.Cu")
		(net "SAS2X28_B_HDD2_RX_+")
	)
	(segment
		(start 10.169398 -114.274092)
		(end 12.629134 -116.733828)
		(width 0.09525)
		(layer "B.Cu")
		(net "SAS2X28_B_HDD2_RX_+")
	)
	(segment
		(start 46.373796 -118.116604)
		(end 197.687184 -269.429738)
		(width 0.09525)
		(layer "B.Cu")
		(net "SAS2X28_B_HDD2_RX_+")
	)
	(segment
		(start 5.228082 -113.57991)
		(end 5.355082 -113.70691)
		(width 0.09525)
		(layer "B.Cu")
		(net "SAS2X28_B_HDD2_RX_+")
	)
	(segment
		(start 2.811526 -113.498884)
		(end 2.81305 -113.500408)
		(width 0.09525)
		(layer "B.Cu")
		(net "SAS2X28_B_HDD2_RX_+")
	)
	(arc
		(start 215.128348 -269.674594)
		(mid 215.164197 -269.648552)
		(end 215.197182 -269.618968)
		(width 0.09525)
		(layer "B.Cu")
		(net "SAS2X28_B_HDD2_RX_+")
	)
	(arc
		(start 214.957914 -269.740634)
		(mid 215.046653 -269.716704)
		(end 215.128348 -269.674594)
		(width 0.09525)
		(layer "B.Cu")
		(net "SAS2X28_B_HDD2_RX_+")
	)
	(arc
		(start 5.441696 -113.774982)
		(mid 5.557446 -113.825316)
		(end 5.682488 -113.842546)
		(width 0.09525)
		(layer "B.Cu")
		(net "SAS2X28_B_HDD2_RX_+")
	)
	(arc
		(start 5.355082 -113.70691)
		(mid 5.396356 -113.743534)
		(end 5.441696 -113.774982)
		(width 0.09525)
		(layer "B.Cu")
		(net "SAS2X28_B_HDD2_RX_+")
	)
	(arc
		(start 44.715684 -117.0686)
		(mid 45.279453 -117.180741)
		(end 45.757338 -117.500146)
		(width 0.09525)
		(layer "B.Cu")
		(net "SAS2X28_B_HDD2_RX_+")
	)
	(arc
		(start 214.890604 -269.745968)
		(mid 214.924363 -269.744612)
		(end 214.957914 -269.740634)
		(width 0.09525)
		(layer "B.Cu")
		(net "SAS2X28_B_HDD2_RX_+")
	)
	(arc
		(start 12.629134 -116.733828)
		(mid 12.999952 -116.981601)
		(end 13.437362 -117.0686)
		(width 0.09525)
		(layer "B.Cu")
		(net "SAS2X28_B_HDD2_RX_+")
	)
	(arc
		(start 197.687184 -269.429738)
		(mid 198.037113 -269.663709)
		(end 198.449946 -269.745968)
		(width 0.09525)
		(layer "B.Cu")
		(net "SAS2X28_B_HDD2_RX_+")
	)
	(arc
		(start 5.036058 -113.500408)
		(mid 5.139967 -113.521077)
		(end 5.228082 -113.57991)
		(width 0.09525)
		(layer "B.Cu")
		(net "SAS2X28_B_HDD2_RX_+")
	)
	(arc
		(start 9.127744 -113.842546)
		(mid 9.691513 -113.954687)
		(end 10.169398 -114.274092)
		(width 0.09525)
		(layer "B.Cu")
		(net "SAS2X28_B_HDD2_RX_+")
	)
	(via
		(at 39.750746 -222.5167)
		(size 0.7112)
		(drill 0.4064)
		(layers "F.Cu" "B.Cu")
		(net "12V_PRE_12")
	)
	(via
		(at 24.764746 -218.9607)
		(size 0.7112)
		(drill 0.4064)
		(layers "F.Cu" "B.Cu")
		(net "12V_PRE_12")
	)
	(via
		(at 24.384 -219.964)
		(size 0.7112)
		(drill 0.3556)
		(layers "F.Cu" "B.Cu")
		(net "12V_PRE_12")
	)
	(via
		(at 39.750746 -221.1197)
		(size 0.7112)
		(drill 0.4064)
		(layers "F.Cu" "B.Cu")
		(net "12V_PRE_12")
	)
	(via
		(at 23.697946 -218.9607)
		(size 0.7112)
		(drill 0.4064)
		(layers "F.Cu" "B.Cu")
		(net "12V_PRE_12")
	)
	(segment
		(start 23.697946 -218.9607)
		(end 24.384 -219.646754)
		(width 0.508)
		(layer "B.Cu")
		(net "12V_PRE_12")
	)
	(segment
		(start 24.384 -219.646754)
		(end 24.384 -219.964)
		(width 0.508)
		(layer "B.Cu")
		(net "12V_PRE_12")
	)
	(via
		(at 25.791414 -320.702178)
		(size 0.5588)
		(drill 0.3048)
		(layers "F.Cu" "B.Cu")
		(net "12V_PRE_11")
	)
	(via
		(at 26.669746 -321.3227)
		(size 0.7112)
		(drill 0.3556)
		(layers "F.Cu" "B.Cu")
		(net "12V_PRE_11")
	)
	(segment
		(start 26.049224 -320.702178)
		(end 26.669746 -321.3227)
		(width 0.508)
		(layer "B.Cu")
		(net "12V_PRE_11")
	)
	(segment
		(start 25.791414 -320.702178)
		(end 26.049224 -320.702178)
		(width 0.508)
		(layer "B.Cu")
		(net "12V_PRE_11")
	)
	(segment
		(start 216.737946 -269.745968)
		(end 216.251536 -269.745968)
		(width 0.09525)
		(layer "F.Cu")
		(net "SAS2X28_B_HDD2_RX_-")
	)
	(segment
		(start 217.318082 -269.466568)
		(end 217.25128 -269.53337)
		(width 0.09525)
		(layer "F.Cu")
		(net "SAS2X28_B_HDD2_RX_-")
	)
	(via
		(at 216.111582 -269.606014)
		(size 0.5588)
		(drill 0.3048)
		(layers "F.Cu" "B.Cu")
		(net "SAS2X28_B_HDD2_RX_-")
	)
	(arc
		(start 216.251536 -269.745968)
		(mid 216.152574 -269.704976)
		(end 216.111582 -269.606014)
		(width 0.09525)
		(layer "F.Cu")
		(net "SAS2X28_B_HDD2_RX_-")
	)
	(arc
		(start 217.25128 -269.53337)
		(mid 217.01576 -269.690739)
		(end 216.737946 -269.745968)
		(width 0.09525)
		(layer "F.Cu")
		(net "SAS2X28_B_HDD2_RX_-")
	)
	(segment
		(start 198.449946 -270.076168)
		(end 215.391746 -270.076168)
		(width 0.09525)
		(layer "B.Cu")
		(net "SAS2X28_B_HDD2_RX_-")
	)
	(segment
		(start 5.010658 -114.498882)
		(end 5.012182 -114.500406)
		(width 0.09525)
		(layer "B.Cu")
		(net "SAS2X28_B_HDD2_RX_-")
	)
	(segment
		(start 13.437108 -117.3988)
		(end 44.715176 -117.3988)
		(width 0.09525)
		(layer "B.Cu")
		(net "SAS2X28_B_HDD2_RX_-")
	)
	(segment
		(start 5.605526 -114.172746)
		(end 9.12749 -114.172746)
		(width 0.09525)
		(layer "B.Cu")
		(net "SAS2X28_B_HDD2_RX_-")
	)
	(segment
		(start 5.22859 -114.410744)
		(end 5.36829 -114.271044)
		(width 0.09525)
		(layer "B.Cu")
		(net "SAS2X28_B_HDD2_RX_-")
	)
	(segment
		(start 2.811526 -114.498882)
		(end 5.010658 -114.498882)
		(width 0.09525)
		(layer "B.Cu")
		(net "SAS2X28_B_HDD2_RX_-")
	)
	(segment
		(start 215.817958 -269.899638)
		(end 216.111582 -269.606014)
		(width 0.09525)
		(layer "B.Cu")
		(net "SAS2X28_B_HDD2_RX_-")
	)
	(segment
		(start 45.523404 -117.733572)
		(end 46.139862 -118.35003)
		(width 0.09525)
		(layer "B.Cu")
		(net "SAS2X28_B_HDD2_RX_-")
	)
	(segment
		(start 9.935718 -114.507518)
		(end 12.395454 -116.967254)
		(width 0.09525)
		(layer "B.Cu")
		(net "SAS2X28_B_HDD2_RX_-")
	)
	(segment
		(start 46.139862 -118.35003)
		(end 46.140116 -118.35003)
		(width 0.09525)
		(layer "B.Cu")
		(net "SAS2X28_B_HDD2_RX_-")
	)
	(segment
		(start 46.140116 -118.35003)
		(end 197.453504 -269.663418)
		(width 0.09525)
		(layer "B.Cu")
		(net "SAS2X28_B_HDD2_RX_-")
	)
	(arc
		(start 215.391746 -270.076168)
		(mid 215.622405 -270.030287)
		(end 215.817958 -269.899638)
		(width 0.09525)
		(layer "B.Cu")
		(net "SAS2X28_B_HDD2_RX_-")
	)
	(arc
		(start 44.715176 -117.3988)
		(mid 45.152583 -117.485806)
		(end 45.523404 -117.733572)
		(width 0.09525)
		(layer "B.Cu")
		(net "SAS2X28_B_HDD2_RX_-")
	)
	(arc
		(start 9.12749 -114.172746)
		(mid 9.564897 -114.259752)
		(end 9.935718 -114.507518)
		(width 0.09525)
		(layer "B.Cu")
		(net "SAS2X28_B_HDD2_RX_-")
	)
	(arc
		(start 5.36829 -114.271044)
		(mid 5.477135 -114.198316)
		(end 5.605526 -114.172746)
		(width 0.09525)
		(layer "B.Cu")
		(net "SAS2X28_B_HDD2_RX_-")
	)
	(arc
		(start 12.395454 -116.967254)
		(mid 12.873369 -117.286587)
		(end 13.437108 -117.3988)
		(width 0.09525)
		(layer "B.Cu")
		(net "SAS2X28_B_HDD2_RX_-")
	)
	(arc
		(start 197.453504 -269.663418)
		(mid 197.910675 -269.96889)
		(end 198.449946 -270.076168)
		(width 0.09525)
		(layer "B.Cu")
		(net "SAS2X28_B_HDD2_RX_-")
	)
	(arc
		(start 5.012182 -114.500406)
		(mid 5.12931 -114.477108)
		(end 5.22859 -114.410744)
		(width 0.09525)
		(layer "B.Cu")
		(net "SAS2X28_B_HDD2_RX_-")
	)
	(via
		(at 24.256746 -423.016172)
		(size 0.5588)
		(drill 0.3048)
		(layers "F.Cu" "B.Cu")
		(net "12V_PRE_10")
	)
	(via
		(at 23.875746 -424.0657)
		(size 0.7112)
		(drill 0.3556)
		(layers "F.Cu" "B.Cu")
		(net "12V_PRE_10")
	)
	(segment
		(start 23.875746 -423.397172)
		(end 23.875746 -424.0657)
		(width 0.508)
		(layer "B.Cu")
		(net "12V_PRE_10")
	)
	(segment
		(start 24.256746 -423.016172)
		(end 23.875746 -423.397172)
		(width 0.508)
		(layer "B.Cu")
		(net "12V_PRE_10")
	)
	(segment
		(start 64.430402 -323.64553)
		(end 26.899616 -361.17657)
		(width 0.09525)
		(layer "F.Cu")
		(net "SAS2X28_A_HDD2_TX_-")
	)
	(segment
		(start 221.741746 -260.162294)
		(end 221.741746 -260.101842)
		(width 0.09525)
		(layer "F.Cu")
		(net "SAS2X28_A_HDD2_TX_-")
	)
	(segment
		(start 217.967306 -259.9563)
		(end 66.11874 -322.205604)
		(width 0.09525)
		(layer "F.Cu")
		(net "SAS2X28_A_HDD2_TX_-")
	)
	(segment
		(start 24.363172 -371.08638)
		(end 11.155172 -384.29438)
		(width 0.09525)
		(layer "F.Cu")
		(net "SAS2X28_A_HDD2_TX_-")
	)
	(segment
		(start 65.22974 -322.846192)
		(end 64.430402 -323.64553)
		(width 0.09525)
		(layer "F.Cu")
		(net "SAS2X28_A_HDD2_TX_-")
	)
	(segment
		(start 10.297922 -391.37463)
		(end 6.787134 -394.885672)
		(width 0.09525)
		(layer "F.Cu")
		(net "SAS2X28_A_HDD2_TX_-")
	)
	(segment
		(start 6.122416 -395.160754)
		(end 5.620004 -395.160754)
		(width 0.09525)
		(layer "F.Cu")
		(net "SAS2X28_A_HDD2_TX_-")
	)
	(segment
		(start 24.904446 -363.83849)
		(end 24.904446 -369.77955)
		(width 0.09525)
		(layer "F.Cu")
		(net "SAS2X28_A_HDD2_TX_-")
	)
	(segment
		(start 217.967052 -259.956046)
		(end 217.967306 -259.9563)
		(width 0.09525)
		(layer "F.Cu")
		(net "SAS2X28_A_HDD2_TX_-")
	)
	(segment
		(start 221.821756 -260.302756)
		(end 221.784418 -260.265418)
		(width 0.09525)
		(layer "F.Cu")
		(net "SAS2X28_A_HDD2_TX_-")
	)
	(segment
		(start 10.637774 -385.543552)
		(end 10.637774 -390.55421)
		(width 0.09525)
		(layer "F.Cu")
		(net "SAS2X28_A_HDD2_TX_-")
	)
	(segment
		(start 4.800092 -395.500352)
		(end 4.798568 -395.498828)
		(width 0.09525)
		(layer "F.Cu")
		(net "SAS2X28_A_HDD2_TX_-")
	)
	(segment
		(start 25.647904 -362.428282)
		(end 25.375616 -362.70057)
		(width 0.09525)
		(layer "F.Cu")
		(net "SAS2X28_A_HDD2_TX_-")
	)
	(segment
		(start 221.506796 -259.866892)
		(end 218.540584 -259.866892)
		(width 0.09525)
		(layer "F.Cu")
		(net "SAS2X28_A_HDD2_TX_-")
	)
	(segment
		(start 218.540584 -259.866892)
		(end 218.529154 -259.86613)
		(width 0.09525)
		(layer "F.Cu")
		(net "SAS2X28_A_HDD2_TX_-")
	)
	(segment
		(start 26.899616 -361.17657)
		(end 26.124916 -361.951016)
		(width 0.09525)
		(layer "F.Cu")
		(net "SAS2X28_A_HDD2_TX_-")
	)
	(segment
		(start 26.124916 -361.951016)
		(end 25.648158 -362.427774)
		(width 0.09525)
		(layer "F.Cu")
		(net "SAS2X28_A_HDD2_TX_-")
	)
	(segment
		(start 223.249998 -260.340094)
		(end 221.911926 -260.340094)
		(width 0.09525)
		(layer "F.Cu")
		(net "SAS2X28_A_HDD2_TX_-")
	)
	(segment
		(start 25.648158 -362.427774)
		(end 25.647904 -362.428282)
		(width 0.09525)
		(layer "F.Cu")
		(net "SAS2X28_A_HDD2_TX_-")
	)
	(segment
		(start 4.798568 -395.498828)
		(end 3.192526 -395.498828)
		(width 0.09525)
		(layer "F.Cu")
		(net "SAS2X28_A_HDD2_TX_-")
	)
	(arc
		(start 24.904446 -369.77955)
		(mid 24.763835 -370.486828)
		(end 24.363172 -371.08638)
		(width 0.09525)
		(layer "F.Cu")
		(net "SAS2X28_A_HDD2_TX_-")
	)
	(arc
		(start 5.620004 -395.160754)
		(mid 5.483241 -395.187958)
		(end 5.367274 -395.265402)
		(width 0.09525)
		(layer "F.Cu")
		(net "SAS2X28_A_HDD2_TX_-")
	)
	(arc
		(start 66.11874 -322.205604)
		(mid 65.648404 -322.490043)
		(end 65.22974 -322.846192)
		(width 0.09525)
		(layer "F.Cu")
		(net "SAS2X28_A_HDD2_TX_-")
	)
	(arc
		(start 11.155172 -384.29438)
		(mid 10.772222 -384.867505)
		(end 10.637774 -385.543552)
		(width 0.09525)
		(layer "F.Cu")
		(net "SAS2X28_A_HDD2_TX_-")
	)
	(arc
		(start 25.375616 -362.70057)
		(mid 25.026879 -363.222681)
		(end 24.904446 -363.83849)
		(width 0.09525)
		(layer "F.Cu")
		(net "SAS2X28_A_HDD2_TX_-")
	)
	(arc
		(start 221.911926 -260.340094)
		(mid 221.863131 -260.330388)
		(end 221.821756 -260.302756)
		(width 0.09525)
		(layer "F.Cu")
		(net "SAS2X28_A_HDD2_TX_-")
	)
	(arc
		(start 221.784418 -260.265418)
		(mid 221.752858 -260.21809)
		(end 221.741746 -260.162294)
		(width 0.09525)
		(layer "F.Cu")
		(net "SAS2X28_A_HDD2_TX_-")
	)
	(arc
		(start 221.572836 -259.87629)
		(mid 221.540151 -259.869235)
		(end 221.506796 -259.866892)
		(width 0.09525)
		(layer "F.Cu")
		(net "SAS2X28_A_HDD2_TX_-")
	)
	(arc
		(start 10.637774 -390.55421)
		(mid 10.549386 -390.998187)
		(end 10.297922 -391.37463)
		(width 0.09525)
		(layer "F.Cu")
		(net "SAS2X28_A_HDD2_TX_-")
	)
	(arc
		(start 5.367274 -395.265402)
		(mid 5.107049 -395.439279)
		(end 4.800092 -395.500352)
		(width 0.09525)
		(layer "F.Cu")
		(net "SAS2X28_A_HDD2_TX_-")
	)
	(arc
		(start 218.529154 -259.86613)
		(mid 218.242912 -259.878645)
		(end 217.967052 -259.956046)
		(width 0.09525)
		(layer "F.Cu")
		(net "SAS2X28_A_HDD2_TX_-")
	)
	(arc
		(start 221.590108 -259.882132)
		(mid 221.581528 -259.879044)
		(end 221.572836 -259.87629)
		(width 0.09525)
		(layer "F.Cu")
		(net "SAS2X28_A_HDD2_TX_-")
	)
	(arc
		(start 6.787134 -394.885672)
		(mid 6.482144 -395.089367)
		(end 6.122416 -395.160754)
		(width 0.09525)
		(layer "F.Cu")
		(net "SAS2X28_A_HDD2_TX_-")
	)
	(arc
		(start 221.741746 -260.101842)
		(mid 221.700153 -259.96837)
		(end 221.590108 -259.882132)
		(width 0.09525)
		(layer "F.Cu")
		(net "SAS2X28_A_HDD2_TX_-")
	)
	(segment
		(start 12.446 -206.7814)
		(end 12.6746 -206.5528)
		(width 0.111252)
		(layer "F.Cu")
		(net "SAS_EXP_B_PWR13")
	)
	(segment
		(start 35.940746 -108.5977)
		(end 36.767008 -108.5977)
		(width 0.111252)
		(layer "F.Cu")
		(net "SAS_EXP_B_PWR13")
	)
	(segment
		(start 10.287 -206.7814)
		(end 12.446 -206.7814)
		(width 0.111252)
		(layer "F.Cu")
		(net "SAS_EXP_B_PWR13")
	)
	(segment
		(start 9.567164 -207.501236)
		(end 10.287 -206.7814)
		(width 0.111252)
		(layer "F.Cu")
		(net "SAS_EXP_B_PWR13")
	)
	(segment
		(start 3.193542 -207.501236)
		(end 9.567164 -207.501236)
		(width 0.111252)
		(layer "F.Cu")
		(net "SAS_EXP_B_PWR13")
	)
	(segment
		(start 35.829748 -108.486702)
		(end 35.940746 -108.5977)
		(width 0.111252)
		(layer "F.Cu")
		(net "SAS_EXP_B_PWR13")
	)
	(segment
		(start 36.767008 -108.5977)
		(end 36.941506 -108.423202)
		(width 0.111252)
		(layer "F.Cu")
		(net "SAS_EXP_B_PWR13")
	)
	(segment
		(start 3.19024 -207.504538)
		(end 3.193542 -207.501236)
		(width 0.111252)
		(layer "F.Cu")
		(net "SAS_EXP_B_PWR13")
	)
	(segment
		(start 34.988246 -108.486702)
		(end 35.829748 -108.486702)
		(width 0.111252)
		(layer "F.Cu")
		(net "SAS_EXP_B_PWR13")
	)
	(via
		(at 35.940746 -108.5977)
		(size 0.5588)
		(drill 0.3048)
		(layers "F.Cu" "B.Cu")
		(net "SAS_EXP_B_PWR13")
	)
	(via
		(at 39.318946 -212.8647)
		(size 0.5588)
		(drill 0.3048)
		(layers "F.Cu" "B.Cu")
		(net "SAS_EXP_B_PWR13")
	)
	(via
		(at 22.606 -207.391)
		(size 0.5588)
		(drill 0.3048)
		(layers "F.Cu" "B.Cu")
		(net "SAS_EXP_B_PWR13")
	)
	(via
		(at 12.6746 -206.5528)
		(size 0.5588)
		(drill 0.3048)
		(layers "F.Cu" "B.Cu")
		(net "SAS_EXP_B_PWR13")
	)
	(via
		(at 50.7746 -140.7287)
		(size 0.5588)
		(drill 0.3048)
		(layers "F.Cu" "B.Cu")
		(net "SAS_EXP_B_PWR13")
	)
	(via
		(at 36.829746 -108.0897)
		(size 0.7112)
		(drill 0.3556)
		(layers "F.Cu" "B.Cu")
		(net "SAS_EXP_B_PWR13")
	)
	(segment
		(start 12.6746 -206.5528)
		(end 13.5382 -205.6892)
		(width 0.111252)
		(layer "B.Cu")
		(net "SAS_EXP_B_PWR13")
	)
	(segment
		(start 13.5382 -205.6892)
		(end 20.6502 -205.6892)
		(width 0.111252)
		(layer "B.Cu")
		(net "SAS_EXP_B_PWR13")
	)
	(segment
		(start 22.352 -207.391)
		(end 22.606 -207.391)
		(width 0.111252)
		(layer "B.Cu")
		(net "SAS_EXP_B_PWR13")
	)
	(segment
		(start 35.940746 -108.5977)
		(end 36.321746 -108.5977)
		(width 0.111252)
		(layer "B.Cu")
		(net "SAS_EXP_B_PWR13")
	)
	(segment
		(start 20.6502 -205.6892)
		(end 22.352 -207.391)
		(width 0.111252)
		(layer "B.Cu")
		(net "SAS_EXP_B_PWR13")
	)
	(segment
		(start 36.321746 -108.5977)
		(end 36.829746 -108.0897)
		(width 0.111252)
		(layer "B.Cu")
		(net "SAS_EXP_B_PWR13")
	)
	(segment
		(start 39.243 -148.475954)
		(end 42.0878 -151.320754)
		(width 0.14605)
		(layer "In2.Cu")
		(net "SAS_EXP_B_PWR13")
	)
	(segment
		(start 39.630604 -193.1797)
		(end 39.630604 -212.553042)
		(width 0.14605)
		(layer "In2.Cu")
		(net "SAS_EXP_B_PWR13")
	)
	(segment
		(start 41.0083 -140.7287)
		(end 39.243 -142.494)
		(width 0.14605)
		(layer "In2.Cu")
		(net "SAS_EXP_B_PWR13")
	)
	(segment
		(start 42.0878 -151.320754)
		(end 42.0878 -190.722504)
		(width 0.14605)
		(layer "In2.Cu")
		(net "SAS_EXP_B_PWR13")
	)
	(segment
		(start 50.7746 -140.7287)
		(end 41.0083 -140.7287)
		(width 0.14605)
		(layer "In2.Cu")
		(net "SAS_EXP_B_PWR13")
	)
	(segment
		(start 39.630604 -212.553042)
		(end 39.318946 -212.8647)
		(width 0.14605)
		(layer "In2.Cu")
		(net "SAS_EXP_B_PWR13")
	)
	(segment
		(start 39.243 -142.494)
		(end 39.243 -148.475954)
		(width 0.14605)
		(layer "In2.Cu")
		(net "SAS_EXP_B_PWR13")
	)
	(segment
		(start 42.0878 -190.722504)
		(end 39.630604 -193.1797)
		(width 0.14605)
		(layer "In2.Cu")
		(net "SAS_EXP_B_PWR13")
	)
	(segment
		(start 39.533068 -113.649252)
		(end 50.7746 -124.890784)
		(width 0.14605)
		(layer "In5.Cu")
		(net "SAS_EXP_B_PWR13")
	)
	(segment
		(start 35.940746 -110.646972)
		(end 38.943026 -113.649252)
		(width 0.14605)
		(layer "In5.Cu")
		(net "SAS_EXP_B_PWR13")
	)
	(segment
		(start 22.606 -207.391)
		(end 22.380448 -207.616552)
		(width 0.14605)
		(layer "In5.Cu")
		(net "SAS_EXP_B_PWR13")
	)
	(segment
		(start 22.380448 -207.616552)
		(end 22.380448 -211.272628)
		(width 0.14605)
		(layer "In5.Cu")
		(net "SAS_EXP_B_PWR13")
	)
	(segment
		(start 38.943026 -113.649252)
		(end 39.533068 -113.649252)
		(width 0.14605)
		(layer "In5.Cu")
		(net "SAS_EXP_B_PWR13")
	)
	(segment
		(start 50.7746 -124.890784)
		(end 50.7746 -140.7287)
		(width 0.14605)
		(layer "In5.Cu")
		(net "SAS_EXP_B_PWR13")
	)
	(segment
		(start 24.013922 -212.906102)
		(end 38.683692 -212.906102)
		(width 0.14605)
		(layer "In5.Cu")
		(net "SAS_EXP_B_PWR13")
	)
	(segment
		(start 38.683692 -212.906102)
		(end 38.725094 -212.8647)
		(width 0.14605)
		(layer "In5.Cu")
		(net "SAS_EXP_B_PWR13")
	)
	(segment
		(start 35.940746 -108.5977)
		(end 35.940746 -110.646972)
		(width 0.14605)
		(layer "In5.Cu")
		(net "SAS_EXP_B_PWR13")
	)
	(segment
		(start 22.380448 -211.272628)
		(end 24.013922 -212.906102)
		(width 0.14605)
		(layer "In5.Cu")
		(net "SAS_EXP_B_PWR13")
	)
	(segment
		(start 38.725094 -212.8647)
		(end 39.318946 -212.8647)
		(width 0.14605)
		(layer "In5.Cu")
		(net "SAS_EXP_B_PWR13")
	)
	(via
		(at 53.847746 -83.1977)
		(size 0.7112)
		(drill 0.3556)
		(layers "F.Cu" "B.Cu")
		(net "12V_PRE_9")
	)
	(segment
		(start 27.897074 -204.875892)
		(end 13.11529 -204.875892)
		(width 0.111252)
		(layer "F.Cu")
		(net "HDD_PRSNT7")
	)
	(segment
		(start 55.722774 -271.6022)
		(end 56.3372 -271.6022)
		(width 0.111252)
		(layer "F.Cu")
		(net "HDD_PRSNT7")
	)
	(segment
		(start 55.245 -272.079974)
		(end 55.722774 -271.6022)
		(width 0.111252)
		(layer "F.Cu")
		(net "HDD_PRSNT7")
	)
	(segment
		(start 13.039598 -204.8002)
		(end 12.9794 -204.8002)
		(width 0.111252)
		(layer "F.Cu")
		(net "HDD_PRSNT7")
	)
	(segment
		(start 55.245 -275.336)
		(end 55.245 -272.079974)
		(width 0.111252)
		(layer "F.Cu")
		(net "HDD_PRSNT7")
	)
	(segment
		(start 13.11529 -204.875892)
		(end 13.039598 -204.8002)
		(width 0.111252)
		(layer "F.Cu")
		(net "HDD_PRSNT7")
	)
	(via
		(at 9.06145 -452.9963)
		(size 0.5588)
		(drill 0.3048)
		(layers "F.Cu" "B.Cu")
		(net "HDD_PRSNT7")
	)
	(via
		(at 56.3372 -271.6022)
		(size 0.5588)
		(drill 0.3048)
		(layers "F.Cu" "B.Cu")
		(net "HDD_PRSNT7")
	)
	(via
		(at 12.9794 -204.8002)
		(size 0.5588)
		(drill 0.3048)
		(layers "F.Cu" "B.Cu")
		(net "HDD_PRSNT7")
	)
	(via
		(at 86.537546 -265.705844)
		(size 0.5588)
		(drill 0.3048)
		(layers "F.Cu" "B.Cu")
		(net "HDD_PRSNT7")
	)
	(via
		(at 10.9982 -204.8002)
		(size 0.7112)
		(drill 0.3556)
		(layers "F.Cu" "B.Cu")
		(net "HDD_PRSNT7")
	)
	(via
		(at 27.897074 -204.875892)
		(size 0.5588)
		(drill 0.3048)
		(layers "F.Cu" "B.Cu")
		(net "HDD_PRSNT7")
	)
	(segment
		(start 9.060942 -452.996808)
		(end 7.746746 -452.996808)
		(width 0.111252)
		(layer "B.Cu")
		(net "HDD_PRSNT7")
	)
	(segment
		(start 10.699242 -204.501242)
		(end 10.9982 -204.8002)
		(width 0.111252)
		(layer "B.Cu")
		(net "HDD_PRSNT7")
	)
	(segment
		(start 7.746746 -452.996808)
		(end 6.242304 -454.50125)
		(width 0.111252)
		(layer "B.Cu")
		(net "HDD_PRSNT7")
	)
	(segment
		(start 2.812542 -454.50125)
		(end 2.80924 -454.504552)
		(width 0.111252)
		(layer "B.Cu")
		(net "HDD_PRSNT7")
	)
	(segment
		(start 9.06145 -452.9963)
		(end 9.060942 -452.996808)
		(width 0.111252)
		(layer "B.Cu")
		(net "HDD_PRSNT7")
	)
	(segment
		(start 2.80924 -204.504544)
		(end 2.812542 -204.501242)
		(width 0.111252)
		(layer "B.Cu")
		(net "HDD_PRSNT7")
	)
	(segment
		(start 10.9982 -204.8002)
		(end 12.9794 -204.8002)
		(width 0.111252)
		(layer "B.Cu")
		(net "HDD_PRSNT7")
	)
	(segment
		(start 2.812542 -204.501242)
		(end 10.699242 -204.501242)
		(width 0.111252)
		(layer "B.Cu")
		(net "HDD_PRSNT7")
	)
	(segment
		(start 6.242304 -454.50125)
		(end 2.812542 -454.50125)
		(width 0.111252)
		(layer "B.Cu")
		(net "HDD_PRSNT7")
	)
	(segment
		(start 8.738362 -452.673212)
		(end 8.738362 -439.70702)
		(width 0.14605)
		(layer "In2.Cu")
		(net "HDD_PRSNT7")
	)
	(segment
		(start 12.195048 -205.584552)
		(end 12.9794 -204.8002)
		(width 0.14605)
		(layer "In2.Cu")
		(net "HDD_PRSNT7")
	)
	(segment
		(start 13.845794 -217.299794)
		(end 13.845794 -212.135974)
		(width 0.14605)
		(layer "In2.Cu")
		(net "HDD_PRSNT7")
	)
	(segment
		(start 13.880338 -256.110232)
		(end 13.880338 -217.334338)
		(width 0.14605)
		(layer "In2.Cu")
		(net "HDD_PRSNT7")
	)
	(segment
		(start 13.563854 -394.489432)
		(end 14.131798 -393.921488)
		(width 0.14605)
		(layer "In2.Cu")
		(net "HDD_PRSNT7")
	)
	(segment
		(start 14.18844 -267.340842)
		(end 14.188186 -267.340588)
		(width 0.14605)
		(layer "In2.Cu")
		(net "HDD_PRSNT7")
	)
	(segment
		(start 12.195048 -207.960468)
		(end 12.195048 -205.584552)
		(width 0.14605)
		(layer "In2.Cu")
		(net "HDD_PRSNT7")
	)
	(segment
		(start 14.9606 -258.40055)
		(end 14.443202 -257.883152)
		(width 0.14605)
		(layer "In2.Cu")
		(net "HDD_PRSNT7")
	)
	(segment
		(start 12.41425 -210.70443)
		(end 12.41425 -208.17967)
		(width 0.14605)
		(layer "In2.Cu")
		(net "HDD_PRSNT7")
	)
	(segment
		(start 12.41425 -208.17967)
		(end 12.195048 -207.960468)
		(width 0.14605)
		(layer "In2.Cu")
		(net "HDD_PRSNT7")
	)
	(segment
		(start 13.28674 -414.80994)
		(end 13.461238 -414.635442)
		(width 0.14605)
		(layer "In2.Cu")
		(net "HDD_PRSNT7")
	)
	(segment
		(start 58.107326 -273.304)
		(end 58.039 -273.304)
		(width 0.14605)
		(layer "In2.Cu")
		(net "HDD_PRSNT7")
	)
	(segment
		(start 58.113676 -273.31035)
		(end 58.107326 -273.304)
		(width 0.14605)
		(layer "In2.Cu")
		(net "HDD_PRSNT7")
	)
	(segment
		(start 13.461238 -396.424404)
		(end 13.563854 -396.321788)
		(width 0.14605)
		(layer "In2.Cu")
		(net "HDD_PRSNT7")
	)
	(segment
		(start 14.443202 -256.673096)
		(end 13.880338 -256.110232)
		(width 0.14605)
		(layer "In2.Cu")
		(net "HDD_PRSNT7")
	)
	(segment
		(start 14.131798 -376.059192)
		(end 14.64945 -375.54154)
		(width 0.14605)
		(layer "In2.Cu")
		(net "HDD_PRSNT7")
	)
	(segment
		(start 13.461238 -414.635442)
		(end 13.461238 -396.424404)
		(width 0.14605)
		(layer "In2.Cu")
		(net "HDD_PRSNT7")
	)
	(segment
		(start 14.131798 -393.921488)
		(end 14.131798 -376.059192)
		(width 0.14605)
		(layer "In2.Cu")
		(net "HDD_PRSNT7")
	)
	(segment
		(start 8.738362 -439.70702)
		(end 13.28674 -435.158642)
		(width 0.14605)
		(layer "In2.Cu")
		(net "HDD_PRSNT7")
	)
	(segment
		(start 13.880338 -217.334338)
		(end 13.845794 -217.299794)
		(width 0.14605)
		(layer "In2.Cu")
		(net "HDD_PRSNT7")
	)
	(segment
		(start 86.29269 -265.9507)
		(end 68.3387 -265.9507)
		(width 0.14605)
		(layer "In2.Cu")
		(net "HDD_PRSNT7")
	)
	(segment
		(start 14.9606 -265.447018)
		(end 14.9606 -258.40055)
		(width 0.14605)
		(layer "In2.Cu")
		(net "HDD_PRSNT7")
	)
	(segment
		(start 14.18844 -365.412274)
		(end 14.18844 -267.340842)
		(width 0.14605)
		(layer "In2.Cu")
		(net "HDD_PRSNT7")
	)
	(segment
		(start 14.188186 -266.219432)
		(end 14.9606 -265.447018)
		(width 0.14605)
		(layer "In2.Cu")
		(net "HDD_PRSNT7")
	)
	(segment
		(start 60.97905 -273.31035)
		(end 58.113676 -273.31035)
		(width 0.14605)
		(layer "In2.Cu")
		(net "HDD_PRSNT7")
	)
	(segment
		(start 13.28674 -435.158642)
		(end 13.28674 -414.80994)
		(width 0.14605)
		(layer "In2.Cu")
		(net "HDD_PRSNT7")
	)
	(segment
		(start 13.845794 -212.135974)
		(end 12.41425 -210.70443)
		(width 0.14605)
		(layer "In2.Cu")
		(net "HDD_PRSNT7")
	)
	(segment
		(start 9.06145 -452.9963)
		(end 8.738362 -452.673212)
		(width 0.14605)
		(layer "In2.Cu")
		(net "HDD_PRSNT7")
	)
	(segment
		(start 14.188186 -267.340588)
		(end 14.188186 -266.219432)
		(width 0.14605)
		(layer "In2.Cu")
		(net "HDD_PRSNT7")
	)
	(segment
		(start 14.64945 -375.54154)
		(end 14.64945 -365.873284)
		(width 0.14605)
		(layer "In2.Cu")
		(net "HDD_PRSNT7")
	)
	(segment
		(start 86.537546 -265.705844)
		(end 86.29269 -265.9507)
		(width 0.14605)
		(layer "In2.Cu")
		(net "HDD_PRSNT7")
	)
	(segment
		(start 14.64945 -365.873284)
		(end 14.18844 -365.412274)
		(width 0.14605)
		(layer "In2.Cu")
		(net "HDD_PRSNT7")
	)
	(segment
		(start 68.3387 -265.9507)
		(end 60.97905 -273.31035)
		(width 0.14605)
		(layer "In2.Cu")
		(net "HDD_PRSNT7")
	)
	(segment
		(start 58.039 -273.304)
		(end 56.3372 -271.6022)
		(width 0.14605)
		(layer "In2.Cu")
		(net "HDD_PRSNT7")
	)
	(segment
		(start 13.563854 -396.321788)
		(end 13.563854 -394.489432)
		(width 0.14605)
		(layer "In2.Cu")
		(net "HDD_PRSNT7")
	)
	(segment
		(start 14.443202 -257.883152)
		(end 14.443202 -256.673096)
		(width 0.14605)
		(layer "In2.Cu")
		(net "HDD_PRSNT7")
	)
	(segment
		(start 28.091892 -204.875892)
		(end 27.897074 -204.875892)
		(width 0.14605)
		(layer "In5.Cu")
		(net "HDD_PRSNT7")
	)
	(segment
		(start 86.143846 -265.312144)
		(end 86.143846 -244.17401)
		(width 0.14605)
		(layer "In5.Cu")
		(net "HDD_PRSNT7")
	)
	(segment
		(start 28.3464 -205.1304)
		(end 28.091892 -204.875892)
		(width 0.14605)
		(layer "In5.Cu")
		(net "HDD_PRSNT7")
	)
	(segment
		(start 86.143846 -244.17401)
		(end 47.100236 -205.1304)
		(width 0.14605)
		(layer "In5.Cu")
		(net "HDD_PRSNT7")
	)
	(segment
		(start 86.537546 -265.705844)
		(end 86.143846 -265.312144)
		(width 0.14605)
		(layer "In5.Cu")
		(net "HDD_PRSNT7")
	)
	(segment
		(start 47.100236 -205.1304)
		(end 28.3464 -205.1304)
		(width 0.14605)
		(layer "In5.Cu")
		(net "HDD_PRSNT7")
	)
	(segment
		(start 223.098106 -267.744194)
		(end 223.002856 -267.83919)
		(width 0.09525)
		(layer "F.Cu")
		(net "SAS2X28_B_HDD2_TX_-")
	)
	(segment
		(start 225.399854 -267.789914)
		(end 224.60585 -267.789914)
		(width 0.09525)
		(layer "F.Cu")
		(net "SAS2X28_B_HDD2_TX_-")
	)
	(segment
		(start 224.319846 -267.6398)
		(end 224.217992 -267.5382)
		(width 0.09525)
		(layer "F.Cu")
		(net "SAS2X28_B_HDD2_TX_-")
	)
	(segment
		(start 224.010982 -267.4747)
		(end 223.748346 -267.4747)
		(width 0.09525)
		(layer "F.Cu")
		(net "SAS2X28_B_HDD2_TX_-")
	)
	(segment
		(start 6.349746 -116.160804)
		(end 5.502656 -116.160804)
		(width 0.09525)
		(layer "F.Cu")
		(net "SAS2X28_B_HDD2_TX_-")
	)
	(segment
		(start 224.370646 -267.6906)
		(end 224.319846 -267.6398)
		(width 0.09525)
		(layer "F.Cu")
		(net "SAS2X28_B_HDD2_TX_-")
	)
	(segment
		(start 224.60585 -267.789914)
		(end 224.602548 -267.786612)
		(width 0.09525)
		(layer "F.Cu")
		(net "SAS2X28_B_HDD2_TX_-")
	)
	(segment
		(start 4.68122 -116.498878)
		(end 3.192526 -116.498878)
		(width 0.09525)
		(layer "F.Cu")
		(net "SAS2X28_B_HDD2_TX_-")
	)
	(segment
		(start 6.806946 -116.458238)
		(end 6.622542 -116.273834)
		(width 0.09525)
		(layer "F.Cu")
		(net "SAS2X28_B_HDD2_TX_-")
	)
	(segment
		(start 4.682744 -116.500402)
		(end 4.68122 -116.498878)
		(width 0.09525)
		(layer "F.Cu")
		(net "SAS2X28_B_HDD2_TX_-")
	)
	(via
		(at 223.002856 -267.83919)
		(size 0.5588)
		(drill 0.3048)
		(layers "F.Cu" "B.Cu")
		(net "SAS2X28_B_HDD2_TX_-")
	)
	(via
		(at 6.806946 -116.458238)
		(size 0.5588)
		(drill 0.3048)
		(layers "F.Cu" "B.Cu")
		(net "SAS2X28_B_HDD2_TX_-")
	)
	(arc
		(start 224.032318 -267.475208)
		(mid 224.021654 -267.474786)
		(end 224.010982 -267.4747)
		(width 0.09525)
		(layer "F.Cu")
		(net "SAS2X28_B_HDD2_TX_-")
	)
	(arc
		(start 223.748346 -267.4747)
		(mid 223.396433 -267.544794)
		(end 223.098106 -267.744194)
		(width 0.09525)
		(layer "F.Cu")
		(net "SAS2X28_B_HDD2_TX_-")
	)
	(arc
		(start 224.602548 -267.786612)
		(mid 224.477061 -267.761651)
		(end 224.370646 -267.6906)
		(width 0.09525)
		(layer "F.Cu")
		(net "SAS2X28_B_HDD2_TX_-")
	)
	(arc
		(start 224.082864 -267.482066)
		(mid 224.057718 -267.477702)
		(end 224.032318 -267.475208)
		(width 0.09525)
		(layer "F.Cu")
		(net "SAS2X28_B_HDD2_TX_-")
	)
	(arc
		(start 6.622542 -116.273834)
		(mid 6.497382 -116.190205)
		(end 6.349746 -116.160804)
		(width 0.09525)
		(layer "F.Cu")
		(net "SAS2X28_B_HDD2_TX_-")
	)
	(arc
		(start 224.217992 -267.5382)
		(mid 224.15601 -267.496692)
		(end 224.082864 -267.482066)
		(width 0.09525)
		(layer "F.Cu")
		(net "SAS2X28_B_HDD2_TX_-")
	)
	(arc
		(start 5.502656 -116.160804)
		(mid 5.339357 -116.193286)
		(end 5.200904 -116.285772)
		(width 0.09525)
		(layer "F.Cu")
		(net "SAS2X28_B_HDD2_TX_-")
	)
	(arc
		(start 5.200904 -116.285772)
		(mid 4.96317 -116.444621)
		(end 4.682744 -116.500402)
		(width 0.09525)
		(layer "F.Cu")
		(net "SAS2X28_B_HDD2_TX_-")
	)
	(segment
		(start 45.568362 -119.190516)
		(end 45.568616 -119.190516)
		(width 0.09525)
		(layer "B.Cu")
		(net "SAS2X28_B_HDD2_TX_-")
	)
	(segment
		(start 221.091252 -270.30807)
		(end 221.091252 -268.1097)
		(width 0.09525)
		(layer "B.Cu")
		(net "SAS2X28_B_HDD2_TX_-")
	)
	(segment
		(start 45.568616 -119.190516)
		(end 196.702426 -270.32458)
		(width 0.09525)
		(layer "B.Cu")
		(net "SAS2X28_B_HDD2_TX_-")
	)
	(segment
		(start 12.141708 -118.364)
		(end 43.74515 -118.364)
		(width 0.09525)
		(layer "B.Cu")
		(net "SAS2X28_B_HDD2_TX_-")
	)
	(segment
		(start 222.956374 -267.792962)
		(end 223.002856 -267.83919)
		(width 0.09525)
		(layer "B.Cu")
		(net "SAS2X28_B_HDD2_TX_-")
	)
	(segment
		(start 220.85554 -270.834358)
		(end 220.885258 -270.804894)
		(width 0.09525)
		(layer "B.Cu")
		(net "SAS2X28_B_HDD2_TX_-")
	)
	(segment
		(start 9.646158 -116.478558)
		(end 11.100054 -117.932454)
		(width 0.09525)
		(layer "B.Cu")
		(net "SAS2X28_B_HDD2_TX_-")
	)
	(segment
		(start 221.259908 -267.702538)
		(end 221.309946 -267.6525)
		(width 0.09525)
		(layer "B.Cu")
		(net "SAS2X28_B_HDD2_TX_-")
	)
	(segment
		(start 198.498206 -271.068546)
		(end 220.289374 -271.068546)
		(width 0.09525)
		(layer "B.Cu")
		(net "SAS2X28_B_HDD2_TX_-")
	)
	(segment
		(start 221.677992 -267.5001)
		(end 222.249746 -267.5001)
		(width 0.09525)
		(layer "B.Cu")
		(net "SAS2X28_B_HDD2_TX_-")
	)
	(segment
		(start 7.121398 -116.143786)
		(end 8.83793 -116.143786)
		(width 0.09525)
		(layer "B.Cu")
		(net "SAS2X28_B_HDD2_TX_-")
	)
	(segment
		(start 45.446696 -119.06885)
		(end 45.568362 -119.190516)
		(width 0.09525)
		(layer "B.Cu")
		(net "SAS2X28_B_HDD2_TX_-")
	)
	(arc
		(start 196.702426 -270.32458)
		(mid 197.526336 -270.875129)
		(end 198.498206 -271.068546)
		(width 0.09525)
		(layer "B.Cu")
		(net "SAS2X28_B_HDD2_TX_-")
	)
	(arc
		(start 8.83793 -116.143786)
		(mid 9.275337 -116.230792)
		(end 9.646158 -116.478558)
		(width 0.09525)
		(layer "B.Cu")
		(net "SAS2X28_B_HDD2_TX_-")
	)
	(arc
		(start 222.249746 -267.5001)
		(mid 222.632181 -267.576265)
		(end 222.956374 -267.792962)
		(width 0.09525)
		(layer "B.Cu")
		(net "SAS2X28_B_HDD2_TX_-")
	)
	(arc
		(start 11.100054 -117.932454)
		(mid 11.577969 -118.251787)
		(end 12.141708 -118.364)
		(width 0.09525)
		(layer "B.Cu")
		(net "SAS2X28_B_HDD2_TX_-")
	)
	(arc
		(start 43.74515 -118.364)
		(mid 44.666038 -118.547176)
		(end 45.446696 -119.06885)
		(width 0.09525)
		(layer "B.Cu")
		(net "SAS2X28_B_HDD2_TX_-")
	)
	(arc
		(start 220.885258 -270.804894)
		(mid 221.03783 -270.577033)
		(end 221.091252 -270.30807)
		(width 0.09525)
		(layer "B.Cu")
		(net "SAS2X28_B_HDD2_TX_-")
	)
	(arc
		(start 221.309946 -267.6525)
		(mid 221.478807 -267.539671)
		(end 221.677992 -267.5001)
		(width 0.09525)
		(layer "B.Cu")
		(net "SAS2X28_B_HDD2_TX_-")
	)
	(arc
		(start 221.091252 -268.1097)
		(mid 221.135084 -267.889344)
		(end 221.259908 -267.702538)
		(width 0.09525)
		(layer "B.Cu")
		(net "SAS2X28_B_HDD2_TX_-")
	)
	(arc
		(start 220.289374 -271.068546)
		(mid 220.595702 -271.007645)
		(end 220.85554 -270.834358)
		(width 0.09525)
		(layer "B.Cu")
		(net "SAS2X28_B_HDD2_TX_-")
	)
	(arc
		(start 6.806946 -116.458238)
		(mid 6.899047 -116.235887)
		(end 7.121398 -116.143786)
		(width 0.09525)
		(layer "B.Cu")
		(net "SAS2X28_B_HDD2_TX_-")
	)
	(segment
		(start 203.690474 -388.6327)
		(end 203.690474 -390.878822)
		(width 0.508)
		(layer "F.Cu")
		(net "P3V3")
	)
	(segment
		(start 41.529 -238.0234)
		(end 43.4086 -239.903)
		(width 0.4064)
		(layer "F.Cu")
		(net "P3V3")
	)
	(segment
		(start 61.214 -375.50344)
		(end 61.214 -377.2154)
		(width 0.4064)
		(layer "F.Cu")
		(net "P3V3")
	)
	(segment
		(start 73.066656 -83.49361)
		(end 73.066656 -87.34679)
		(width 0.508)
		(layer "F.Cu")
		(net "P3V3")
	)
	(segment
		(start 214.769954 -481.8634)
		(end 208.149444 -481.8634)
		(width 0.508)
		(layer "F.Cu")
		(net "P3V3")
	)
	(segment
		(start 38.608 -132.207)
		(end 38.608 -132.286502)
		(width 0.508)
		(layer "F.Cu")
		(net "P3V3")
	)
	(segment
		(start 30.608778 -336.536284)
		(end 30.608778 -337.336384)
		(width 0.508)
		(layer "F.Cu")
		(net "P3V3")
	)
	(segment
		(start 73.405746 -186.3217)
		(end 73.608946 -186.5249)
		(width 0.508)
		(layer "F.Cu")
		(net "P3V3")
	)
	(segment
		(start 8.826246 -155.3337)
		(end 9.651746 -155.3337)
		(width 0.508)
		(layer "F.Cu")
		(net "P3V3")
	)
	(segment
		(start 203.02601 -460.663036)
		(end 200.164446 -460.663036)
		(width 1.016)
		(layer "F.Cu")
		(net "P3V3")
	)
	(segment
		(start 174.376842 -459.901036)
		(end 173.405546 -459.901036)
		(width 0.3048)
		(layer "F.Cu")
		(net "P3V3")
	)
	(segment
		(start 206.9084 -274.828)
		(end 207.264 -275.1836)
		(width 0.508)
		(layer "F.Cu")
		(net "P3V3")
	)
	(segment
		(start 174.872142 -460.396336)
		(end 174.634144 -460.158338)
		(width 0.508)
		(layer "F.Cu")
		(net "P3V3")
	)
	(segment
		(start 95.313246 -13.4747)
		(end 95.313246 -14.4907)
		(width 0.508)
		(layer "F.Cu")
		(net "P3V3")
	)
	(segment
		(start 83.184746 -77.3557)
		(end 78.756002 -72.926956)
		(width 0.508)
		(layer "F.Cu")
		(net "P3V3")
	)
	(segment
		(start 85.439758 -17.7927)
		(end 84.899246 -17.252188)
		(width 0.508)
		(layer "F.Cu")
		(net "P3V3")
	)
	(segment
		(start 34.543746 -432.6382)
		(end 34.543746 -432.49215)
		(width 0.508)
		(layer "F.Cu")
		(net "P3V3")
	)
	(segment
		(start 26.415746 -373.0117)
		(end 25.9715 -373.0117)
		(width 0.508)
		(layer "F.Cu")
		(net "P3V3")
	)
	(segment
		(start 78.756002 -72.926956)
		(end 61.468 -72.926956)
		(width 0.508)
		(layer "F.Cu")
		(net "P3V3")
	)
	(segment
		(start 164.413184 -462.060798)
		(end 163.66744 -462.060798)
		(width 0.508)
		(layer "F.Cu")
		(net "P3V3")
	)
	(segment
		(start 32.57042 -277.998428)
		(end 32.57042 -277.80742)
		(width 0.508)
		(layer "F.Cu")
		(net "P3V3")
	)
	(segment
		(start 63.3476 -381.7112)
		(end 63.754 -382.1176)
		(width 0.508)
		(layer "F.Cu")
		(net "P3V3")
	)
	(segment
		(start 203.009246 -183.5912)
		(end 203.009246 -185.9407)
		(width 0.508)
		(layer "F.Cu")
		(net "P3V3")
	)
	(segment
		(start 192.531746 -376.9487)
		(end 203.8477 -376.9487)
		(width 0.508)
		(layer "F.Cu")
		(net "P3V3")
	)
	(segment
		(start 85.026246 -187.4012)
		(end 85.026246 -188.2267)
		(width 0.508)
		(layer "F.Cu")
		(net "P3V3")
	)
	(segment
		(start 84.899246 -17.252188)
		(end 84.899246 -17.0307)
		(width 0.508)
		(layer "F.Cu")
		(net "P3V3")
	)
	(segment
		(start 57.276746 -381.7112)
		(end 63.3476 -381.7112)
		(width 0.508)
		(layer "F.Cu")
		(net "P3V3")
	)
	(segment
		(start 164.540946 -461.933036)
		(end 164.413184 -462.060798)
		(width 0.508)
		(layer "F.Cu")
		(net "P3V3")
	)
	(segment
		(start 29.349446 -373.0117)
		(end 29.362146 -372.999)
		(width 0.508)
		(layer "F.Cu")
		(net "P3V3")
	)
	(segment
		(start 43.57878 -135.45185)
		(end 43.575478 -135.455152)
		(width 0.3556)
		(layer "F.Cu")
		(net "P3V3")
	)
	(segment
		(start 174.634144 -460.158338)
		(end 174.376842 -459.901036)
		(width 0.3048)
		(layer "F.Cu")
		(net "P3V3")
	)
	(segment
		(start 177.177446 -460.599536)
		(end 176.161446 -460.599536)
		(width 0.508)
		(layer "F.Cu")
		(net "P3V3")
	)
	(segment
		(start 176.161446 -460.599536)
		(end 175.081946 -460.599536)
		(width 0.508)
		(layer "F.Cu")
		(net "P3V3")
	)
	(segment
		(start 58.356246 -176.1617)
		(end 59.067192 -176.1617)
		(width 0.508)
		(layer "F.Cu")
		(net "P3V3")
	)
	(segment
		(start 53.339746 -229.047802)
		(end 53.561234 -229.047802)
		(width 0.508)
		(layer "F.Cu")
		(net "P3V3")
	)
	(segment
		(start 61.47816 -72.916796)
		(end 61.468 -72.926956)
		(width 0.4064)
		(layer "F.Cu")
		(net "P3V3")
	)
	(segment
		(start 73.342246 -190.9572)
		(end 72.516746 -190.9572)
		(width 0.508)
		(layer "F.Cu")
		(net "P3V3")
	)
	(segment
		(start 59.067192 -176.1617)
		(end 59.0677 -176.162208)
		(width 0.508)
		(layer "F.Cu")
		(net "P3V3")
	)
	(segment
		(start 73.608946 -190.6905)
		(end 73.342246 -190.9572)
		(width 0.508)
		(layer "F.Cu")
		(net "P3V3")
	)
	(segment
		(start 207.616044 -481.104956)
		(end 207.616044 -481.33)
		(width 0.4064)
		(layer "F.Cu")
		(net "P3V3")
	)
	(segment
		(start 25.9715 -373.0117)
		(end 25.577546 -373.405654)
		(width 0.508)
		(layer "F.Cu")
		(net "P3V3")
	)
	(segment
		(start 30.111446 -377.2662)
		(end 30.027118 -377.181872)
		(width 0.3556)
		(layer "F.Cu")
		(net "P3V3")
	)
	(segment
		(start 197.141846 -459.901036)
		(end 197.141846 -459.479396)
		(width 0.508)
		(layer "F.Cu")
		(net "P3V3")
	)
	(segment
		(start 84.137246 -393.5222)
		(end 83.565746 -392.9507)
		(width 0.508)
		(layer "F.Cu")
		(net "P3V3")
	)
	(segment
		(start 164.286946 -460.853536)
		(end 164.096446 -461.044036)
		(width 0.508)
		(layer "F.Cu")
		(net "P3V3")
	)
	(segment
		(start 193.027046 -481.33)
		(end 207.616044 -481.33)
		(width 0.508)
		(layer "F.Cu")
		(net "P3V3")
	)
	(segment
		(start 73.066656 -87.34679)
		(end 72.707246 -87.7062)
		(width 0.508)
		(layer "F.Cu")
		(net "P3V3")
	)
	(segment
		(start 177.240946 -460.536036)
		(end 177.177446 -460.599536)
		(width 0.508)
		(layer "F.Cu")
		(net "P3V3")
	)
	(segment
		(start 43.941746 -130.800348)
		(end 43.941746 -131.0386)
		(width 0.508)
		(layer "F.Cu")
		(net "P3V3")
	)
	(segment
		(start 26.860246 -437.035702)
		(end 26.860246 -436.019702)
		(width 0.508)
		(layer "F.Cu")
		(net "P3V3")
	)
	(segment
		(start 192.658746 -480.9617)
		(end 193.027046 -481.33)
		(width 0.508)
		(layer "F.Cu")
		(net "P3V3")
	)
	(segment
		(start 61.468 -72.926956)
		(end 58.355992 -72.926956)
		(width 0.508)
		(layer "F.Cu")
		(net "P3V3")
	)
	(segment
		(start 84.137246 -394.6017)
		(end 84.137246 -393.5222)
		(width 0.508)
		(layer "F.Cu")
		(net "P3V3")
	)
	(segment
		(start 200.801986 -80.29194)
		(end 200.801986 -81.6102)
		(width 0.4064)
		(layer "F.Cu")
		(net "P3V3")
	)
	(segment
		(start 24.853646 -274.7518)
		(end 24.853646 -273.6596)
		(width 0.508)
		(layer "F.Cu")
		(net "P3V3")
	)
	(segment
		(start 72.846946 -392.7729)
		(end 72.846946 -396.6845)
		(width 0.508)
		(layer "F.Cu")
		(net "P3V3")
	)
	(segment
		(start 59.0677 -176.162208)
		(end 60.0583 -176.162208)
		(width 0.508)
		(layer "F.Cu")
		(net "P3V3")
	)
	(segment
		(start 211.585302 -43.252644)
		(end 212.280246 -42.5577)
		(width 0.3048)
		(layer "F.Cu")
		(net "P3V3")
	)
	(segment
		(start 208.8134 -378.6886)
		(end 208.8134 -376.72264)
		(width 0.4064)
		(layer "F.Cu")
		(net "P3V3")
	)
	(segment
		(start 27.4828 -244.7544)
		(end 27.686 -244.9576)
		(width 0.508)
		(layer "F.Cu")
		(net "P3V3")
	)
	(segment
		(start 27.177746 -310.861202)
		(end 26.336244 -310.861202)
		(width 0.508)
		(layer "F.Cu")
		(net "P3V3")
	)
	(segment
		(start 44.221146 -135.4709)
		(end 44.202096 -135.45185)
		(width 0.3048)
		(layer "F.Cu")
		(net "P3V3")
	)
	(segment
		(start 60.0583 -176.162208)
		(end 60.058808 -176.1617)
		(width 0.508)
		(layer "F.Cu")
		(net "P3V3")
	)
	(segment
		(start 201.421746 -80.1497)
		(end 202.310746 -80.1497)
		(width 0.508)
		(layer "F.Cu")
		(net "P3V3")
	)
	(segment
		(start 164.096446 -461.044036)
		(end 163.969446 -461.044036)
		(width 0.508)
		(layer "F.Cu")
		(net "P3V3")
	)
	(segment
		(start 211.585048 -455.317098)
		(end 211.585048 -456.944984)
		(width 0.3556)
		(layer "F.Cu")
		(net "P3V3")
	)
	(segment
		(start 203.009246 -287.2232)
		(end 203.009246 -287.7947)
		(width 0.508)
		(layer "F.Cu")
		(net "P3V3")
	)
	(segment
		(start 44.386246 -232.92943)
		(end 43.815 -233.500676)
		(width 0.508)
		(layer "F.Cu")
		(net "P3V3")
	)
	(segment
		(start 27.686 -244.9576)
		(end 27.686 -245.846854)
		(width 0.508)
		(layer "F.Cu")
		(net "P3V3")
	)
	(segment
		(start 177.6222 -461.3148)
		(end 177.240946 -460.933546)
		(width 0.508)
		(layer "F.Cu")
		(net "P3V3")
	)
	(segment
		(start 43.74896 -428.1932)
		(end 42.9514 -428.1932)
		(width 0.4064)
		(layer "F.Cu")
		(net "P3V3")
	)
	(segment
		(start 43.941746 -131.0386)
		(end 44.246546 -131.3434)
		(width 0.508)
		(layer "F.Cu")
		(net "P3V3")
	)
	(segment
		(start 178.9176 -461.3148)
		(end 177.6222 -461.3148)
		(width 0.508)
		(layer "F.Cu")
		(net "P3V3")
	)
	(segment
		(start 8.788146 -404.3934)
		(end 8.788146 -405.2062)
		(width 0.508)
		(layer "F.Cu")
		(net "P3V3")
	)
	(segment
		(start 61.32576 -176.15154)
		(end 61.3156 -176.1617)
		(width 0.4064)
		(layer "F.Cu")
		(net "P3V3")
	)
	(segment
		(start 212.407246 -453.903842)
		(end 212.407246 -454.1647)
		(width 0.508)
		(layer "F.Cu")
		(net "P3V3")
	)
	(segment
		(start 190.880746 -172.503592)
		(end 191.617854 -173.2407)
		(width 0.508)
		(layer "F.Cu")
		(net "P3V3")
	)
	(segment
		(start 208.149444 -481.8634)
		(end 207.616044 -481.33)
		(width 0.508)
		(layer "F.Cu")
		(net "P3V3")
	)
	(segment
		(start 71.246746 -87.7062)
		(end 72.389746 -87.7062)
		(width 0.508)
		(layer "F.Cu")
		(net "P3V3")
	)
	(segment
		(start 35.79876 -141.6558)
		(end 35.79876 -142.6972)
		(width 0.4064)
		(layer "F.Cu")
		(net "P3V3")
	)
	(segment
		(start 73.608946 -186.5249)
		(end 73.608946 -190.6905)
		(width 0.508)
		(layer "F.Cu")
		(net "P3V3")
	)
	(segment
		(start 179.07 -461.1624)
		(end 178.9176 -461.3148)
		(width 0.508)
		(layer "F.Cu")
		(net "P3V3")
	)
	(segment
		(start 43.4086 -239.903)
		(end 46.06036 -239.903)
		(width 0.4064)
		(layer "F.Cu")
		(net "P3V3")
	)
	(segment
		(start 26.796746 -304.384202)
		(end 26.209244 -303.7967)
		(width 0.508)
		(layer "F.Cu")
		(net "P3V3")
	)
	(segment
		(start 202.420474 -387.3627)
		(end 203.690474 -388.6327)
		(width 0.508)
		(layer "F.Cu")
		(net "P3V3")
	)
	(segment
		(start 54.000146 -228.60889)
		(end 54.000146 -228.447854)
		(width 0.508)
		(layer "F.Cu")
		(net "P3V3")
	)
	(segment
		(start 89.661746 -17.7927)
		(end 85.439758 -17.7927)
		(width 0.508)
		(layer "F.Cu")
		(net "P3V3")
	)
	(segment
		(start 203.8477 -376.9487)
		(end 205.5876 -378.6886)
		(width 0.508)
		(layer "F.Cu")
		(net "P3V3")
	)
	(segment
		(start 61.47816 -71.755)
		(end 61.47816 -72.916796)
		(width 0.4064)
		(layer "F.Cu")
		(net "P3V3")
	)
	(segment
		(start 187.019946 -458.885036)
		(end 186.067446 -458.885036)
		(width 0.508)
		(layer "F.Cu")
		(net "P3V3")
	)
	(segment
		(start 211.585048 -456.944984)
		(end 211.585302 -456.945238)
		(width 0.3556)
		(layer "F.Cu")
		(net "P3V3")
	)
	(segment
		(start 83.184746 -81.2927)
		(end 83.184746 -77.3557)
		(width 0.508)
		(layer "F.Cu")
		(net "P3V3")
	)
	(segment
		(start 82.549746 -184.7977)
		(end 82.676746 -184.9247)
		(width 0.508)
		(layer "F.Cu")
		(net "P3V3")
	)
	(segment
		(start 56.752744 -480.97821)
		(end 56.752744 -480.17811)
		(width 0.508)
		(layer "F.Cu")
		(net "P3V3")
	)
	(segment
		(start 33.527746 -432.6382)
		(end 32.702246 -432.6382)
		(width 0.508)
		(layer "F.Cu")
		(net "P3V3")
	)
	(segment
		(start 28.320746 -373.0117)
		(end 29.349446 -373.0117)
		(width 0.508)
		(layer "F.Cu")
		(net "P3V3")
	)
	(segment
		(start 56.7182 -479.0948)
		(end 57.277 -478.536)
		(width 0.4064)
		(layer "F.Cu")
		(net "P3V3")
	)
	(segment
		(start 206.152242 -274.2057)
		(end 206.774542 -274.828)
		(width 0.508)
		(layer "F.Cu")
		(net "P3V3")
	)
	(segment
		(start 33.654746 -278.3967)
		(end 33.654746 -278.0157)
		(width 0.508)
		(layer "F.Cu")
		(net "P3V3")
	)
	(segment
		(start 80.644746 -381.8382)
		(end 67.8434 -381.8382)
		(width 0.508)
		(layer "F.Cu")
		(net "P3V3")
	)
	(segment
		(start 25.044146 -378.8029)
		(end 25.475946 -379.2347)
		(width 0.508)
		(layer "F.Cu")
		(net "P3V3")
	)
	(segment
		(start 64.389 -382.7526)
		(end 63.754 -382.1176)
		(width 0.508)
		(layer "F.Cu")
		(net "P3V3")
	)
	(segment
		(start 54.000146 -228.447854)
		(end 54.6227 -227.8253)
		(width 0.508)
		(layer "F.Cu")
		(net "P3V3")
	)
	(segment
		(start 77.992732 -22.1107)
		(end 78.485746 -22.1107)
		(width 0.508)
		(layer "F.Cu")
		(net "P3V3")
	)
	(segment
		(start 27.686 -246.888)
		(end 27.686 -245.846854)
		(width 0.508)
		(layer "F.Cu")
		(net "P3V3")
	)
	(segment
		(start 11.8872 -103.8479)
		(end 11.8872 -103.1748)
		(width 0.508)
		(layer "F.Cu")
		(net "P3V3")
	)
	(segment
		(start 214.446612 -173.2407)
		(end 208.4324 -173.2407)
		(width 0.508)
		(layer "F.Cu")
		(net "P3V3")
	)
	(segment
		(start 212.407246 -454.1647)
		(end 212.407246 -454.4949)
		(width 0.3556)
		(layer "F.Cu")
		(net "P3V3")
	)
	(segment
		(start 212.343746 -40.6527)
		(end 212.280246 -40.7162)
		(width 0.508)
		(layer "F.Cu")
		(net "P3V3")
	)
	(segment
		(start 11.8872 -103.1748)
		(end 11.6332 -102.9208)
		(width 0.508)
		(layer "F.Cu")
		(net "P3V3")
	)
	(segment
		(start 33.841182 -431.789586)
		(end 33.80486 -431.789586)
		(width 0.508)
		(layer "F.Cu")
		(net "P3V3")
	)
	(segment
		(start 56.7182 -480.143566)
		(end 56.7182 -479.0948)
		(width 0.4064)
		(layer "F.Cu")
		(net "P3V3")
	)
	(segment
		(start 77.660246 -21.999702)
		(end 77.881734 -21.999702)
		(width 0.508)
		(layer "F.Cu")
		(net "P3V3")
	)
	(segment
		(start 86.225634 -493.625886)
		(end 87.025734 -493.625886)
		(width 0.508)
		(layer "F.Cu")
		(net "P3V3")
	)
	(segment
		(start 61.32576 -175.2346)
		(end 61.32576 -176.15154)
		(width 0.4064)
		(layer "F.Cu")
		(net "P3V3")
	)
	(segment
		(start 77.850746 -176.1617)
		(end 82.549746 -180.8607)
		(width 0.508)
		(layer "F.Cu")
		(net "P3V3")
	)
	(segment
		(start 27.797506 -275.7932)
		(end 26.923746 -275.7932)
		(width 0.508)
		(layer "F.Cu")
		(net "P3V3")
	)
	(segment
		(start 187.019946 -460.790036)
		(end 186.194446 -460.790036)
		(width 0.508)
		(layer "F.Cu")
		(net "P3V3")
	)
	(segment
		(start 83.565746 -81.6737)
		(end 83.184746 -81.2927)
		(width 0.508)
		(layer "F.Cu")
		(net "P3V3")
	)
	(segment
		(start 211.585302 -44.945046)
		(end 211.585302 -43.252644)
		(width 0.3048)
		(layer "F.Cu")
		(net "P3V3")
	)
	(segment
		(start 74.139044 -494.452402)
		(end 74.139044 -496.230402)
		(width 0.508)
		(layer "F.Cu")
		(net "P3V3")
	)
	(segment
		(start 212.724746 -452.1327)
		(end 212.724746 -453.586342)
		(width 0.508)
		(layer "F.Cu")
		(net "P3V3")
	)
	(segment
		(start 38.544246 -131.473702)
		(end 38.544246 -132.143246)
		(width 0.508)
		(layer "F.Cu")
		(net "P3V3")
	)
	(segment
		(start 200.164446 -460.663036)
		(end 198.894446 -460.663036)
		(width 1.016)
		(layer "F.Cu")
		(net "P3V3")
	)
	(segment
		(start 44.246546 -131.3434)
		(end 44.484798 -131.3434)
		(width 0.508)
		(layer "F.Cu")
		(net "P3V3")
	)
	(segment
		(start 208.4324 -173.2407)
		(end 208.4324 -170.85564)
		(width 0.4064)
		(layer "F.Cu")
		(net "P3V3")
	)
	(segment
		(start 214.814912 -71.354696)
		(end 213.994746 -71.354696)
		(width 0.508)
		(layer "F.Cu")
		(net "P3V3")
	)
	(segment
		(start 45.326046 -132.184648)
		(end 45.326046 -133.3119)
		(width 0.508)
		(layer "F.Cu")
		(net "P3V3")
	)
	(segment
		(start 201.421746 -285.6357)
		(end 203.009246 -287.2232)
		(width 0.508)
		(layer "F.Cu")
		(net "P3V3")
	)
	(segment
		(start 84.899246 -16.0147)
		(end 84.899246 -17.0307)
		(width 0.508)
		(layer "F.Cu")
		(net "P3V3")
	)
	(segment
		(start 31.190946 -378.3203)
		(end 31.190946 -377.2662)
		(width 0.508)
		(layer "F.Cu")
		(net "P3V3")
	)
	(segment
		(start 197.903846 -460.663036)
		(end 197.141846 -459.901036)
		(width 0.508)
		(layer "F.Cu")
		(net "P3V3")
	)
	(segment
		(start 192.404746 -274.2057)
		(end 206.152242 -274.2057)
		(width 0.508)
		(layer "F.Cu")
		(net "P3V3")
	)
	(segment
		(start 57.6072 -276.8727)
		(end 57.6072 -277.7236)
		(width 0.508)
		(layer "F.Cu")
		(net "P3V3")
	)
	(segment
		(start 206.774542 -274.828)
		(end 206.9084 -274.828)
		(width 0.508)
		(layer "F.Cu")
		(net "P3V3")
	)
	(segment
		(start 44.386246 -232.692702)
		(end 44.386246 -232.92943)
		(width 0.508)
		(layer "F.Cu")
		(net "P3V3")
	)
	(segment
		(start 212.280246 -40.7162)
		(end 212.280246 -42.5577)
		(width 0.508)
		(layer "F.Cu")
		(net "P3V3")
	)
	(segment
		(start 45.326046 -133.3119)
		(end 45.326046 -134.366)
		(width 0.508)
		(layer "F.Cu")
		(net "P3V3")
	)
	(segment
		(start 203.009246 -287.7947)
		(end 203.009246 -288.8107)
		(width 0.508)
		(layer "F.Cu")
		(net "P3V3")
	)
	(segment
		(start 31.9786 -277.2156)
		(end 31.9786 -277.185628)
		(width 0.508)
		(layer "F.Cu")
		(net "P3V3")
	)
	(segment
		(start 70.738746 -396.9512)
		(end 71.754746 -396.9512)
		(width 0.508)
		(layer "F.Cu")
		(net "P3V3")
	)
	(segment
		(start 32.57042 -277.80742)
		(end 31.9786 -277.2156)
		(width 0.508)
		(layer "F.Cu")
		(net "P3V3")
	)
	(segment
		(start 43.617388 -130.512058)
		(end 43.653456 -130.512058)
		(width 0.508)
		(layer "F.Cu")
		(net "P3V3")
	)
	(segment
		(start 82.676746 -390.7917)
		(end 82.676746 -383.8702)
		(width 0.508)
		(layer "F.Cu")
		(net "P3V3")
	)
	(segment
		(start 202.310746 -80.1497)
		(end 203.390246 -81.2292)
		(width 0.508)
		(layer "F.Cu")
		(net "P3V3")
	)
	(segment
		(start 203.309474 -495.168428)
		(end 203.834746 -495.6937)
		(width 0.508)
		(layer "F.Cu")
		(net "P3V3")
	)
	(segment
		(start 25.577546 -373.405654)
		(end 25.577546 -373.6467)
		(width 0.508)
		(layer "F.Cu")
		(net "P3V3")
	)
	(segment
		(start 205.5876 -378.6886)
		(end 208.8134 -378.6886)
		(width 0.508)
		(layer "F.Cu")
		(net "P3V3")
	)
	(segment
		(start 52.323746 -229.047802)
		(end 53.339746 -229.047802)
		(width 0.508)
		(layer "F.Cu")
		(net "P3V3")
	)
	(segment
		(start 86.225634 -494.641886)
		(end 87.121746 -494.641886)
		(width 0.508)
		(layer "F.Cu")
		(net "P3V3")
	)
	(segment
		(start 24.853646 -273.3548)
		(end 25.780746 -272.4277)
		(width 0.508)
		(layer "F.Cu")
		(net "P3V3")
	)
	(segment
		(start 203.309474 -493.875822)
		(end 203.309474 -493.063022)
		(width 0.508)
		(layer "F.Cu")
		(net "P3V3")
	)
	(segment
		(start 179.7304 -461.1624)
		(end 179.07 -461.1624)
		(width 0.508)
		(layer "F.Cu")
		(net "P3V3")
	)
	(segment
		(start 85.026246 -188.2267)
		(end 85.026246 -189.2427)
		(width 0.508)
		(layer "F.Cu")
		(net "P3V3")
	)
	(segment
		(start 42.468546 -131.3434)
		(end 41.541446 -131.3434)
		(width 0.508)
		(layer "F.Cu")
		(net "P3V3")
	)
	(segment
		(start 175.081946 -460.599536)
		(end 174.878746 -460.396336)
		(width 0.508)
		(layer "F.Cu")
		(net "P3V3")
	)
	(segment
		(start 56.752744 -480.17811)
		(end 56.7182 -480.143566)
		(width 0.4064)
		(layer "F.Cu")
		(net "P3V3")
	)
	(segment
		(start 214.903558 -379.043184)
		(end 214.548974 -378.6886)
		(width 0.508)
		(layer "F.Cu")
		(net "P3V3")
	)
	(segment
		(start 201.421746 -283.4767)
		(end 201.421746 -285.6357)
		(width 0.508)
		(layer "F.Cu")
		(net "P3V3")
	)
	(segment
		(start 29.362146 -371.6147)
		(end 27.177746 -369.4303)
		(width 0.508)
		(layer "F.Cu")
		(net "P3V3")
	)
	(segment
		(start 33.037018 -279.014428)
		(end 33.654746 -278.3967)
		(width 0.508)
		(layer "F.Cu")
		(net "P3V3")
	)
	(segment
		(start 24.853646 -273.6596)
		(end 24.853646 -273.3548)
		(width 0.508)
		(layer "F.Cu")
		(net "P3V3")
	)
	(segment
		(start 27.162506 -309.083202)
		(end 26.415746 -309.083202)
		(width 0.508)
		(layer "F.Cu")
		(net "P3V3")
	)
	(segment
		(start 204.235304 -452.966836)
		(end 204.235304 -459.453742)
		(width 1.016)
		(layer "F.Cu")
		(net "P3V3")
	)
	(segment
		(start 79.829406 -23.45436)
		(end 80.6196 -23.45436)
		(width 0.4064)
		(layer "F.Cu")
		(net "P3V3")
	)
	(segment
		(start 212.724746 -453.586342)
		(end 212.407246 -453.903842)
		(width 0.508)
		(layer "F.Cu")
		(net "P3V3")
	)
	(segment
		(start 215.027256 -482.120702)
		(end 214.769954 -481.8634)
		(width 0.508)
		(layer "F.Cu")
		(net "P3V3")
	)
	(segment
		(start 201.548746 -387.3627)
		(end 202.420474 -387.3627)
		(width 0.508)
		(layer "F.Cu")
		(net "P3V3")
	)
	(segment
		(start 208.3562 -273.16684)
		(end 208.3562 -274.0914)
		(width 0.4064)
		(layer "F.Cu")
		(net "P3V3")
	)
	(segment
		(start 204.235304 -459.453742)
		(end 203.02601 -460.663036)
		(width 1.016)
		(layer "F.Cu")
		(net "P3V3")
	)
	(segment
		(start 29.362146 -372.999)
		(end 29.362146 -371.6147)
		(width 0.508)
		(layer "F.Cu")
		(net "P3V3")
	)
	(segment
		(start 44.202096 -135.45185)
		(end 43.57878 -135.45185)
		(width 0.3556)
		(layer "F.Cu")
		(net "P3V3")
	)
	(segment
		(start 214.548974 -378.6886)
		(end 208.8134 -378.6886)
		(width 0.508)
		(layer "F.Cu")
		(net "P3V3")
	)
	(segment
		(start 21.297646 -254.1143)
		(end 20.497546 -254.1143)
		(width 0.508)
		(layer "F.Cu")
		(net "P3V3")
	)
	(segment
		(start 63.754 -379.7554)
		(end 63.754 -382.1176)
		(width 0.4064)
		(layer "F.Cu")
		(net "P3V3")
	)
	(segment
		(start 29.844746 -432.463702)
		(end 29.844746 -433.3367)
		(width 0.508)
		(layer "F.Cu")
		(net "P3V3")
	)
	(segment
		(start 208.3562 -274.0914)
		(end 207.264 -275.1836)
		(width 0.4064)
		(layer "F.Cu")
		(net "P3V3")
	)
	(segment
		(start 59.5884 -271.0688)
		(end 59.5884 -271.526)
		(width 0.4064)
		(layer "F.Cu")
		(net "P3V3")
	)
	(segment
		(start 32.57042 -279.014428)
		(end 33.037018 -279.014428)
		(width 0.508)
		(layer "F.Cu")
		(net "P3V3")
	)
	(segment
		(start 73.779634 -496.589812)
		(end 73.242932 -496.589812)
		(width 0.508)
		(layer "F.Cu")
		(net "P3V3")
	)
	(segment
		(start 78.485746 -22.1107)
		(end 79.829406 -23.45436)
		(width 0.4064)
		(layer "F.Cu")
		(net "P3V3")
	)
	(segment
		(start 72.707246 -87.7062)
		(end 72.389746 -87.7062)
		(width 0.508)
		(layer "F.Cu")
		(net "P3V3")
	)
	(segment
		(start 67.8434 -381.8382)
		(end 66.929 -382.7526)
		(width 0.508)
		(layer "F.Cu")
		(net "P3V3")
	)
	(segment
		(start 164.858446 -460.853536)
		(end 164.286946 -460.853536)
		(width 0.508)
		(layer "F.Cu")
		(net "P3V3")
	)
	(segment
		(start 203.690474 -390.878822)
		(end 203.690474 -391.894822)
		(width 0.508)
		(layer "F.Cu")
		(net "P3V3")
	)
	(segment
		(start 30.276546 -379.2347)
		(end 31.190946 -378.3203)
		(width 0.508)
		(layer "F.Cu")
		(net "P3V3")
	)
	(segment
		(start 43.653456 -130.512058)
		(end 43.941746 -130.800348)
		(width 0.508)
		(layer "F.Cu")
		(net "P3V3")
	)
	(segment
		(start 208.9658 -479.7552)
		(end 207.616044 -481.104956)
		(width 0.4064)
		(layer "F.Cu")
		(net "P3V3")
	)
	(segment
		(start 21.297646 -255.1303)
		(end 20.497546 -255.1303)
		(width 0.508)
		(layer "F.Cu")
		(net "P3V3")
	)
	(segment
		(start 177.240946 -460.933546)
		(end 177.240946 -460.536036)
		(width 0.508)
		(layer "F.Cu")
		(net "P3V3")
	)
	(segment
		(start 214.397082 -276.197568)
		(end 208.277968 -276.197568)
		(width 0.508)
		(layer "F.Cu")
		(net "P3V3")
	)
	(segment
		(start 187.019946 -456.853036)
		(end 186.219846 -456.853036)
		(width 0.508)
		(layer "F.Cu")
		(net "P3V3")
	)
	(segment
		(start 200.547986 -284.25394)
		(end 200.547986 -285.8262)
		(width 0.4064)
		(layer "F.Cu")
		(net "P3V3")
	)
	(segment
		(start 198.894446 -460.663036)
		(end 197.903846 -460.663036)
		(width 0.508)
		(layer "F.Cu")
		(net "P3V3")
	)
	(segment
		(start 29.590746 -336.515202)
		(end 29.590746 -337.315302)
		(width 0.508)
		(layer "F.Cu")
		(net "P3V3")
	)
	(segment
		(start 82.676746 -383.8702)
		(end 80.644746 -381.8382)
		(width 0.508)
		(layer "F.Cu")
		(net "P3V3")
	)
	(segment
		(start 27.812746 -304.384202)
		(end 27.812746 -304.0507)
		(width 0.508)
		(layer "F.Cu")
		(net "P3V3")
	)
	(segment
		(start 72.846946 -396.6845)
		(end 72.580246 -396.9512)
		(width 0.508)
		(layer "F.Cu")
		(net "P3V3")
	)
	(segment
		(start 72.580246 -396.9512)
		(end 71.754746 -396.9512)
		(width 0.508)
		(layer "F.Cu")
		(net "P3V3")
	)
	(segment
		(start 71.500746 -190.9572)
		(end 72.516746 -190.9572)
		(width 0.508)
		(layer "F.Cu")
		(net "P3V3")
	)
	(segment
		(start 174.878746 -460.396336)
		(end 174.872142 -460.396336)
		(width 0.508)
		(layer "F.Cu")
		(net "P3V3")
	)
	(segment
		(start 72.226932 -496.589812)
		(end 73.242932 -496.589812)
		(width 0.508)
		(layer "F.Cu")
		(net "P3V3")
	)
	(segment
		(start 53.561234 -229.047802)
		(end 54.000146 -228.60889)
		(width 0.508)
		(layer "F.Cu")
		(net "P3V3")
	)
	(segment
		(start 208.9658 -479.44024)
		(end 208.9658 -479.7552)
		(width 0.4064)
		(layer "F.Cu")
		(net "P3V3")
	)
	(segment
		(start 83.565746 -392.9507)
		(end 83.311746 -392.9507)
		(width 0.508)
		(layer "F.Cu")
		(net "P3V3")
	)
	(segment
		(start 84.137246 -394.6017)
		(end 84.137246 -395.6177)
		(width 0.508)
		(layer "F.Cu")
		(net "P3V3")
	)
	(segment
		(start 60.058808 -176.1617)
		(end 61.3156 -176.1617)
		(width 0.508)
		(layer "F.Cu")
		(net "P3V3")
	)
	(segment
		(start 30.027118 -377.181872)
		(end 29.478732 -377.181872)
		(width 0.3556)
		(layer "F.Cu")
		(net "P3V3")
	)
	(segment
		(start 208.8134 -68.59524)
		(end 208.8134 -70.993)
		(width 0.4064)
		(layer "F.Cu")
		(net "P3V3")
	)
	(segment
		(start 191.617854 -173.2407)
		(end 208.4324 -173.2407)
		(width 0.508)
		(layer "F.Cu")
		(net "P3V3")
	)
	(segment
		(start 59.309 -270.7894)
		(end 59.5884 -271.0688)
		(width 0.4064)
		(layer "F.Cu")
		(net "P3V3")
	)
	(segment
		(start 27.812746 -304.0507)
		(end 27.177746 -303.4157)
		(width 0.508)
		(layer "F.Cu")
		(net "P3V3")
	)
	(segment
		(start 34.5059 -335.8515)
		(end 35.08756 -336.43316)
		(width 0.4064)
		(layer "F.Cu")
		(net "P3V3")
	)
	(segment
		(start 203.42606 -452.157592)
		(end 204.235304 -452.966836)
		(width 1.016)
		(layer "F.Cu")
		(net "P3V3")
	)
	(segment
		(start 61.3156 -176.1617)
		(end 77.850746 -176.1617)
		(width 0.508)
		(layer "F.Cu")
		(net "P3V3")
	)
	(segment
		(start 203.309474 -494.891822)
		(end 203.309474 -495.168428)
		(width 0.508)
		(layer "F.Cu")
		(net "P3V3")
	)
	(segment
		(start 34.543746 -432.49215)
		(end 33.841182 -431.789586)
		(width 0.508)
		(layer "F.Cu")
		(net "P3V3")
	)
	(segment
		(start 44.484798 -131.3434)
		(end 45.326046 -132.184648)
		(width 0.508)
		(layer "F.Cu")
		(net "P3V3")
	)
	(segment
		(start 26.209244 -303.7967)
		(end 26.1366 -303.7967)
		(width 0.508)
		(layer "F.Cu")
		(net "P3V3")
	)
	(segment
		(start 54.6227 -227.8253)
		(end 54.8386 -227.8253)
		(width 0.508)
		(layer "F.Cu")
		(net "P3V3")
	)
	(segment
		(start 74.421746 -494.1697)
		(end 74.139044 -494.452402)
		(width 0.508)
		(layer "F.Cu")
		(net "P3V3")
	)
	(segment
		(start 35.08756 -336.43316)
		(end 35.56 -336.43316)
		(width 0.4064)
		(layer "F.Cu")
		(net "P3V3")
	)
	(segment
		(start 25.475946 -379.2347)
		(end 30.276546 -379.2347)
		(width 0.508)
		(layer "F.Cu")
		(net "P3V3")
	)
	(segment
		(start 61.214 -377.2154)
		(end 63.754 -379.7554)
		(width 0.4064)
		(layer "F.Cu")
		(net "P3V3")
	)
	(segment
		(start 214.489284 -173.198028)
		(end 214.446612 -173.2407)
		(width 0.508)
		(layer "F.Cu")
		(net "P3V3")
	)
	(segment
		(start 203.009246 -186.9567)
		(end 203.009246 -185.9407)
		(width 0.508)
		(layer "F.Cu")
		(net "P3V3")
	)
	(segment
		(start 202.056746 -182.6387)
		(end 203.009246 -183.5912)
		(width 0.508)
		(layer "F.Cu")
		(net "P3V3")
	)
	(segment
		(start 41.541446 -131.3434)
		(end 40.436546 -131.3434)
		(width 0.508)
		(layer "F.Cu")
		(net "P3V3")
	)
	(segment
		(start 26.860246 -436.019702)
		(end 26.860246 -435.038246)
		(width 0.762)
		(layer "F.Cu")
		(net "P3V3")
	)
	(segment
		(start 29.478732 -377.181872)
		(end 29.47543 -377.185174)
		(width 0.3556)
		(layer "F.Cu")
		(net "P3V3")
	)
	(segment
		(start 77.881734 -21.999702)
		(end 77.992732 -22.1107)
		(width 0.508)
		(layer "F.Cu")
		(net "P3V3")
	)
	(segment
		(start 74.139044 -496.230402)
		(end 73.779634 -496.589812)
		(width 0.508)
		(layer "F.Cu")
		(net "P3V3")
	)
	(segment
		(start 66.929 -382.7526)
		(end 64.389 -382.7526)
		(width 0.508)
		(layer "F.Cu")
		(net "P3V3")
	)
	(segment
		(start 57.277 -478.536)
		(end 57.277 -478.27184)
		(width 0.4064)
		(layer "F.Cu")
		(net "P3V3")
	)
	(segment
		(start 27.686 -245.846854)
		(end 27.673046 -245.8339)
		(width 0.508)
		(layer "F.Cu")
		(net "P3V3")
	)
	(segment
		(start 31.190946 -377.2662)
		(end 30.111446 -377.2662)
		(width 0.508)
		(layer "F.Cu")
		(net "P3V3")
	)
	(segment
		(start 45.326046 -134.366)
		(end 44.221146 -135.4709)
		(width 0.508)
		(layer "F.Cu")
		(net "P3V3")
	)
	(segment
		(start 203.390246 -85.3567)
		(end 203.390246 -84.3407)
		(width 0.508)
		(layer "F.Cu")
		(net "P3V3")
	)
	(segment
		(start 203.390246 -81.2292)
		(end 203.390246 -84.3407)
		(width 0.508)
		(layer "F.Cu")
		(net "P3V3")
	)
	(segment
		(start 208.277968 -276.197568)
		(end 207.264 -275.1836)
		(width 0.508)
		(layer "F.Cu")
		(net "P3V3")
	)
	(segment
		(start 212.407246 -454.4949)
		(end 211.585048 -455.317098)
		(width 0.3556)
		(layer "F.Cu")
		(net "P3V3")
	)
	(segment
		(start 38.544246 -132.143246)
		(end 38.608 -132.207)
		(width 0.508)
		(layer "F.Cu")
		(net "P3V3")
	)
	(segment
		(start 82.549746 -180.8607)
		(end 82.549746 -184.7977)
		(width 0.508)
		(layer "F.Cu")
		(net "P3V3")
	)
	(via
		(at 249.2248 -412.9532)
		(size 0.5588)
		(drill 0.3048)
		(layers "F.Cu" "B.Cu")
		(net "P3V3")
	)
	(via
		(at 90.169746 -18.3007)
		(size 0.5588)
		(drill 0.3048)
		(layers "F.Cu" "B.Cu")
		(net "P3V3")
	)
	(via
		(at 38.607746 -237.8837)
		(size 0.7112)
		(drill 0.4064)
		(layers "F.Cu" "B.Cu")
		(net "P3V3")
	)
	(via
		(at 195.325746 -490.2327)
		(size 0.7112)
		(drill 0.4064)
		(layers "F.Cu" "B.Cu")
		(net "P3V3")
	)
	(via
		(at 30.608778 -337.336384)
		(size 0.5588)
		(drill 0.3048)
		(layers "F.Cu" "B.Cu")
		(net "P3V3")
	)
	(via
		(at 191.174878 -451.991984)
		(size 0.7112)
		(drill 0.4064)
		(layers "F.Cu" "B.Cu")
		(net "P3V3")
	)
	(via
		(at 96.900746 -16.6497)
		(size 0.7112)
		(drill 0.4064)
		(layers "F.Cu" "B.Cu")
		(net "P3V3")
	)
	(via
		(at 42.9514 -428.1932)
		(size 0.5588)
		(drill 0.3048)
		(layers "F.Cu" "B.Cu")
		(net "P3V3")
	)
	(via
		(at 189.229746 -181.7497)
		(size 0.7112)
		(drill 0.4064)
		(layers "F.Cu" "B.Cu")
		(net "P3V3")
	)
	(via
		(at 141.858746 -156.4767)
		(size 0.7112)
		(drill 0.4064)
		(layers "F.Cu" "B.Cu")
		(net "P3V3")
	)
	(via
		(at 20.497546 -255.1303)
		(size 0.5588)
		(drill 0.3048)
		(layers "F.Cu" "B.Cu")
		(net "P3V3")
	)
	(via
		(at 143.128746 -380.3777)
		(size 0.7112)
		(drill 0.4064)
		(layers "F.Cu" "B.Cu")
		(net "P3V3")
	)
	(via
		(at 33.146746 -439.4327)
		(size 0.7112)
		(drill 0.4064)
		(layers "F.Cu" "B.Cu")
		(net "P3V3")
	)
	(via
		(at 192.531746 -40.3987)
		(size 0.7112)
		(drill 0.4064)
		(layers "F.Cu" "B.Cu")
		(net "P3V3")
	)
	(via
		(at 49.529746 -124.4727)
		(size 0.7112)
		(drill 0.4064)
		(layers "F.Cu" "B.Cu")
		(net "P3V3")
	)
	(via
		(at 25.577546 -373.6467)
		(size 0.5588)
		(drill 0.3048)
		(layers "F.Cu" "B.Cu")
		(net "P3V3")
	)
	(via
		(at 25.044146 -378.8029)
		(size 0.5588)
		(drill 0.3048)
		(layers "F.Cu" "B.Cu")
		(net "P3V3")
	)
	(via
		(at 96.900746 -17.7927)
		(size 0.7112)
		(drill 0.4064)
		(layers "F.Cu" "B.Cu")
		(net "P3V3")
	)
	(via
		(at 141.731746 -81.9277)
		(size 0.7112)
		(drill 0.4064)
		(layers "F.Cu" "B.Cu")
		(net "P3V3")
	)
	(via
		(at 191.403732 -449.566284)
		(size 0.7112)
		(drill 0.4064)
		(layers "F.Cu" "B.Cu")
		(net "P3V3")
	)
	(via
		(at 26.415746 -309.083202)
		(size 0.5588)
		(drill 0.3048)
		(layers "F.Cu" "B.Cu")
		(net "P3V3")
	)
	(via
		(at 140.842746 -158.6357)
		(size 0.7112)
		(drill 0.4064)
		(layers "F.Cu" "B.Cu")
		(net "P3V3")
	)
	(via
		(at 54.736746 -224.4217)
		(size 0.7112)
		(drill 0.4064)
		(layers "F.Cu" "B.Cu")
		(net "P3V3")
	)
	(via
		(at 190.499746 -284.3657)
		(size 0.7112)
		(drill 0.4064)
		(layers "F.Cu" "B.Cu")
		(net "P3V3")
	)
	(via
		(at 41.529 -238.0234)
		(size 0.5588)
		(drill 0.3048)
		(layers "F.Cu" "B.Cu")
		(net "P3V3")
	)
	(via
		(at 57.6072 -277.7236)
		(size 0.5588)
		(drill 0.3048)
		(layers "F.Cu" "B.Cu")
		(net "P3V3")
	)
	(via
		(at 27.4828 -244.7544)
		(size 0.5588)
		(drill 0.3048)
		(layers "F.Cu" "B.Cu")
		(net "P3V3")
	)
	(via
		(at 196.595746 -488.5817)
		(size 0.7112)
		(drill 0.4064)
		(layers "F.Cu" "B.Cu")
		(net "P3V3")
	)
	(via
		(at 191.515746 -39.2557)
		(size 0.7112)
		(drill 0.4064)
		(layers "F.Cu" "B.Cu")
		(net "P3V3")
	)
	(via
		(at 36.702746 -439.3057)
		(size 0.7112)
		(drill 0.4064)
		(layers "F.Cu" "B.Cu")
		(net "P3V3")
	)
	(via
		(at 25.653746 -279.2857)
		(size 0.7112)
		(drill 0.4064)
		(layers "F.Cu" "B.Cu")
		(net "P3V3")
	)
	(via
		(at 38.734746 -207.2767)
		(size 0.7112)
		(drill 0.4064)
		(layers "F.Cu" "B.Cu")
		(net "P3V3")
	)
	(via
		(at 192.531746 -376.9487)
		(size 0.5588)
		(drill 0.3048)
		(layers "F.Cu" "B.Cu")
		(net "P3V3")
	)
	(via
		(at 95.757746 -16.6497)
		(size 0.7112)
		(drill 0.4064)
		(layers "F.Cu" "B.Cu")
		(net "P3V3")
	)
	(via
		(at 195.071746 -488.4547)
		(size 0.7112)
		(drill 0.4064)
		(layers "F.Cu" "B.Cu")
		(net "P3V3")
	)
	(via
		(at 141.731746 -82.9437)
		(size 0.7112)
		(drill 0.4064)
		(layers "F.Cu" "B.Cu")
		(net "P3V3")
	)
	(via
		(at 190.754 -387.35)
		(size 0.7112)
		(drill 0.4064)
		(layers "F.Cu" "B.Cu")
		(net "P3V3")
	)
	(via
		(at 143.128746 -378.9807)
		(size 0.7112)
		(drill 0.4064)
		(layers "F.Cu" "B.Cu")
		(net "P3V3")
	)
	(via
		(at 11.6332 -102.9208)
		(size 0.5588)
		(drill 0.3048)
		(layers "F.Cu" "B.Cu")
		(net "P3V3")
	)
	(via
		(at 186.219846 -456.853036)
		(size 0.5588)
		(drill 0.3048)
		(layers "F.Cu" "B.Cu")
		(net "P3V3")
	)
	(via
		(at 20.497546 -254.1143)
		(size 0.5588)
		(drill 0.3048)
		(layers "F.Cu" "B.Cu")
		(net "P3V3")
	)
	(via
		(at 30.327346 -329.720702)
		(size 0.5588)
		(drill 0.3048)
		(layers "F.Cu" "B.Cu")
		(net "P3V3")
	)
	(via
		(at 190.372746 -181.8767)
		(size 0.7112)
		(drill 0.4064)
		(layers "F.Cu" "B.Cu")
		(net "P3V3")
	)
	(via
		(at 190.499746 -182.8927)
		(size 0.7112)
		(drill 0.4064)
		(layers "F.Cu" "B.Cu")
		(net "P3V3")
	)
	(via
		(at 141.714982 -84.07654)
		(size 0.7112)
		(drill 0.4064)
		(layers "F.Cu" "B.Cu")
		(net "P3V3")
	)
	(via
		(at 25.653746 -278.1427)
		(size 0.7112)
		(drill 0.4064)
		(layers "F.Cu" "B.Cu")
		(net "P3V3")
	)
	(via
		(at 26.67 -279.527)
		(size 0.7112)
		(drill 0.4064)
		(layers "F.Cu" "B.Cu")
		(net "P3V3")
	)
	(via
		(at 190.245746 -283.3497)
		(size 0.7112)
		(drill 0.4064)
		(layers "F.Cu" "B.Cu")
		(net "P3V3")
	)
	(via
		(at 140.842746 -157.4927)
		(size 0.7112)
		(drill 0.4064)
		(layers "F.Cu" "B.Cu")
		(net "P3V3")
	)
	(via
		(at 34.5059 -335.8515)
		(size 0.5588)
		(drill 0.3048)
		(layers "F.Cu" "B.Cu")
		(net "P3V3")
	)
	(via
		(at 192.023746 -450.9897)
		(size 0.7112)
		(drill 0.4064)
		(layers "F.Cu" "B.Cu")
		(net "P3V3")
	)
	(via
		(at 192.409572 -449.711318)
		(size 0.7112)
		(drill 0.4064)
		(layers "F.Cu" "B.Cu")
		(net "P3V3")
	)
	(via
		(at 192.180718 -452.137018)
		(size 0.7112)
		(drill 0.4064)
		(layers "F.Cu" "B.Cu")
		(net "P3V3")
	)
	(via
		(at 163.66744 -462.060798)
		(size 0.5588)
		(drill 0.3048)
		(layers "F.Cu" "B.Cu")
		(net "P3V3")
	)
	(via
		(at 143.128746 -381.9017)
		(size 0.7112)
		(drill 0.4064)
		(layers "F.Cu" "B.Cu")
		(net "P3V3")
	)
	(via
		(at 38.734746 -205.8797)
		(size 0.7112)
		(drill 0.4064)
		(layers "F.Cu" "B.Cu")
		(net "P3V3")
	)
	(via
		(at 26.923746 -275.7932)
		(size 0.5588)
		(drill 0.3048)
		(layers "F.Cu" "B.Cu")
		(net "P3V3")
	)
	(via
		(at 35.433 -439.547)
		(size 0.7112)
		(drill 0.4064)
		(layers "F.Cu" "B.Cu")
		(net "P3V3")
	)
	(via
		(at 54.863746 -225.4377)
		(size 0.7112)
		(drill 0.4064)
		(layers "F.Cu" "B.Cu")
		(net "P3V3")
	)
	(via
		(at 186.067446 -458.885036)
		(size 0.5588)
		(drill 0.3048)
		(layers "F.Cu" "B.Cu")
		(net "P3V3")
	)
	(via
		(at 78.485746 -22.1107)
		(size 0.5588)
		(drill 0.3048)
		(layers "F.Cu" "B.Cu")
		(net "P3V3")
	)
	(via
		(at 33.80486 -431.789586)
		(size 0.5588)
		(drill 0.3048)
		(layers "F.Cu" "B.Cu")
		(net "P3V3")
	)
	(via
		(at 37.4142 -133.7818)
		(size 0.7112)
		(drill 0.4064)
		(layers "F.Cu" "B.Cu")
		(net "P3V3")
	)
	(via
		(at 104.4702 -83.312)
		(size 0.7112)
		(drill 0.3556)
		(layers "F.Cu" "B.Cu")
		(net "P3V3")
	)
	(via
		(at 87.025734 -493.625886)
		(size 0.5588)
		(drill 0.3048)
		(layers "F.Cu" "B.Cu")
		(net "P3V3")
	)
	(via
		(at 126.0602 -378.968)
		(size 0.7112)
		(drill 0.3556)
		(layers "F.Cu" "B.Cu")
		(net "P3V3")
	)
	(via
		(at 192.404746 -274.2057)
		(size 0.5588)
		(drill 0.3048)
		(layers "F.Cu" "B.Cu")
		(net "P3V3")
	)
	(via
		(at 29.844746 -433.3367)
		(size 0.5588)
		(drill 0.3048)
		(layers "F.Cu" "B.Cu")
		(net "P3V3")
	)
	(via
		(at 190.880746 -172.503592)
		(size 0.7112)
		(drill 0.4064)
		(layers "F.Cu" "B.Cu")
		(net "P3V3")
	)
	(via
		(at 77.977746 -490.8677)
		(size 0.7112)
		(drill 0.4064)
		(layers "F.Cu" "B.Cu")
		(net "P3V3")
	)
	(via
		(at 196.722746 -490.2327)
		(size 0.7112)
		(drill 0.4064)
		(layers "F.Cu" "B.Cu")
		(net "P3V3")
	)
	(via
		(at 141.909546 -158.6357)
		(size 0.7112)
		(drill 0.4064)
		(layers "F.Cu" "B.Cu")
		(net "P3V3")
	)
	(via
		(at 38.734746 -209.5627)
		(size 0.7112)
		(drill 0.4064)
		(layers "F.Cu" "B.Cu")
		(net "P3V3")
	)
	(via
		(at 29.590746 -337.315302)
		(size 0.5588)
		(drill 0.3048)
		(layers "F.Cu" "B.Cu")
		(net "P3V3")
	)
	(via
		(at 9.651746 -155.3337)
		(size 0.5588)
		(drill 0.3048)
		(layers "F.Cu" "B.Cu")
		(net "P3V3")
	)
	(via
		(at 38.734746 -236.6137)
		(size 0.7112)
		(drill 0.4064)
		(layers "F.Cu" "B.Cu")
		(net "P3V3")
	)
	(via
		(at 57.657746 -493.0267)
		(size 0.7112)
		(drill 0.4064)
		(layers "F.Cu" "B.Cu")
		(net "P3V3")
	)
	(via
		(at 37.48786 -132.461)
		(size 0.7112)
		(drill 0.4064)
		(layers "F.Cu" "B.Cu")
		(net "P3V3")
	)
	(via
		(at 35.79876 -142.6972)
		(size 0.5588)
		(drill 0.3048)
		(layers "F.Cu" "B.Cu")
		(net "P3V3")
	)
	(via
		(at 59.309 -270.7894)
		(size 0.5588)
		(drill 0.3048)
		(layers "F.Cu" "B.Cu")
		(net "P3V3")
	)
	(via
		(at 74.675746 -490.9947)
		(size 0.7112)
		(drill 0.4064)
		(layers "F.Cu" "B.Cu")
		(net "P3V3")
	)
	(via
		(at 163.969446 -461.044036)
		(size 0.5588)
		(drill 0.3048)
		(layers "F.Cu" "B.Cu")
		(net "P3V3")
	)
	(via
		(at 140.793216 -156.42336)
		(size 0.7112)
		(drill 0.4064)
		(layers "F.Cu" "B.Cu")
		(net "P3V3")
	)
	(via
		(at 38.4302 -266.5222)
		(size 0.7112)
		(drill 0.4064)
		(layers "F.Cu" "B.Cu")
		(net "P3V3")
	)
	(via
		(at 75.818746 -490.8677)
		(size 0.7112)
		(drill 0.4064)
		(layers "F.Cu" "B.Cu")
		(net "P3V3")
	)
	(via
		(at 87.121746 -494.641886)
		(size 0.5588)
		(drill 0.3048)
		(layers "F.Cu" "B.Cu")
		(net "P3V3")
	)
	(via
		(at 190.118746 -282.3337)
		(size 0.7112)
		(drill 0.4064)
		(layers "F.Cu" "B.Cu")
		(net "P3V3")
	)
	(via
		(at 32.8676 -108.4326)
		(size 0.7112)
		(drill 0.4064)
		(layers "F.Cu" "B.Cu")
		(net "P3V3")
	)
	(via
		(at 191.896746 -79.8957)
		(size 0.7112)
		(drill 0.4064)
		(layers "F.Cu" "B.Cu")
		(net "P3V3")
	)
	(via
		(at 191.515746 -40.3987)
		(size 0.7112)
		(drill 0.4064)
		(layers "F.Cu" "B.Cu")
		(net "P3V3")
	)
	(via
		(at 179.7304 -461.1624)
		(size 0.5588)
		(drill 0.3048)
		(layers "F.Cu" "B.Cu")
		(net "P3V3")
	)
	(via
		(at 32.702246 -432.6382)
		(size 0.5588)
		(drill 0.3048)
		(layers "F.Cu" "B.Cu")
		(net "P3V3")
	)
	(via
		(at 203.309474 -493.063022)
		(size 0.5588)
		(drill 0.3048)
		(layers "F.Cu" "B.Cu")
		(net "P3V3")
	)
	(via
		(at 143.128746 -377.5837)
		(size 0.7112)
		(drill 0.4064)
		(layers "F.Cu" "B.Cu")
		(net "P3V3")
	)
	(via
		(at 43.815 -233.500676)
		(size 0.5588)
		(drill 0.3048)
		(layers "F.Cu" "B.Cu")
		(net "P3V3")
	)
	(via
		(at 195.1482 -451.612)
		(size 0.7112)
		(drill 0.3556)
		(layers "F.Cu" "B.Cu")
		(net "P3V3")
	)
	(via
		(at 250.7234 -412.7246)
		(size 0.5588)
		(drill 0.3048)
		(layers "F.Cu" "B.Cu")
		(net "P3V3")
	)
	(via
		(at 32.512 -440.69)
		(size 0.7112)
		(drill 0.4064)
		(layers "F.Cu" "B.Cu")
		(net "P3V3")
	)
	(via
		(at 186.194446 -460.790036)
		(size 0.5588)
		(drill 0.3048)
		(layers "F.Cu" "B.Cu")
		(net "P3V3")
	)
	(via
		(at 191.857884 -81.063846)
		(size 0.7112)
		(drill 0.4064)
		(layers "F.Cu" "B.Cu")
		(net "P3V3")
	)
	(via
		(at 26.336244 -310.861202)
		(size 0.5588)
		(drill 0.3048)
		(layers "F.Cu" "B.Cu")
		(net "P3V3")
	)
	(via
		(at 48.386746 -123.8377)
		(size 0.7112)
		(drill 0.4064)
		(layers "F.Cu" "B.Cu")
		(net "P3V3")
	)
	(via
		(at 191.896746 -284.2387)
		(size 0.7112)
		(drill 0.4064)
		(layers "F.Cu" "B.Cu")
		(net "P3V3")
	)
	(via
		(at 27.177746 -369.4303)
		(size 0.5588)
		(drill 0.3048)
		(layers "F.Cu" "B.Cu")
		(net "P3V3")
	)
	(via
		(at 26.860246 -435.038246)
		(size 0.7112)
		(drill 0.4064)
		(layers "F.Cu" "B.Cu")
		(net "P3V3")
	)
	(via
		(at 48.564546 -124.8537)
		(size 0.7112)
		(drill 0.4064)
		(layers "F.Cu" "B.Cu")
		(net "P3V3")
	)
	(via
		(at 208.8134 -70.993)
		(size 0.5588)
		(drill 0.3048)
		(layers "F.Cu" "B.Cu")
		(net "P3V3")
	)
	(via
		(at 41.541446 -131.3434)
		(size 0.5588)
		(drill 0.3048)
		(layers "F.Cu" "B.Cu")
		(net "P3V3")
	)
	(via
		(at 141.757146 -85.1027)
		(size 0.7112)
		(drill 0.4064)
		(layers "F.Cu" "B.Cu")
		(net "P3V3")
	)
	(via
		(at 189.356746 -182.8927)
		(size 0.7112)
		(drill 0.4064)
		(layers "F.Cu" "B.Cu")
		(net "P3V3")
	)
	(via
		(at 192.2526 -448.564)
		(size 0.7112)
		(drill 0.4064)
		(layers "F.Cu" "B.Cu")
		(net "P3V3")
	)
	(via
		(at 56.752744 -480.17811)
		(size 0.5588)
		(drill 0.3048)
		(layers "F.Cu" "B.Cu")
		(net "P3V3")
	)
	(via
		(at 191.007746 -450.9897)
		(size 0.7112)
		(drill 0.4064)
		(layers "F.Cu" "B.Cu")
		(net "P3V3")
	)
	(via
		(at 31.9786 -277.185628)
		(size 0.5588)
		(drill 0.3048)
		(layers "F.Cu" "B.Cu")
		(net "P3V3")
	)
	(via
		(at 192.531746 -39.2557)
		(size 0.7112)
		(drill 0.4064)
		(layers "F.Cu" "B.Cu")
		(net "P3V3")
	)
	(via
		(at 47.675546 -125.1839)
		(size 0.5588)
		(drill 0.3048)
		(layers "F.Cu" "B.Cu")
		(net "P3V3")
	)
	(via
		(at 192.658746 -480.9617)
		(size 0.5588)
		(drill 0.3048)
		(layers "F.Cu" "B.Cu")
		(net "P3V3")
	)
	(via
		(at 192.405 -386.715)
		(size 0.7112)
		(drill 0.4064)
		(layers "F.Cu" "B.Cu")
		(net "P3V3")
	)
	(via
		(at 203.834746 -495.6937)
		(size 0.5588)
		(drill 0.3048)
		(layers "F.Cu" "B.Cu")
		(net "P3V3")
	)
	(via
		(at 38.734746 -208.4197)
		(size 0.7112)
		(drill 0.4064)
		(layers "F.Cu" "B.Cu")
		(net "P3V3")
	)
	(via
		(at 213.994746 -71.354696)
		(size 0.5588)
		(drill 0.3048)
		(layers "F.Cu" "B.Cu")
		(net "P3V3")
	)
	(via
		(at 27.177746 -303.4157)
		(size 0.5588)
		(drill 0.3048)
		(layers "F.Cu" "B.Cu")
		(net "P3V3")
	)
	(via
		(at 191.2366 -448.564)
		(size 0.7112)
		(drill 0.4064)
		(layers "F.Cu" "B.Cu")
		(net "P3V3")
	)
	(via
		(at 38.608 -132.286502)
		(size 0.5588)
		(drill 0.3048)
		(layers "F.Cu" "B.Cu")
		(net "P3V3")
	)
	(via
		(at 34.8234 -110.9472)
		(size 0.7112)
		(drill 0.4064)
		(layers "F.Cu" "B.Cu")
		(net "P3V3")
	)
	(via
		(at 190.754 -386.334)
		(size 0.7112)
		(drill 0.4064)
		(layers "F.Cu" "B.Cu")
		(net "P3V3")
	)
	(via
		(at 141.912086 -157.54223)
		(size 0.7112)
		(drill 0.4064)
		(layers "F.Cu" "B.Cu")
		(net "P3V3")
	)
	(via
		(at 95.757746 -17.7927)
		(size 0.7112)
		(drill 0.4064)
		(layers "F.Cu" "B.Cu")
		(net "P3V3")
	)
	(via
		(at 76.834746 -490.8677)
		(size 0.7112)
		(drill 0.4064)
		(layers "F.Cu" "B.Cu")
		(net "P3V3")
	)
	(via
		(at 33.654746 -278.0157)
		(size 0.5588)
		(drill 0.3048)
		(layers "F.Cu" "B.Cu")
		(net "P3V3")
	)
	(via
		(at 33.782 -440.563)
		(size 0.7112)
		(drill 0.4064)
		(layers "F.Cu" "B.Cu")
		(net "P3V3")
	)
	(via
		(at 43.617388 -130.512058)
		(size 0.5588)
		(drill 0.3048)
		(layers "F.Cu" "B.Cu")
		(net "P3V3")
	)
	(via
		(at 127.858266 -157.7721)
		(size 0.7112)
		(drill 0.3556)
		(layers "F.Cu" "B.Cu")
		(net "P3V3")
	)
	(via
		(at 56.006746 -225.4377)
		(size 0.7112)
		(drill 0.4064)
		(layers "F.Cu" "B.Cu")
		(net "P3V3")
	)
	(via
		(at 190.880746 -80.7847)
		(size 0.7112)
		(drill 0.4064)
		(layers "F.Cu" "B.Cu")
		(net "P3V3")
	)
	(via
		(at 26.1366 -303.7967)
		(size 0.5588)
		(drill 0.3048)
		(layers "F.Cu" "B.Cu")
		(net "P3V3")
	)
	(via
		(at 8.788146 -405.2062)
		(size 0.5588)
		(drill 0.3048)
		(layers "F.Cu" "B.Cu")
		(net "P3V3")
	)
	(via
		(at 190.890906 -79.751936)
		(size 0.7112)
		(drill 0.4064)
		(layers "F.Cu" "B.Cu")
		(net "P3V3")
	)
	(via
		(at 25.780746 -272.4277)
		(size 0.5588)
		(drill 0.3048)
		(layers "F.Cu" "B.Cu")
		(net "P3V3")
	)
	(via
		(at 190.754 -385.318)
		(size 0.7112)
		(drill 0.4064)
		(layers "F.Cu" "B.Cu")
		(net "P3V3")
	)
	(via
		(at 26.671524 -278.222964)
		(size 0.7112)
		(drill 0.4064)
		(layers "F.Cu" "B.Cu")
		(net "P3V3")
	)
	(segment
		(start 251.89434 -414.222692)
		(end 251.971556 -414.299908)
		(width 0.762)
		(layer "B.Cu")
		(net "P3V3")
	)
	(segment
		(start 208.8134 -70.993)
		(end 213.63305 -70.993)
		(width 0.508)
		(layer "B.Cu")
		(net "P3V3")
	)
	(segment
		(start 57.657746 -493.0267)
		(end 56.810148 -492.179102)
		(width 1.016)
		(layer "B.Cu")
		(net "P3V3")
	)
	(segment
		(start 213.63305 -70.993)
		(end 213.994746 -71.354696)
		(width 0.508)
		(layer "B.Cu")
		(net "P3V3")
	)
	(segment
		(start 250.494292 -414.222692)
		(end 251.89434 -414.222692)
		(width 0.762)
		(layer "B.Cu")
		(net "P3V3")
	)
	(segment
		(start 190.890906 -76.45654)
		(end 196.354446 -70.993)
		(width 0.508)
		(layer "B.Cu")
		(net "P3V3")
	)
	(segment
		(start 85.235796 -21.58365)
		(end 79.012796 -21.58365)
		(width 0.508)
		(layer "B.Cu")
		(net "P3V3")
	)
	(segment
		(start 190.890906 -79.751936)
		(end 190.890906 -76.45654)
		(width 0.508)
		(layer "B.Cu")
		(net "P3V3")
	)
	(segment
		(start 56.810148 -490.123734)
		(end 56.752744 -490.06633)
		(width 1.016)
		(layer "B.Cu")
		(net "P3V3")
	)
	(segment
		(start 88.518746 -18.3007)
		(end 85.235796 -21.58365)
		(width 0.508)
		(layer "B.Cu")
		(net "P3V3")
	)
	(segment
		(start 90.169746 -18.3007)
		(end 88.518746 -18.3007)
		(width 0.508)
		(layer "B.Cu")
		(net "P3V3")
	)
	(segment
		(start 250.7234 -412.7246)
		(end 251.028708 -413.029908)
		(width 0.762)
		(layer "B.Cu")
		(net "P3V3")
	)
	(segment
		(start 196.354446 -70.993)
		(end 208.8134 -70.993)
		(width 0.508)
		(layer "B.Cu")
		(net "P3V3")
	)
	(segment
		(start 79.012796 -21.58365)
		(end 78.485746 -22.1107)
		(width 0.508)
		(layer "B.Cu")
		(net "P3V3")
	)
	(segment
		(start 251.971556 -414.299908)
		(end 255.093978 -414.299908)
		(width 0.762)
		(layer "B.Cu")
		(net "P3V3")
	)
	(segment
		(start 56.810148 -492.179102)
		(end 56.810148 -490.123734)
		(width 1.016)
		(layer "B.Cu")
		(net "P3V3")
	)
	(segment
		(start 56.752744 -490.06633)
		(end 56.752744 -480.17811)
		(width 1.016)
		(layer "B.Cu")
		(net "P3V3")
	)
	(segment
		(start 251.028708 -413.029908)
		(end 255.093978 -413.029908)
		(width 0.762)
		(layer "B.Cu")
		(net "P3V3")
	)
	(segment
		(start 249.2248 -412.9532)
		(end 250.494292 -414.222692)
		(width 0.762)
		(layer "B.Cu")
		(net "P3V3")
	)
	(segment
		(start 45.8216 -266.5222)
		(end 38.4302 -266.5222)
		(width 0.762)
		(layer "In2.Cu")
		(net "P3V3")
	)
	(segment
		(start 57.6072 -277.7236)
		(end 57.023 -277.7236)
		(width 0.762)
		(layer "In2.Cu")
		(net "P3V3")
	)
	(segment
		(start 57.023 -277.7236)
		(end 45.8216 -266.5222)
		(width 0.762)
		(layer "In2.Cu")
		(net "P3V3")
	)
	(segment
		(start 42.9514 -428.1932)
		(end 37.401246 -428.1932)
		(width 0.508)
		(layer "In2.Cu")
		(net "P3V3")
	)
	(segment
		(start 37.401246 -428.1932)
		(end 33.80486 -431.789586)
		(width 0.508)
		(layer "In2.Cu")
		(net "P3V3")
	)
	(segment
		(start 59.309 -270.7894)
		(end 59.309 -276.0218)
		(width 0.508)
		(layer "In5.Cu")
		(net "P3V3")
	)
	(segment
		(start 59.309 -276.0218)
		(end 57.6072 -277.7236)
		(width 0.508)
		(layer "In5.Cu")
		(net "P3V3")
	)
	(segment
		(start 32.829246 -269.2527)
		(end 32.564324 -269.2527)
		(width 0.09525)
		(layer "F.Cu")
		(net "SAS2X28_B_HDD7_RX_-")
	)
	(segment
		(start 32.003746 -268.512544)
		(end 32.003746 -267.3477)
		(width 0.09525)
		(layer "F.Cu")
		(net "SAS2X28_B_HDD7_RX_-")
	)
	(segment
		(start 31.521146 -266.8651)
		(end 31.495746 -266.8651)
		(width 0.09525)
		(layer "F.Cu")
		(net "SAS2X28_B_HDD7_RX_-")
	)
	(via
		(at 6.73481 -122.376692)
		(size 0.5588)
		(drill 0.3048)
		(layers "F.Cu" "B.Cu")
		(net "SAS2X28_B_HDD7_RX_-")
	)
	(via
		(at 31.495746 -266.8651)
		(size 0.5588)
		(drill 0.3048)
		(layers "F.Cu" "B.Cu")
		(net "SAS2X28_B_HDD7_RX_-")
	)
	(arc
		(start 32.003746 -267.3477)
		(mid 31.862396 -267.00645)
		(end 31.521146 -266.8651)
		(width 0.09525)
		(layer "F.Cu")
		(net "SAS2X28_B_HDD7_RX_-")
	)
	(arc
		(start 32.257746 -269.1257)
		(mid 32.069775 -268.844382)
		(end 32.003746 -268.512544)
		(width 0.09525)
		(layer "F.Cu")
		(net "SAS2X28_B_HDD7_RX_-")
	)
	(arc
		(start 32.564324 -269.2527)
		(mid 32.398401 -269.219696)
		(end 32.257746 -269.1257)
		(width 0.09525)
		(layer "F.Cu")
		(net "SAS2X28_B_HDD7_RX_-")
	)
	(segment
		(start 4.926076 -122.498866)
		(end 2.811526 -122.498866)
		(width 0.09525)
		(layer "B.Cu")
		(net "SAS2X28_B_HDD7_RX_-")
	)
	(segment
		(start 6.73481 -122.376692)
		(end 6.73481 -122.159776)
		(width 0.09525)
		(layer "B.Cu")
		(net "SAS2X28_B_HDD7_RX_-")
	)
	(segment
		(start 5.203444 -122.283982)
		(end 5.0292 -122.45848)
		(width 0.09525)
		(layer "B.Cu")
		(net "SAS2X28_B_HDD7_RX_-")
	)
	(segment
		(start 6.019546 -122.160792)
		(end 5.500878 -122.160792)
		(width 0.09525)
		(layer "B.Cu")
		(net "SAS2X28_B_HDD7_RX_-")
	)
	(segment
		(start 4.9276 -122.50039)
		(end 4.926076 -122.498866)
		(width 0.09525)
		(layer "B.Cu")
		(net "SAS2X28_B_HDD7_RX_-")
	)
	(arc
		(start 6.73481 -122.159776)
		(mid 6.670651 -122.044643)
		(end 6.538976 -122.038618)
		(width 0.09525)
		(layer "B.Cu")
		(net "SAS2X28_B_HDD7_RX_-")
	)
	(arc
		(start 5.0292 -122.45848)
		(mid 4.98257 -122.489544)
		(end 4.9276 -122.50039)
		(width 0.09525)
		(layer "B.Cu")
		(net "SAS2X28_B_HDD7_RX_-")
	)
	(arc
		(start 5.500878 -122.160792)
		(mid 5.339912 -122.19281)
		(end 5.203444 -122.283982)
		(width 0.09525)
		(layer "B.Cu")
		(net "SAS2X28_B_HDD7_RX_-")
	)
	(arc
		(start 6.538976 -122.038618)
		(mid 6.286369 -122.129923)
		(end 6.019546 -122.160792)
		(width 0.09525)
		(layer "B.Cu")
		(net "SAS2X28_B_HDD7_RX_-")
	)
	(segment
		(start 29.18968 -131.604512)
		(end 29.02458 -131.439412)
		(width 0.1143)
		(layer "In2.Cu")
		(net "SAS2X28_B_HDD7_RX_-")
	)
	(segment
		(start 32.537146 -265.5443)
		(end 31.603696 -264.61085)
		(width 0.1143)
		(layer "In2.Cu")
		(net "SAS2X28_B_HDD7_RX_-")
	)
	(segment
		(start 31.0134 -263.185656)
		(end 31.0134 -208.084928)
		(width 0.1143)
		(layer "In2.Cu")
		(net "SAS2X28_B_HDD7_RX_-")
	)
	(segment
		(start 6.778244 -122.272044)
		(end 6.73481 -122.376692)
		(width 0.1143)
		(layer "In2.Cu")
		(net "SAS2X28_B_HDD7_RX_-")
	)
	(segment
		(start 6.903974 -121.937272)
		(end 6.873748 -121.967498)
		(width 0.1143)
		(layer "In2.Cu")
		(net "SAS2X28_B_HDD7_RX_-")
	)
	(segment
		(start 7.257542 -121.871486)
		(end 7.062978 -121.871486)
		(width 0.1143)
		(layer "In2.Cu")
		(net "SAS2X28_B_HDD7_RX_-")
	)
	(segment
		(start 30.162754 -206.031846)
		(end 29.650182 -205.519274)
		(width 0.1143)
		(layer "In2.Cu")
		(net "SAS2X28_B_HDD7_RX_-")
	)
	(segment
		(start 31.0134 -208.084928)
		(end 31.013146 -208.085182)
		(width 0.1143)
		(layer "In2.Cu")
		(net "SAS2X28_B_HDD7_RX_-")
	)
	(segment
		(start 29.024326 -131.439412)
		(end 19.94408 -122.359166)
		(width 0.1143)
		(layer "In2.Cu")
		(net "SAS2X28_B_HDD7_RX_-")
	)
	(segment
		(start 32.257746 -267.1699)
		(end 32.257746 -267.169646)
		(width 0.1143)
		(layer "In2.Cu")
		(net "SAS2X28_B_HDD7_RX_-")
	)
	(segment
		(start 6.828536 -122.127518)
		(end 6.78688 -122.228102)
		(width 0.1143)
		(layer "In2.Cu")
		(net "SAS2X28_B_HDD7_RX_-")
	)
	(segment
		(start 31.93923 -267.1699)
		(end 32.257746 -267.1699)
		(width 0.1143)
		(layer "In2.Cu")
		(net "SAS2X28_B_HDD7_RX_-")
	)
	(segment
		(start 31.495746 -266.8651)
		(end 31.701994 -267.071602)
		(width 0.1143)
		(layer "In2.Cu")
		(net "SAS2X28_B_HDD7_RX_-")
	)
	(segment
		(start 29.426154 -204.978)
		(end 29.426154 -132.175504)
		(width 0.1143)
		(layer "In2.Cu")
		(net "SAS2X28_B_HDD7_RX_-")
	)
	(segment
		(start 29.02458 -131.439412)
		(end 29.024326 -131.439412)
		(width 0.1143)
		(layer "In2.Cu")
		(net "SAS2X28_B_HDD7_RX_-")
	)
	(segment
		(start 19.393408 -122.131074)
		(end 7.883906 -122.131074)
		(width 0.1143)
		(layer "In2.Cu")
		(net "SAS2X28_B_HDD7_RX_-")
	)
	(segment
		(start 6.837934 -122.054112)
		(end 6.837934 -122.080528)
		(width 0.1143)
		(layer "In2.Cu")
		(net "SAS2X28_B_HDD7_RX_-")
	)
	(segment
		(start 32.714946 -266.673076)
		(end 32.714946 -265.97356)
		(width 0.1143)
		(layer "In2.Cu")
		(net "SAS2X28_B_HDD7_RX_-")
	)
	(segment
		(start 30.163008 -206.031592)
		(end 30.162754 -206.031846)
		(width 0.1143)
		(layer "In2.Cu")
		(net "SAS2X28_B_HDD7_RX_-")
	)
	(arc
		(start 7.062978 -121.871486)
		(mid 6.97694 -121.888582)
		(end 6.903974 -121.937272)
		(width 0.1143)
		(layer "In2.Cu")
		(net "SAS2X28_B_HDD7_RX_-")
	)
	(arc
		(start 6.78688 -122.228102)
		(mid 6.784725 -122.250498)
		(end 6.778244 -122.272044)
		(width 0.1143)
		(layer "In2.Cu")
		(net "SAS2X28_B_HDD7_RX_-")
	)
	(arc
		(start 32.714946 -265.97356)
		(mid 32.668736 -265.741248)
		(end 32.537146 -265.5443)
		(width 0.1143)
		(layer "In2.Cu")
		(net "SAS2X28_B_HDD7_RX_-")
	)
	(arc
		(start 19.94408 -122.359166)
		(mid 19.69143 -122.19035)
		(end 19.393408 -122.131074)
		(width 0.1143)
		(layer "In2.Cu")
		(net "SAS2X28_B_HDD7_RX_-")
	)
	(arc
		(start 6.873748 -121.967498)
		(mid 6.847249 -122.007251)
		(end 6.837934 -122.054112)
		(width 0.1143)
		(layer "In2.Cu")
		(net "SAS2X28_B_HDD7_RX_-")
	)
	(arc
		(start 31.603696 -264.61085)
		(mid 31.166838 -263.956951)
		(end 31.0134 -263.185656)
		(width 0.1143)
		(layer "In2.Cu")
		(net "SAS2X28_B_HDD7_RX_-")
	)
	(arc
		(start 6.837934 -122.080528)
		(mid 6.835571 -122.104492)
		(end 6.828536 -122.127518)
		(width 0.1143)
		(layer "In2.Cu")
		(net "SAS2X28_B_HDD7_RX_-")
	)
	(arc
		(start 32.257746 -267.169646)
		(mid 32.421987 -267.137088)
		(end 32.561276 -267.04417)
		(width 0.1143)
		(layer "In2.Cu")
		(net "SAS2X28_B_HDD7_RX_-")
	)
	(arc
		(start 31.701994 -267.071602)
		(mid 31.810839 -267.14433)
		(end 31.93923 -267.1699)
		(width 0.1143)
		(layer "In2.Cu")
		(net "SAS2X28_B_HDD7_RX_-")
	)
	(arc
		(start 7.883906 -122.131074)
		(mid 7.593565 -122.073322)
		(end 7.347458 -121.908824)
		(width 0.1143)
		(layer "In2.Cu")
		(net "SAS2X28_B_HDD7_RX_-")
	)
	(arc
		(start 29.426154 -132.175504)
		(mid 29.364689 -131.8665)
		(end 29.18968 -131.604512)
		(width 0.1143)
		(layer "In2.Cu")
		(net "SAS2X28_B_HDD7_RX_-")
	)
	(arc
		(start 31.013146 -208.085182)
		(mid 30.792294 -206.973852)
		(end 30.163008 -206.031592)
		(width 0.1143)
		(layer "In2.Cu")
		(net "SAS2X28_B_HDD7_RX_-")
	)
	(arc
		(start 32.561276 -267.04417)
		(mid 32.67504 -266.873911)
		(end 32.714946 -266.673076)
		(width 0.1143)
		(layer "In2.Cu")
		(net "SAS2X28_B_HDD7_RX_-")
	)
	(arc
		(start 29.650182 -205.519274)
		(mid 29.48433 -205.27092)
		(end 29.426154 -204.978)
		(width 0.1143)
		(layer "In2.Cu")
		(net "SAS2X28_B_HDD7_RX_-")
	)
	(arc
		(start 7.347458 -121.908824)
		(mid 7.306218 -121.881205)
		(end 7.257542 -121.871486)
		(width 0.1143)
		(layer "In2.Cu")
		(net "SAS2X28_B_HDD7_RX_-")
	)
	(via
		(at 53.974746 -186.9567)
		(size 0.7112)
		(drill 0.3556)
		(layers "F.Cu" "B.Cu")
		(net "12V_PRE_8")
	)
	(segment
		(start 4.692904 -115.49888)
		(end 3.192526 -115.49888)
		(width 0.09525)
		(layer "F.Cu")
		(net "SAS2X28_B_HDD2_TX_+")
	)
	(segment
		(start 6.533642 -115.830604)
		(end 5.49148 -115.830604)
		(width 0.09525)
		(layer "F.Cu")
		(net "SAS2X28_B_HDD2_TX_+")
	)
	(segment
		(start 225.399854 -266.990068)
		(end 224.630234 -266.990068)
		(width 0.09525)
		(layer "F.Cu")
		(net "SAS2X28_B_HDD2_TX_+")
	)
	(segment
		(start 224.294192 -267.1445)
		(end 223.472756 -267.1445)
		(width 0.09525)
		(layer "F.Cu")
		(net "SAS2X28_B_HDD2_TX_+")
	)
	(segment
		(start 4.694428 -115.500404)
		(end 4.692904 -115.49888)
		(width 0.09525)
		(layer "F.Cu")
		(net "SAS2X28_B_HDD2_TX_+")
	)
	(segment
		(start 224.630234 -266.990068)
		(end 224.626932 -266.986766)
		(width 0.09525)
		(layer "F.Cu")
		(net "SAS2X28_B_HDD2_TX_+")
	)
	(via
		(at 6.832346 -115.5319)
		(size 0.5588)
		(drill 0.3048)
		(layers "F.Cu" "B.Cu")
		(net "SAS2X28_B_HDD2_TX_+")
	)
	(via
		(at 223.071182 -266.97813)
		(size 0.5588)
		(drill 0.3048)
		(layers "F.Cu" "B.Cu")
		(net "SAS2X28_B_HDD2_TX_+")
	)
	(arc
		(start 5.205222 -115.711986)
		(mid 4.970868 -115.555395)
		(end 4.694428 -115.500404)
		(width 0.09525)
		(layer "F.Cu")
		(net "SAS2X28_B_HDD2_TX_+")
	)
	(arc
		(start 224.626932 -266.986766)
		(mid 224.52973 -267.006101)
		(end 224.447354 -267.061188)
		(width 0.09525)
		(layer "F.Cu")
		(net "SAS2X28_B_HDD2_TX_+")
	)
	(arc
		(start 224.447354 -267.061188)
		(mid 224.424263 -267.079504)
		(end 224.40265 -267.099542)
		(width 0.09525)
		(layer "F.Cu")
		(net "SAS2X28_B_HDD2_TX_+")
	)
	(arc
		(start 224.40265 -267.099542)
		(mid 224.352889 -267.132791)
		(end 224.294192 -267.1445)
		(width 0.09525)
		(layer "F.Cu")
		(net "SAS2X28_B_HDD2_TX_+")
	)
	(arc
		(start 223.472756 -267.1445)
		(mid 223.255413 -267.101268)
		(end 223.071182 -266.97813)
		(width 0.09525)
		(layer "F.Cu")
		(net "SAS2X28_B_HDD2_TX_+")
	)
	(arc
		(start 6.832346 -115.5319)
		(mid 6.744858 -115.743116)
		(end 6.533642 -115.830604)
		(width 0.09525)
		(layer "F.Cu")
		(net "SAS2X28_B_HDD2_TX_+")
	)
	(arc
		(start 5.49148 -115.830604)
		(mid 5.336541 -115.799785)
		(end 5.205222 -115.711986)
		(width 0.09525)
		(layer "F.Cu")
		(net "SAS2X28_B_HDD2_TX_+")
	)
	(segment
		(start 12.141962 -118.0338)
		(end 43.745404 -118.0338)
		(width 0.09525)
		(layer "B.Cu")
		(net "SAS2X28_B_HDD2_TX_+")
	)
	(segment
		(start 221.026228 -267.468858)
		(end 221.076266 -267.41882)
		(width 0.09525)
		(layer "B.Cu")
		(net "SAS2X28_B_HDD2_TX_+")
	)
	(segment
		(start 198.49846 -270.738346)
		(end 220.28912 -270.738346)
		(width 0.09525)
		(layer "B.Cu")
		(net "SAS2X28_B_HDD2_TX_+")
	)
	(segment
		(start 223.070928 -267.008864)
		(end 223.071182 -266.97813)
		(width 0.09525)
		(layer "B.Cu")
		(net "SAS2X28_B_HDD2_TX_+")
	)
	(segment
		(start 45.705268 -118.860316)
		(end 45.705522 -118.860316)
		(width 0.09525)
		(layer "B.Cu")
		(net "SAS2X28_B_HDD2_TX_+")
	)
	(segment
		(start 45.705522 -118.860316)
		(end 196.936106 -270.0909)
		(width 0.09525)
		(layer "B.Cu")
		(net "SAS2X28_B_HDD2_TX_+")
	)
	(segment
		(start 221.678246 -267.1699)
		(end 222.25 -267.1699)
		(width 0.09525)
		(layer "B.Cu")
		(net "SAS2X28_B_HDD2_TX_+")
	)
	(segment
		(start 220.761052 -270.308324)
		(end 220.761052 -268.1097)
		(width 0.09525)
		(layer "B.Cu")
		(net "SAS2X28_B_HDD2_TX_+")
	)
	(segment
		(start 9.879838 -116.245132)
		(end 11.333734 -117.699028)
		(width 0.09525)
		(layer "B.Cu")
		(net "SAS2X28_B_HDD2_TX_+")
	)
	(segment
		(start 7.114032 -115.813586)
		(end 8.838184 -115.813586)
		(width 0.09525)
		(layer "B.Cu")
		(net "SAS2X28_B_HDD2_TX_+")
	)
	(segment
		(start 220.622622 -270.60017)
		(end 220.65234 -270.570706)
		(width 0.09525)
		(layer "B.Cu")
		(net "SAS2X28_B_HDD2_TX_+")
	)
	(segment
		(start 45.680122 -118.83517)
		(end 45.705268 -118.860316)
		(width 0.09525)
		(layer "B.Cu")
		(net "SAS2X28_B_HDD2_TX_+")
	)
	(arc
		(start 11.333734 -117.699028)
		(mid 11.704552 -117.946801)
		(end 12.141962 -118.0338)
		(width 0.09525)
		(layer "B.Cu")
		(net "SAS2X28_B_HDD2_TX_+")
	)
	(arc
		(start 220.28912 -270.738346)
		(mid 220.469584 -270.702374)
		(end 220.622622 -270.60017)
		(width 0.09525)
		(layer "B.Cu")
		(net "SAS2X28_B_HDD2_TX_+")
	)
	(arc
		(start 221.076266 -267.41882)
		(mid 221.352488 -267.234471)
		(end 221.678246 -267.1699)
		(width 0.09525)
		(layer "B.Cu")
		(net "SAS2X28_B_HDD2_TX_+")
	)
	(arc
		(start 6.832346 -115.5319)
		(mid 6.91485 -115.731082)
		(end 7.114032 -115.813586)
		(width 0.09525)
		(layer "B.Cu")
		(net "SAS2X28_B_HDD2_TX_+")
	)
	(arc
		(start 8.838184 -115.813586)
		(mid 9.401953 -115.925727)
		(end 9.879838 -116.245132)
		(width 0.09525)
		(layer "B.Cu")
		(net "SAS2X28_B_HDD2_TX_+")
	)
	(arc
		(start 222.716598 -267.254482)
		(mid 222.957992 -267.224384)
		(end 223.070928 -267.008864)
		(width 0.09525)
		(layer "B.Cu")
		(net "SAS2X28_B_HDD2_TX_+")
	)
	(arc
		(start 196.936106 -270.0909)
		(mid 197.652891 -270.569997)
		(end 198.49846 -270.738346)
		(width 0.09525)
		(layer "B.Cu")
		(net "SAS2X28_B_HDD2_TX_+")
	)
	(arc
		(start 222.25 -267.1699)
		(mid 222.487103 -267.19121)
		(end 222.716598 -267.254482)
		(width 0.09525)
		(layer "B.Cu")
		(net "SAS2X28_B_HDD2_TX_+")
	)
	(arc
		(start 43.745404 -118.0338)
		(mid 44.792434 -118.242125)
		(end 45.680122 -118.83517)
		(width 0.09525)
		(layer "B.Cu")
		(net "SAS2X28_B_HDD2_TX_+")
	)
	(arc
		(start 220.65234 -270.570706)
		(mid 220.732801 -270.450338)
		(end 220.761052 -270.308324)
		(width 0.09525)
		(layer "B.Cu")
		(net "SAS2X28_B_HDD2_TX_+")
	)
	(arc
		(start 220.761052 -268.1097)
		(mid 220.829936 -267.762928)
		(end 221.026228 -267.468858)
		(width 0.09525)
		(layer "B.Cu")
		(net "SAS2X28_B_HDD2_TX_+")
	)
	(segment
		(start 202.86726 -369.109752)
		(end 83.384898 -408.977592)
		(width 0.09525)
		(layer "F.Cu")
		(net "SAS2X28_A_HDD1_RX_+")
	)
	(segment
		(start 7.84733 -409.561284)
		(end 8.062722 -409.776422)
		(width 0.09525)
		(layer "F.Cu")
		(net "SAS2X28_A_HDD1_RX_+")
	)
	(segment
		(start 210.110324 -366.693196)
		(end 202.86726 -369.109752)
		(width 0.09525)
		(layer "F.Cu")
		(net "SAS2X28_A_HDD1_RX_+")
	)
	(segment
		(start 216.952576 -366.571784)
		(end 210.946746 -366.571784)
		(width 0.09525)
		(layer "F.Cu")
		(net "SAS2X28_A_HDD1_RX_+")
	)
	(segment
		(start 82.423 -409.122118)
		(end 8.31469 -409.122118)
		(width 0.09525)
		(layer "F.Cu")
		(net "SAS2X28_A_HDD1_RX_+")
	)
	(via
		(at 8.203946 -409.835096)
		(size 0.5588)
		(drill 0.3048)
		(layers "F.Cu" "B.Cu")
		(net "SAS2X28_A_HDD1_RX_+")
	)
	(arc
		(start 8.062722 -409.776422)
		(mid 8.127501 -409.819799)
		(end 8.203946 -409.835096)
		(width 0.09525)
		(layer "F.Cu")
		(net "SAS2X28_A_HDD1_RX_+")
	)
	(arc
		(start 82.549746 -409.119578)
		(mid 82.486385 -409.121462)
		(end 82.423 -409.122118)
		(width 0.09525)
		(layer "F.Cu")
		(net "SAS2X28_A_HDD1_RX_+")
	)
	(arc
		(start 217.697558 -366.851184)
		(mid 217.350405 -366.643921)
		(end 216.952576 -366.571784)
		(width 0.09525)
		(layer "F.Cu")
		(net "SAS2X28_A_HDD1_RX_+")
	)
	(arc
		(start 7.843012 -409.324302)
		(mid 7.797273 -409.443688)
		(end 7.84733 -409.561284)
		(width 0.09525)
		(layer "F.Cu")
		(net "SAS2X28_A_HDD1_RX_+")
	)
	(arc
		(start 7.853426 -409.31338)
		(mid 7.848187 -409.31881)
		(end 7.843012 -409.324302)
		(width 0.09525)
		(layer "F.Cu")
		(net "SAS2X28_A_HDD1_RX_+")
	)
	(arc
		(start 210.946746 -366.571784)
		(mid 210.524152 -366.602295)
		(end 210.110324 -366.693196)
		(width 0.09525)
		(layer "F.Cu")
		(net "SAS2X28_A_HDD1_RX_+")
	)
	(arc
		(start 83.384898 -408.977592)
		(mid 82.971906 -409.075545)
		(end 82.549746 -409.119578)
		(width 0.09525)
		(layer "F.Cu")
		(net "SAS2X28_A_HDD1_RX_+")
	)
	(arc
		(start 8.31469 -409.122118)
		(mid 8.065008 -409.171819)
		(end 7.853426 -409.31338)
		(width 0.09525)
		(layer "F.Cu")
		(net "SAS2X28_A_HDD1_RX_+")
	)
	(segment
		(start 7.970266 -409.338272)
		(end 7.970266 -407.403046)
		(width 0.09525)
		(layer "B.Cu")
		(net "SAS2X28_A_HDD1_RX_+")
	)
	(segment
		(start 7.726426 -406.81402)
		(end 7.289546 -406.37714)
		(width 0.09525)
		(layer "B.Cu")
		(net "SAS2X28_A_HDD1_RX_+")
	)
	(segment
		(start 8.203946 -409.835096)
		(end 8.156194 -409.787344)
		(width 0.09525)
		(layer "B.Cu")
		(net "SAS2X28_A_HDD1_RX_+")
	)
	(segment
		(start 4.789678 -405.498808)
		(end 2.811526 -405.498808)
		(width 0.09525)
		(layer "B.Cu")
		(net "SAS2X28_A_HDD1_RX_+")
	)
	(segment
		(start 5.841746 -405.7777)
		(end 5.460746 -405.7777)
		(width 0.09525)
		(layer "B.Cu")
		(net "SAS2X28_A_HDD1_RX_+")
	)
	(segment
		(start 4.791202 -405.500332)
		(end 4.789678 -405.498808)
		(width 0.09525)
		(layer "B.Cu")
		(net "SAS2X28_A_HDD1_RX_+")
	)
	(arc
		(start 5.460746 -405.7777)
		(mid 5.384443 -405.762522)
		(end 5.319776 -405.71928)
		(width 0.09525)
		(layer "B.Cu")
		(net "SAS2X28_A_HDD1_RX_+")
	)
	(arc
		(start 8.156194 -409.787344)
		(mid 8.018579 -409.581294)
		(end 7.970266 -409.338272)
		(width 0.09525)
		(layer "B.Cu")
		(net "SAS2X28_A_HDD1_RX_+")
	)
	(arc
		(start 6.30682 -405.83104)
		(mid 6.075812 -405.791035)
		(end 5.841746 -405.7777)
		(width 0.09525)
		(layer "B.Cu")
		(net "SAS2X28_A_HDD1_RX_+")
	)
	(arc
		(start 7.970266 -407.403046)
		(mid 7.906883 -407.084308)
		(end 7.726426 -406.81402)
		(width 0.09525)
		(layer "B.Cu")
		(net "SAS2X28_A_HDD1_RX_+")
	)
	(arc
		(start 7.289546 -406.37714)
		(mid 6.836395 -406.035333)
		(end 6.30682 -405.83104)
		(width 0.09525)
		(layer "B.Cu")
		(net "SAS2X28_A_HDD1_RX_+")
	)
	(arc
		(start 5.319776 -405.71928)
		(mid 5.077264 -405.557239)
		(end 4.791202 -405.500332)
		(width 0.09525)
		(layer "B.Cu")
		(net "SAS2X28_A_HDD1_RX_+")
	)
	(via
		(at 32.257746 -290.4617)
		(size 0.7112)
		(drill 0.3556)
		(layers "F.Cu" "B.Cu")
		(net "12V_PRE_7")
	)
	(segment
		(start 31.673546 -268.492478)
		(end 31.673546 -268.15796)
		(width 0.09525)
		(layer "F.Cu")
		(net "SAS2X28_B_HDD7_RX_+")
	)
	(segment
		(start 32.829246 -270.1417)
		(end 32.022542 -269.334996)
		(width 0.09525)
		(layer "F.Cu")
		(net "SAS2X28_B_HDD7_RX_+")
	)
	(via
		(at 6.679946 -121.514616)
		(size 0.5588)
		(drill 0.3048)
		(layers "F.Cu" "B.Cu")
		(net "SAS2X28_B_HDD7_RX_+")
	)
	(via
		(at 31.495746 -267.7287)
		(size 0.5588)
		(drill 0.3048)
		(layers "F.Cu" "B.Cu")
		(net "SAS2X28_B_HDD7_RX_+")
	)
	(arc
		(start 31.673546 -268.15796)
		(mid 31.666087 -268.063594)
		(end 31.644082 -267.971524)
		(width 0.09525)
		(layer "F.Cu")
		(net "SAS2X28_B_HDD7_RX_+")
	)
	(arc
		(start 32.022542 -269.334996)
		(mid 31.764257 -268.948445)
		(end 31.673546 -268.492478)
		(width 0.09525)
		(layer "F.Cu")
		(net "SAS2X28_B_HDD7_RX_+")
	)
	(arc
		(start 31.644082 -267.971524)
		(mid 31.595404 -267.860129)
		(end 31.525464 -267.760704)
		(width 0.09525)
		(layer "F.Cu")
		(net "SAS2X28_B_HDD7_RX_+")
	)
	(arc
		(start 31.525464 -267.760704)
		(mid 31.510895 -267.744433)
		(end 31.495746 -267.7287)
		(width 0.09525)
		(layer "F.Cu")
		(net "SAS2X28_B_HDD7_RX_+")
	)
	(segment
		(start 4.875276 -121.498868)
		(end 2.811526 -121.498868)
		(width 0.09525)
		(layer "B.Cu")
		(net "SAS2X28_B_HDD7_RX_+")
	)
	(segment
		(start 6.679946 -121.514616)
		(end 6.607556 -121.587006)
		(width 0.09525)
		(layer "B.Cu")
		(net "SAS2X28_B_HDD7_RX_+")
	)
	(segment
		(start 6.019546 -121.830592)
		(end 5.489956 -121.830592)
		(width 0.09525)
		(layer "B.Cu")
		(net "SAS2X28_B_HDD7_RX_+")
	)
	(segment
		(start 4.8768 -121.500392)
		(end 4.875276 -121.498868)
		(width 0.09525)
		(layer "B.Cu")
		(net "SAS2X28_B_HDD7_RX_+")
	)
	(segment
		(start 5.207762 -121.713752)
		(end 5.077714 -121.58345)
		(width 0.09525)
		(layer "B.Cu")
		(net "SAS2X28_B_HDD7_RX_+")
	)
	(arc
		(start 5.489956 -121.830592)
		(mid 5.337252 -121.800217)
		(end 5.207762 -121.713752)
		(width 0.09525)
		(layer "B.Cu")
		(net "SAS2X28_B_HDD7_RX_+")
	)
	(arc
		(start 5.077714 -121.58345)
		(mid 4.985519 -121.52194)
		(end 4.8768 -121.500392)
		(width 0.09525)
		(layer "B.Cu")
		(net "SAS2X28_B_HDD7_RX_+")
	)
	(arc
		(start 6.607556 -121.587006)
		(mid 6.337775 -121.767268)
		(end 6.019546 -121.830592)
		(width 0.09525)
		(layer "B.Cu")
		(net "SAS2X28_B_HDD7_RX_+")
	)
	(segment
		(start 19.393408 -121.826274)
		(end 7.88416 -121.826274)
		(width 0.1143)
		(layer "In2.Cu")
		(net "SAS2X28_B_HDD7_RX_+")
	)
	(segment
		(start 32.108902 -267.4747)
		(end 32.258 -267.4747)
		(width 0.1143)
		(layer "In2.Cu")
		(net "SAS2X28_B_HDD7_RX_+")
	)
	(segment
		(start 29.730954 -204.978)
		(end 29.730954 -132.175504)
		(width 0.1143)
		(layer "In2.Cu")
		(net "SAS2X28_B_HDD7_RX_+")
	)
	(segment
		(start 32.752538 -265.328908)
		(end 32.752792 -265.328654)
		(width 0.1143)
		(layer "In2.Cu")
		(net "SAS2X28_B_HDD7_RX_+")
	)
	(segment
		(start 28.881832 -130.865372)
		(end 20.159726 -122.14352)
		(width 0.1143)
		(layer "In2.Cu")
		(net "SAS2X28_B_HDD7_RX_+")
	)
	(segment
		(start 32.776668 -267.259816)
		(end 32.776668 -267.259562)
		(width 0.1143)
		(layer "In2.Cu")
		(net "SAS2X28_B_HDD7_RX_+")
	)
	(segment
		(start 32.004254 -267.48105)
		(end 32.004508 -267.48105)
		(width 0.1143)
		(layer "In2.Cu")
		(net "SAS2X28_B_HDD7_RX_+")
	)
	(segment
		(start 31.3182 -263.185402)
		(end 31.3182 -208.085182)
		(width 0.1143)
		(layer "In2.Cu")
		(net "SAS2X28_B_HDD7_RX_+")
	)
	(segment
		(start 30.3784 -205.8162)
		(end 29.865828 -205.303628)
		(width 0.1143)
		(layer "In2.Cu")
		(net "SAS2X28_B_HDD7_RX_+")
	)
	(segment
		(start 7.095744 -121.514616)
		(end 6.679946 -121.514616)
		(width 0.1143)
		(layer "In2.Cu")
		(net "SAS2X28_B_HDD7_RX_+")
	)
	(segment
		(start 33.019746 -266.672822)
		(end 33.019746 -265.973814)
		(width 0.1143)
		(layer "In2.Cu")
		(net "SAS2X28_B_HDD7_RX_+")
	)
	(segment
		(start 32.752792 -265.328654)
		(end 31.819342 -264.395204)
		(width 0.1143)
		(layer "In2.Cu")
		(net "SAS2X28_B_HDD7_RX_+")
	)
	(segment
		(start 29.405326 -131.388866)
		(end 28.881832 -130.865372)
		(width 0.1143)
		(layer "In2.Cu")
		(net "SAS2X28_B_HDD7_RX_+")
	)
	(arc
		(start 32.258 -267.4747)
		(mid 32.538693 -267.418809)
		(end 32.776668 -267.259816)
		(width 0.1143)
		(layer "In2.Cu")
		(net "SAS2X28_B_HDD7_RX_+")
	)
	(arc
		(start 31.3182 -208.085182)
		(mid 31.073946 -206.857234)
		(end 30.3784 -205.8162)
		(width 0.1143)
		(layer "In2.Cu")
		(net "SAS2X28_B_HDD7_RX_+")
	)
	(arc
		(start 32.004508 -267.48105)
		(mid 32.056609 -267.476306)
		(end 32.108902 -267.4747)
		(width 0.1143)
		(layer "In2.Cu")
		(net "SAS2X28_B_HDD7_RX_+")
	)
	(arc
		(start 7.563358 -121.693178)
		(mid 7.536895 -121.668793)
		(end 7.508494 -121.646696)
		(width 0.1143)
		(layer "In2.Cu")
		(net "SAS2X28_B_HDD7_RX_+")
	)
	(arc
		(start 29.730954 -132.175504)
		(mid 29.646371 -131.749805)
		(end 29.405326 -131.388866)
		(width 0.1143)
		(layer "In2.Cu")
		(net "SAS2X28_B_HDD7_RX_+")
	)
	(arc
		(start 32.776668 -267.259562)
		(mid 32.956594 -266.990378)
		(end 33.019746 -266.672822)
		(width 0.1143)
		(layer "In2.Cu")
		(net "SAS2X28_B_HDD7_RX_+")
	)
	(arc
		(start 31.495746 -267.7287)
		(mid 31.729242 -267.562254)
		(end 32.004254 -267.48105)
		(width 0.1143)
		(layer "In2.Cu")
		(net "SAS2X28_B_HDD7_RX_+")
	)
	(arc
		(start 29.865828 -205.303628)
		(mid 29.766003 -205.154229)
		(end 29.730954 -204.978)
		(width 0.1143)
		(layer "In2.Cu")
		(net "SAS2X28_B_HDD7_RX_+")
	)
	(arc
		(start 7.508494 -121.646696)
		(mid 7.312436 -121.548404)
		(end 7.095744 -121.514616)
		(width 0.1143)
		(layer "In2.Cu")
		(net "SAS2X28_B_HDD7_RX_+")
	)
	(arc
		(start 31.819342 -264.395204)
		(mid 31.448462 -263.840142)
		(end 31.3182 -263.185402)
		(width 0.1143)
		(layer "In2.Cu")
		(net "SAS2X28_B_HDD7_RX_+")
	)
	(arc
		(start 20.159726 -122.14352)
		(mid 19.808121 -121.908678)
		(end 19.393408 -121.826274)
		(width 0.1143)
		(layer "In2.Cu")
		(net "SAS2X28_B_HDD7_RX_+")
	)
	(arc
		(start 33.019746 -265.973814)
		(mid 32.9503 -265.624777)
		(end 32.752538 -265.328908)
		(width 0.1143)
		(layer "In2.Cu")
		(net "SAS2X28_B_HDD7_RX_+")
	)
	(arc
		(start 7.88416 -121.826274)
		(mid 7.710529 -121.791625)
		(end 7.563358 -121.693178)
		(width 0.1143)
		(layer "In2.Cu")
		(net "SAS2X28_B_HDD7_RX_+")
	)
	(segment
		(start 10.307574 -385.543552)
		(end 10.307574 -390.553956)
		(width 0.09525)
		(layer "F.Cu")
		(net "SAS2X28_A_HDD2_TX_+")
	)
	(segment
		(start 4.689094 -394.49883)
		(end 3.192526 -394.49883)
		(width 0.09525)
		(layer "F.Cu")
		(net "SAS2X28_A_HDD2_TX_+")
	)
	(segment
		(start 10.064242 -391.14095)
		(end 6.553454 -394.651992)
		(width 0.09525)
		(layer "F.Cu")
		(net "SAS2X28_A_HDD2_TX_+")
	)
	(segment
		(start 221.4372 -259.536692)
		(end 218.552268 -259.536692)
		(width 0.09525)
		(layer "F.Cu")
		(net "SAS2X28_A_HDD2_TX_+")
	)
	(segment
		(start 221.795848 -259.127752)
		(end 221.762066 -259.161534)
		(width 0.09525)
		(layer "F.Cu")
		(net "SAS2X28_A_HDD2_TX_+")
	)
	(segment
		(start 25.891236 -361.717336)
		(end 25.41397 -362.194602)
		(width 0.09525)
		(layer "F.Cu")
		(net "SAS2X28_A_HDD2_TX_+")
	)
	(segment
		(start 221.734888 -259.199634)
		(end 221.724728 -259.22097)
		(width 0.09525)
		(layer "F.Cu")
		(net "SAS2X28_A_HDD2_TX_+")
	)
	(segment
		(start 6.122416 -394.830554)
		(end 5.487924 -394.830554)
		(width 0.09525)
		(layer "F.Cu")
		(net "SAS2X28_A_HDD2_TX_+")
	)
	(segment
		(start 25.41397 -362.194602)
		(end 25.413716 -362.19511)
		(width 0.09525)
		(layer "F.Cu")
		(net "SAS2X28_A_HDD2_TX_+")
	)
	(segment
		(start 25.413716 -362.19511)
		(end 25.141936 -362.46689)
		(width 0.09525)
		(layer "F.Cu")
		(net "SAS2X28_A_HDD2_TX_+")
	)
	(segment
		(start 64.995806 -322.612258)
		(end 64.196722 -323.41185)
		(width 0.09525)
		(layer "F.Cu")
		(net "SAS2X28_A_HDD2_TX_+")
	)
	(segment
		(start 217.842084 -259.650738)
		(end 66.026538 -321.886326)
		(width 0.09525)
		(layer "F.Cu")
		(net "SAS2X28_A_HDD2_TX_+")
	)
	(segment
		(start 24.574246 -363.838744)
		(end 24.574246 -369.77955)
		(width 0.09525)
		(layer "F.Cu")
		(net "SAS2X28_A_HDD2_TX_+")
	)
	(segment
		(start 223.249998 -259.070094)
		(end 223.24314 -259.076952)
		(width 0.09525)
		(layer "F.Cu")
		(net "SAS2X28_A_HDD2_TX_+")
	)
	(segment
		(start 223.24314 -259.076952)
		(end 221.918276 -259.076952)
		(width 0.09525)
		(layer "F.Cu")
		(net "SAS2X28_A_HDD2_TX_+")
	)
	(segment
		(start 64.996314 -322.612766)
		(end 64.995806 -322.612258)
		(width 0.09525)
		(layer "F.Cu")
		(net "SAS2X28_A_HDD2_TX_+")
	)
	(segment
		(start 64.196722 -323.41185)
		(end 26.665936 -360.94289)
		(width 0.09525)
		(layer "F.Cu")
		(net "SAS2X28_A_HDD2_TX_+")
	)
	(segment
		(start 4.690618 -394.500354)
		(end 4.689094 -394.49883)
		(width 0.09525)
		(layer "F.Cu")
		(net "SAS2X28_A_HDD2_TX_+")
	)
	(segment
		(start 26.665936 -360.94289)
		(end 25.891236 -361.717336)
		(width 0.09525)
		(layer "F.Cu")
		(net "SAS2X28_A_HDD2_TX_+")
	)
	(segment
		(start 24.129746 -370.8527)
		(end 10.921746 -384.0607)
		(width 0.09525)
		(layer "F.Cu")
		(net "SAS2X28_A_HDD2_TX_+")
	)
	(arc
		(start 221.724728 -259.22097)
		(mid 221.718646 -259.238678)
		(end 221.7166 -259.257292)
		(width 0.09525)
		(layer "F.Cu")
		(net "SAS2X28_A_HDD2_TX_+")
	)
	(arc
		(start 5.239512 -394.727684)
		(mid 4.987677 -394.559413)
		(end 4.690618 -394.500354)
		(width 0.09525)
		(layer "F.Cu")
		(net "SAS2X28_A_HDD2_TX_+")
	)
	(arc
		(start 66.026538 -321.886326)
		(mid 65.998517 -321.897488)
		(end 65.971166 -321.910202)
		(width 0.09525)
		(layer "F.Cu")
		(net "SAS2X28_A_HDD2_TX_+")
	)
	(arc
		(start 221.570296 -259.50291)
		(mid 221.505857 -259.528109)
		(end 221.4372 -259.536692)
		(width 0.09525)
		(layer "F.Cu")
		(net "SAS2X28_A_HDD2_TX_+")
	)
	(arc
		(start 5.487924 -394.830554)
		(mid 5.353494 -394.803814)
		(end 5.239512 -394.727684)
		(width 0.09525)
		(layer "F.Cu")
		(net "SAS2X28_A_HDD2_TX_+")
	)
	(arc
		(start 10.921746 -384.0607)
		(mid 10.467188 -384.741039)
		(end 10.307574 -385.543552)
		(width 0.09525)
		(layer "F.Cu")
		(net "SAS2X28_A_HDD2_TX_+")
	)
	(arc
		(start 218.552268 -259.536692)
		(mid 218.190597 -259.552747)
		(end 217.842084 -259.650738)
		(width 0.09525)
		(layer "F.Cu")
		(net "SAS2X28_A_HDD2_TX_+")
	)
	(arc
		(start 6.553454 -394.651992)
		(mid 6.355692 -394.784132)
		(end 6.122416 -394.830554)
		(width 0.09525)
		(layer "F.Cu")
		(net "SAS2X28_A_HDD2_TX_+")
	)
	(arc
		(start 25.141936 -362.46689)
		(mid 24.721752 -363.096401)
		(end 24.574246 -363.838744)
		(width 0.09525)
		(layer "F.Cu")
		(net "SAS2X28_A_HDD2_TX_+")
	)
	(arc
		(start 221.7166 -259.257292)
		(mid 221.677259 -259.400247)
		(end 221.570296 -259.50291)
		(width 0.09525)
		(layer "F.Cu")
		(net "SAS2X28_A_HDD2_TX_+")
	)
	(arc
		(start 65.971166 -321.910202)
		(mid 65.455408 -322.22217)
		(end 64.996314 -322.612766)
		(width 0.09525)
		(layer "F.Cu")
		(net "SAS2X28_A_HDD2_TX_+")
	)
	(arc
		(start 221.918276 -259.076952)
		(mid 221.851999 -259.090153)
		(end 221.795848 -259.127752)
		(width 0.09525)
		(layer "F.Cu")
		(net "SAS2X28_A_HDD2_TX_+")
	)
	(arc
		(start 10.307574 -390.553956)
		(mid 10.244286 -390.871654)
		(end 10.064242 -391.14095)
		(width 0.09525)
		(layer "F.Cu")
		(net "SAS2X28_A_HDD2_TX_+")
	)
	(arc
		(start 221.762066 -259.161534)
		(mid 221.746869 -259.179437)
		(end 221.734888 -259.199634)
		(width 0.09525)
		(layer "F.Cu")
		(net "SAS2X28_A_HDD2_TX_+")
	)
	(arc
		(start 24.574246 -369.77955)
		(mid 24.458722 -370.36033)
		(end 24.129746 -370.8527)
		(width 0.09525)
		(layer "F.Cu")
		(net "SAS2X28_A_HDD2_TX_+")
	)
	(segment
		(start 82.041746 -408.139646)
		(end 5.520182 -408.139646)
		(width 0.09525)
		(layer "F.Cu")
		(net "SAS2X28_A_HDD1_TX_-")
	)
	(segment
		(start 223.249998 -363.340142)
		(end 221.90202 -363.340142)
		(width 0.09525)
		(layer "F.Cu")
		(net "SAS2X28_A_HDD1_TX_-")
	)
	(segment
		(start 215.286082 -362.964984)
		(end 201.733404 -367.579402)
		(width 0.09525)
		(layer "F.Cu")
		(net "SAS2X28_A_HDD1_TX_-")
	)
	(segment
		(start 5.265928 -408.244802)
		(end 5.265674 -408.245056)
		(width 0.09525)
		(layer "F.Cu")
		(net "SAS2X28_A_HDD1_TX_-")
	)
	(segment
		(start 4.64947 -408.500326)
		(end 4.647946 -408.498802)
		(width 0.09525)
		(layer "F.Cu")
		(net "SAS2X28_A_HDD1_TX_-")
	)
	(segment
		(start 221.741746 -363.179868)
		(end 221.741746 -363.01934)
		(width 0.09525)
		(layer "F.Cu")
		(net "SAS2X28_A_HDD1_TX_-")
	)
	(segment
		(start 221.589346 -362.86694)
		(end 215.899746 -362.86694)
		(width 0.09525)
		(layer "F.Cu")
		(net "SAS2X28_A_HDD1_TX_-")
	)
	(segment
		(start 4.647946 -408.498802)
		(end 3.192526 -408.498802)
		(width 0.09525)
		(layer "F.Cu")
		(net "SAS2X28_A_HDD1_TX_-")
	)
	(segment
		(start 186.620912 -372.724934)
		(end 83.13547 -407.959306)
		(width 0.09525)
		(layer "F.Cu")
		(net "SAS2X28_A_HDD1_TX_-")
	)
	(segment
		(start 201.733404 -367.579402)
		(end 186.620912 -372.724934)
		(width 0.09525)
		(layer "F.Cu")
		(net "SAS2X28_A_HDD1_TX_-")
	)
	(arc
		(start 5.265674 -408.245056)
		(mid 4.982957 -408.433961)
		(end 4.64947 -408.500326)
		(width 0.09525)
		(layer "F.Cu")
		(net "SAS2X28_A_HDD1_TX_-")
	)
	(arc
		(start 5.520182 -408.139646)
		(mid 5.510399 -408.139765)
		(end 5.500624 -408.140154)
		(width 0.09525)
		(layer "F.Cu")
		(net "SAS2X28_A_HDD1_TX_-")
	)
	(arc
		(start 221.741746 -363.01934)
		(mid 221.697109 -362.911577)
		(end 221.589346 -362.86694)
		(width 0.09525)
		(layer "F.Cu")
		(net "SAS2X28_A_HDD1_TX_-")
	)
	(arc
		(start 83.10245 -407.970482)
		(mid 82.578805 -408.097119)
		(end 82.041746 -408.139646)
		(width 0.09525)
		(layer "F.Cu")
		(net "SAS2X28_A_HDD1_TX_-")
	)
	(arc
		(start 215.899746 -362.86694)
		(mid 215.589023 -362.891605)
		(end 215.286082 -362.964984)
		(width 0.09525)
		(layer "F.Cu")
		(net "SAS2X28_A_HDD1_TX_-")
	)
	(arc
		(start 5.500624 -408.140154)
		(mid 5.373589 -408.170748)
		(end 5.265928 -408.244802)
		(width 0.09525)
		(layer "F.Cu")
		(net "SAS2X28_A_HDD1_TX_-")
	)
	(arc
		(start 83.13547 -407.959306)
		(mid 83.118988 -407.964976)
		(end 83.10245 -407.970482)
		(width 0.09525)
		(layer "F.Cu")
		(net "SAS2X28_A_HDD1_TX_-")
	)
	(arc
		(start 221.90202 -363.340142)
		(mid 221.788689 -363.293199)
		(end 221.741746 -363.179868)
		(width 0.09525)
		(layer "F.Cu")
		(net "SAS2X28_A_HDD1_TX_-")
	)
	(via
		(at 53.848 -392.303)
		(size 0.7112)
		(drill 0.3556)
		(layers "F.Cu" "B.Cu")
		(net "12V_PRE_6")
	)
	(segment
		(start 31.140146 -161.9885)
		(end 31.165546 -161.9631)
		(width 0.09525)
		(layer "F.Cu")
		(net "SAS2X28_B_HDD7_TX_-")
	)
	(segment
		(start 41.39565 -267.789914)
		(end 41.398952 -267.786612)
		(width 0.09525)
		(layer "F.Cu")
		(net "SAS2X28_B_HDD7_TX_-")
	)
	(segment
		(start 37.7444 -191.153796)
		(end 37.7444 -189.369954)
		(width 0.09525)
		(layer "F.Cu")
		(net "SAS2X28_B_HDD7_TX_-")
	)
	(segment
		(start 37.007292 -187.794646)
		(end 31.538418 -182.325772)
		(width 0.09525)
		(layer "F.Cu")
		(net "SAS2X28_B_HDD7_TX_-")
	)
	(segment
		(start 31.089346 -181.2417)
		(end 31.089346 -162.111182)
		(width 0.09525)
		(layer "F.Cu")
		(net "SAS2X28_B_HDD7_TX_-")
	)
	(segment
		(start 41.781476 -267.6017)
		(end 42.366946 -267.6017)
		(width 0.09525)
		(layer "F.Cu")
		(net "SAS2X28_B_HDD7_TX_-")
	)
	(segment
		(start 5.623814 -124.165868)
		(end 15.875 -124.165868)
		(width 0.09525)
		(layer "F.Cu")
		(net "SAS2X28_B_HDD7_TX_-")
	)
	(segment
		(start 16.30553 -124.344176)
		(end 16.323818 -124.362464)
		(width 0.09525)
		(layer "F.Cu")
		(net "SAS2X28_B_HDD7_TX_-")
	)
	(segment
		(start 42.976546 -266.9921)
		(end 42.976546 -255.905762)
		(width 0.09525)
		(layer "F.Cu")
		(net "SAS2X28_B_HDD7_TX_-")
	)
	(segment
		(start 40.39997 -267.789914)
		(end 41.39565 -267.789914)
		(width 0.09525)
		(layer "F.Cu")
		(net "SAS2X28_B_HDD7_TX_-")
	)
	(segment
		(start 37.744146 -191.15405)
		(end 37.7444 -191.153796)
		(width 0.09525)
		(layer "F.Cu")
		(net "SAS2X28_B_HDD7_TX_-")
	)
	(segment
		(start 37.007546 -187.794646)
		(end 37.007292 -187.794646)
		(width 0.09525)
		(layer "F.Cu")
		(net "SAS2X28_B_HDD7_TX_-")
	)
	(segment
		(start 4.814824 -124.498862)
		(end 4.816348 -124.500386)
		(width 0.09525)
		(layer "F.Cu")
		(net "SAS2X28_B_HDD7_TX_-")
	)
	(segment
		(start 37.744146 -249.46991)
		(end 37.744146 -191.15405)
		(width 0.09525)
		(layer "F.Cu")
		(net "SAS2X28_B_HDD7_TX_-")
	)
	(segment
		(start 42.392346 -254.4953)
		(end 38.010846 -250.1138)
		(width 0.09525)
		(layer "F.Cu")
		(net "SAS2X28_B_HDD7_TX_-")
	)
	(segment
		(start 31.65221 -162.068764)
		(end 31.876746 -162.2933)
		(width 0.09525)
		(layer "F.Cu")
		(net "SAS2X28_B_HDD7_TX_-")
	)
	(segment
		(start 3.192526 -124.498862)
		(end 4.814824 -124.498862)
		(width 0.09525)
		(layer "F.Cu")
		(net "SAS2X28_B_HDD7_TX_-")
	)
	(segment
		(start 37.152326 -187.939426)
		(end 37.007546 -187.794646)
		(width 0.09525)
		(layer "F.Cu")
		(net "SAS2X28_B_HDD7_TX_-")
	)
	(via
		(at 31.876746 -162.2933)
		(size 0.5588)
		(drill 0.3048)
		(layers "F.Cu" "B.Cu")
		(net "SAS2X28_B_HDD7_TX_-")
	)
	(via
		(at 16.323818 -124.362464)
		(size 0.5588)
		(drill 0.3048)
		(layers "F.Cu" "B.Cu")
		(net "SAS2X28_B_HDD7_TX_-")
	)
	(arc
		(start 37.7444 -189.369954)
		(mid 37.59062 -188.595816)
		(end 37.152326 -187.939426)
		(width 0.09525)
		(layer "F.Cu")
		(net "SAS2X28_B_HDD7_TX_-")
	)
	(arc
		(start 42.976546 -255.905762)
		(mid 42.824659 -255.142463)
		(end 42.392346 -254.4953)
		(width 0.09525)
		(layer "F.Cu")
		(net "SAS2X28_B_HDD7_TX_-")
	)
	(arc
		(start 31.10865 -181.484016)
		(mid 31.094185 -181.363241)
		(end 31.089346 -181.2417)
		(width 0.09525)
		(layer "F.Cu")
		(net "SAS2X28_B_HDD7_TX_-")
	)
	(arc
		(start 41.477946 -267.753846)
		(mid 41.525047 -267.725949)
		(end 41.566846 -267.6906)
		(width 0.09525)
		(layer "F.Cu")
		(net "SAS2X28_B_HDD7_TX_-")
	)
	(arc
		(start 42.366946 -267.6017)
		(mid 42.797998 -267.423152)
		(end 42.976546 -266.9921)
		(width 0.09525)
		(layer "F.Cu")
		(net "SAS2X28_B_HDD7_TX_-")
	)
	(arc
		(start 41.566846 -267.6906)
		(mid 41.665319 -267.624802)
		(end 41.781476 -267.6017)
		(width 0.09525)
		(layer "F.Cu")
		(net "SAS2X28_B_HDD7_TX_-")
	)
	(arc
		(start 15.875 -124.165868)
		(mid 16.107992 -124.212213)
		(end 16.30553 -124.344176)
		(width 0.09525)
		(layer "F.Cu")
		(net "SAS2X28_B_HDD7_TX_-")
	)
	(arc
		(start 31.374588 -161.907728)
		(mid 31.523937 -161.970088)
		(end 31.65221 -162.068764)
		(width 0.09525)
		(layer "F.Cu")
		(net "SAS2X28_B_HDD7_TX_-")
	)
	(arc
		(start 41.398952 -267.786612)
		(mid 41.441721 -267.778105)
		(end 41.477946 -267.753846)
		(width 0.09525)
		(layer "F.Cu")
		(net "SAS2X28_B_HDD7_TX_-")
	)
	(arc
		(start 31.538418 -182.325772)
		(mid 31.257051 -181.938838)
		(end 31.10865 -181.484016)
		(width 0.09525)
		(layer "F.Cu")
		(net "SAS2X28_B_HDD7_TX_-")
	)
	(arc
		(start 31.165546 -161.9631)
		(mid 31.262625 -161.907263)
		(end 31.374588 -161.907728)
		(width 0.09525)
		(layer "F.Cu")
		(net "SAS2X28_B_HDD7_TX_-")
	)
	(arc
		(start 5.32892 -124.288042)
		(mid 5.464219 -124.197638)
		(end 5.623814 -124.165868)
		(width 0.09525)
		(layer "F.Cu")
		(net "SAS2X28_B_HDD7_TX_-")
	)
	(arc
		(start 4.816348 -124.500386)
		(mid 5.093761 -124.445205)
		(end 5.32892 -124.288042)
		(width 0.09525)
		(layer "F.Cu")
		(net "SAS2X28_B_HDD7_TX_-")
	)
	(arc
		(start 31.089346 -162.111182)
		(mid 31.102552 -162.044793)
		(end 31.140146 -161.9885)
		(width 0.09525)
		(layer "F.Cu")
		(net "SAS2X28_B_HDD7_TX_-")
	)
	(arc
		(start 38.010846 -250.1138)
		(mid 37.813453 -249.818381)
		(end 37.744146 -249.46991)
		(width 0.09525)
		(layer "F.Cu")
		(net "SAS2X28_B_HDD7_TX_-")
	)
	(segment
		(start 20.706842 -124.41555)
		(end 28.136342 -131.84505)
		(width 0.1143)
		(layer "In5.Cu")
		(net "SAS2X28_B_HDD7_TX_-")
	)
	(segment
		(start 28.7655 -159.892746)
		(end 30.504892 -161.632138)
		(width 0.1143)
		(layer "In5.Cu")
		(net "SAS2X28_B_HDD7_TX_-")
	)
	(segment
		(start 31.165546 -161.937446)
		(end 31.165546 -161.9377)
		(width 0.1143)
		(layer "In5.Cu")
		(net "SAS2X28_B_HDD7_TX_-")
	)
	(segment
		(start 31.574994 -161.991548)
		(end 31.876746 -162.2933)
		(width 0.1143)
		(layer "In5.Cu")
		(net "SAS2X28_B_HDD7_TX_-")
	)
	(segment
		(start 31.165546 -161.9377)
		(end 31.444946 -161.9377)
		(width 0.1143)
		(layer "In5.Cu")
		(net "SAS2X28_B_HDD7_TX_-")
	)
	(segment
		(start 16.882364 -124.13107)
		(end 20.020026 -124.13107)
		(width 0.1143)
		(layer "In5.Cu")
		(net "SAS2X28_B_HDD7_TX_-")
	)
	(segment
		(start 30.504892 -161.632138)
		(end 30.559248 -161.686748)
		(width 0.1143)
		(layer "In5.Cu")
		(net "SAS2X28_B_HDD7_TX_-")
	)
	(segment
		(start 28.352242 -132.366258)
		(end 28.352242 -158.894526)
		(width 0.1143)
		(layer "In5.Cu")
		(net "SAS2X28_B_HDD7_TX_-")
	)
	(arc
		(start 16.323818 -124.362464)
		(mid 16.580081 -124.191234)
		(end 16.882364 -124.13107)
		(width 0.1143)
		(layer "In5.Cu")
		(net "SAS2X28_B_HDD7_TX_-")
	)
	(arc
		(start 30.559248 -161.686748)
		(mid 30.837451 -161.872421)
		(end 31.165546 -161.937446)
		(width 0.1143)
		(layer "In5.Cu")
		(net "SAS2X28_B_HDD7_TX_-")
	)
	(arc
		(start 31.444946 -161.9377)
		(mid 31.51532 -161.951698)
		(end 31.574994 -161.991548)
		(width 0.1143)
		(layer "In5.Cu")
		(net "SAS2X28_B_HDD7_TX_-")
	)
	(arc
		(start 28.352242 -158.894526)
		(mid 28.459601 -159.434729)
		(end 28.7655 -159.892746)
		(width 0.1143)
		(layer "In5.Cu")
		(net "SAS2X28_B_HDD7_TX_-")
	)
	(arc
		(start 28.136342 -131.84505)
		(mid 28.296125 -132.084182)
		(end 28.352242 -132.366258)
		(width 0.1143)
		(layer "In5.Cu")
		(net "SAS2X28_B_HDD7_TX_-")
	)
	(arc
		(start 20.020026 -124.13107)
		(mid 20.391725 -124.205006)
		(end 20.706842 -124.41555)
		(width 0.1143)
		(layer "In5.Cu")
		(net "SAS2X28_B_HDD7_TX_-")
	)
	(segment
		(start 215.203278 -362.644182)
		(end 201.626724 -367.266474)
		(width 0.09525)
		(layer "F.Cu")
		(net "SAS2X28_A_HDD1_TX_+")
	)
	(segment
		(start 82.041746 -407.809446)
		(end 5.482844 -407.809446)
		(width 0.09525)
		(layer "F.Cu")
		(net "SAS2X28_A_HDD1_TX_+")
	)
	(segment
		(start 221.741746 -362.227368)
		(end 221.741746 -362.38434)
		(width 0.09525)
		(layer "F.Cu")
		(net "SAS2X28_A_HDD1_TX_+")
	)
	(segment
		(start 4.735068 -407.498804)
		(end 3.192526 -407.498804)
		(width 0.09525)
		(layer "F.Cu")
		(net "SAS2X28_A_HDD1_TX_+")
	)
	(segment
		(start 4.736592 -407.500328)
		(end 4.735068 -407.498804)
		(width 0.09525)
		(layer "F.Cu")
		(net "SAS2X28_A_HDD1_TX_+")
	)
	(segment
		(start 221.589346 -362.53674)
		(end 215.899746 -362.53674)
		(width 0.09525)
		(layer "F.Cu")
		(net "SAS2X28_A_HDD1_TX_+")
	)
	(segment
		(start 201.626724 -367.266474)
		(end 186.514232 -372.412006)
		(width 0.09525)
		(layer "F.Cu")
		(net "SAS2X28_A_HDD1_TX_+")
	)
	(segment
		(start 186.514232 -372.412006)
		(end 82.999834 -407.656538)
		(width 0.09525)
		(layer "F.Cu")
		(net "SAS2X28_A_HDD1_TX_+")
	)
	(segment
		(start 223.249998 -362.070142)
		(end 221.898972 -362.070142)
		(width 0.09525)
		(layer "F.Cu")
		(net "SAS2X28_A_HDD1_TX_+")
	)
	(arc
		(start 82.999834 -407.656538)
		(mid 82.526853 -407.770981)
		(end 82.041746 -407.809446)
		(width 0.09525)
		(layer "F.Cu")
		(net "SAS2X28_A_HDD1_TX_+")
	)
	(arc
		(start 215.899746 -362.53674)
		(mid 215.547392 -362.563758)
		(end 215.203278 -362.644182)
		(width 0.09525)
		(layer "F.Cu")
		(net "SAS2X28_A_HDD1_TX_+")
	)
	(arc
		(start 221.898972 -362.070142)
		(mid 221.787796 -362.116192)
		(end 221.741746 -362.227368)
		(width 0.09525)
		(layer "F.Cu")
		(net "SAS2X28_A_HDD1_TX_+")
	)
	(arc
		(start 5.482844 -407.809446)
		(mid 5.358426 -407.784698)
		(end 5.252974 -407.714196)
		(width 0.09525)
		(layer "F.Cu")
		(net "SAS2X28_A_HDD1_TX_+")
	)
	(arc
		(start 5.252974 -407.714196)
		(mid 5.016056 -407.555892)
		(end 4.736592 -407.500328)
		(width 0.09525)
		(layer "F.Cu")
		(net "SAS2X28_A_HDD1_TX_+")
	)
	(arc
		(start 221.741746 -362.38434)
		(mid 221.697109 -362.492103)
		(end 221.589346 -362.53674)
		(width 0.09525)
		(layer "F.Cu")
		(net "SAS2X28_A_HDD1_TX_+")
	)
	(segment
		(start 12.094718 -386.316474)
		(end 12.094972 -386.316728)
		(width 0.09525)
		(layer "F.Cu")
		(net "SAS2X28_A_HDD2_RX_+")
	)
	(segment
		(start 27.564588 -361.841542)
		(end 26.398728 -363.00664)
		(width 0.09525)
		(layer "F.Cu")
		(net "SAS2X28_A_HDD2_RX_+")
	)
	(segment
		(start 216.407746 -263.726168)
		(end 213.944962 -263.726168)
		(width 0.09525)
		(layer "F.Cu")
		(net "SAS2X28_A_HDD2_RX_+")
	)
	(segment
		(start 11.029696 -392.296904)
		(end 8.172196 -395.154404)
		(width 0.09525)
		(layer "F.Cu")
		(net "SAS2X28_A_HDD2_RX_+")
	)
	(segment
		(start 65.540128 -323.866002)
		(end 27.564588 -361.841542)
		(width 0.09525)
		(layer "F.Cu")
		(net "SAS2X28_A_HDD2_RX_+")
	)
	(segment
		(start 12.094972 -386.316728)
		(end 12.094972 -389.9027)
		(width 0.09525)
		(layer "F.Cu")
		(net "SAS2X28_A_HDD2_RX_+")
	)
	(segment
		(start 212.93709 -263.897618)
		(end 66.273172 -323.394578)
		(width 0.09525)
		(layer "F.Cu")
		(net "SAS2X28_A_HDD2_RX_+")
	)
	(segment
		(start 25.844246 -364.34522)
		(end 25.844246 -370.578634)
		(width 0.09525)
		(layer "F.Cu")
		(net "SAS2X28_A_HDD2_RX_+")
	)
	(segment
		(start 12.094718 -385.663948)
		(end 12.094718 -386.316474)
		(width 0.09525)
		(layer "F.Cu")
		(net "SAS2X28_A_HDD2_RX_+")
	)
	(segment
		(start 25.336246 -371.8052)
		(end 12.53109 -384.610356)
		(width 0.09525)
		(layer "F.Cu")
		(net "SAS2X28_A_HDD2_RX_+")
	)
	(segment
		(start 7.454646 -396.5067)
		(end 7.454646 -398.6657)
		(width 0.09525)
		(layer "F.Cu")
		(net "SAS2X28_A_HDD2_RX_+")
	)
	(via
		(at 7.75208 -399.300446)
		(size 0.5588)
		(drill 0.3048)
		(layers "F.Cu" "B.Cu")
		(net "SAS2X28_A_HDD2_RX_+")
	)
	(arc
		(start 213.944962 -263.726168)
		(mid 213.431692 -263.757012)
		(end 212.93709 -263.897618)
		(width 0.09525)
		(layer "F.Cu")
		(net "SAS2X28_A_HDD2_RX_+")
	)
	(arc
		(start 12.53109 -384.610356)
		(mid 12.208098 -385.093748)
		(end 12.094718 -385.663948)
		(width 0.09525)
		(layer "F.Cu")
		(net "SAS2X28_A_HDD2_RX_+")
	)
	(arc
		(start 66.273172 -323.394578)
		(mid 65.88134 -323.590935)
		(end 65.540128 -323.866002)
		(width 0.09525)
		(layer "F.Cu")
		(net "SAS2X28_A_HDD2_RX_+")
	)
	(arc
		(start 26.398728 -363.00664)
		(mid 25.988369 -363.620786)
		(end 25.844246 -364.34522)
		(width 0.09525)
		(layer "F.Cu")
		(net "SAS2X28_A_HDD2_RX_+")
	)
	(arc
		(start 7.918196 -395.40815)
		(mid 7.57526 -395.910522)
		(end 7.454646 -396.5067)
		(width 0.09525)
		(layer "F.Cu")
		(net "SAS2X28_A_HDD2_RX_+")
	)
	(arc
		(start 12.094972 -389.9027)
		(mid 11.816628 -391.212943)
		(end 11.029696 -392.296904)
		(width 0.09525)
		(layer "F.Cu")
		(net "SAS2X28_A_HDD2_RX_+")
	)
	(arc
		(start 7.454646 -398.6657)
		(mid 7.532692 -399.016188)
		(end 7.75208 -399.300446)
		(width 0.09525)
		(layer "F.Cu")
		(net "SAS2X28_A_HDD2_RX_+")
	)
	(arc
		(start 25.844246 -370.578634)
		(mid 25.712157 -371.242398)
		(end 25.336246 -371.8052)
		(width 0.09525)
		(layer "F.Cu")
		(net "SAS2X28_A_HDD2_RX_+")
	)
	(arc
		(start 8.172196 -395.154404)
		(mid 8.045228 -395.281309)
		(end 7.918196 -395.40815)
		(width 0.09525)
		(layer "F.Cu")
		(net "SAS2X28_A_HDD2_RX_+")
	)
	(arc
		(start 217.318082 -264.005568)
		(mid 216.883868 -263.797601)
		(end 216.407746 -263.726168)
		(width 0.09525)
		(layer "F.Cu")
		(net "SAS2X28_A_HDD2_RX_+")
	)
	(segment
		(start 5.249164 -397.74241)
		(end 5.221986 -397.715232)
		(width 0.09525)
		(layer "B.Cu")
		(net "SAS2X28_A_HDD2_RX_+")
	)
	(segment
		(start 6.349746 -397.830548)
		(end 5.50037 -397.830548)
		(width 0.09525)
		(layer "B.Cu")
		(net "SAS2X28_A_HDD2_RX_+")
	)
	(segment
		(start 4.703318 -397.500348)
		(end 4.701794 -397.498824)
		(width 0.09525)
		(layer "B.Cu")
		(net "SAS2X28_A_HDD2_RX_+")
	)
	(segment
		(start 4.701794 -397.498824)
		(end 2.811526 -397.498824)
		(width 0.09525)
		(layer "B.Cu")
		(net "SAS2X28_A_HDD2_RX_+")
	)
	(arc
		(start 5.455158 -397.827754)
		(mid 5.343668 -397.805577)
		(end 5.249164 -397.74241)
		(width 0.09525)
		(layer "B.Cu")
		(net "SAS2X28_A_HDD2_RX_+")
	)
	(arc
		(start 7.535926 -398.64157)
		(mid 7.295082 -398.304785)
		(end 6.984746 -398.0307)
		(width 0.09525)
		(layer "B.Cu")
		(net "SAS2X28_A_HDD2_RX_+")
	)
	(arc
		(start 5.221986 -397.715232)
		(mid 4.984019 -397.556228)
		(end 4.703318 -397.500348)
		(width 0.09525)
		(layer "B.Cu")
		(net "SAS2X28_A_HDD2_RX_+")
	)
	(arc
		(start 6.984746 -398.0307)
		(mid 6.938494 -398.000059)
		(end 6.890766 -397.971772)
		(width 0.09525)
		(layer "B.Cu")
		(net "SAS2X28_A_HDD2_RX_+")
	)
	(arc
		(start 7.75208 -399.300446)
		(mid 7.675462 -398.960689)
		(end 7.535926 -398.64157)
		(width 0.09525)
		(layer "B.Cu")
		(net "SAS2X28_A_HDD2_RX_+")
	)
	(arc
		(start 5.50037 -397.830548)
		(mid 5.477723 -397.829808)
		(end 5.455158 -397.827754)
		(width 0.09525)
		(layer "B.Cu")
		(net "SAS2X28_A_HDD2_RX_+")
	)
	(arc
		(start 6.890766 -397.971772)
		(mid 6.629312 -397.866485)
		(end 6.349746 -397.830548)
		(width 0.09525)
		(layer "B.Cu")
		(net "SAS2X28_A_HDD2_RX_+")
	)
	(segment
		(start 42.158666 -254.728726)
		(end 37.77742 -250.34748)
		(width 0.09525)
		(layer "F.Cu")
		(net "SAS2X28_B_HDD7_TX_+")
	)
	(segment
		(start 37.413946 -249.46991)
		(end 37.413946 -191.017144)
		(width 0.09525)
		(layer "F.Cu")
		(net "SAS2X28_B_HDD7_TX_+")
	)
	(segment
		(start 36.870386 -188.124846)
		(end 31.304738 -182.559452)
		(width 0.09525)
		(layer "F.Cu")
		(net "SAS2X28_B_HDD7_TX_+")
	)
	(segment
		(start 30.906466 -161.75482)
		(end 30.93212 -161.72942)
		(width 0.09525)
		(layer "F.Cu")
		(net "SAS2X28_B_HDD7_TX_+")
	)
	(segment
		(start 30.759146 -181.241954)
		(end 30.759146 -162.111182)
		(width 0.09525)
		(layer "F.Cu")
		(net "SAS2X28_B_HDD7_TX_+")
	)
	(segment
		(start 36.87064 -188.124846)
		(end 36.870386 -188.124846)
		(width 0.09525)
		(layer "F.Cu")
		(net "SAS2X28_B_HDD7_TX_+")
	)
	(segment
		(start 15.875 -123.835668)
		(end 5.57276 -123.835668)
		(width 0.09525)
		(layer "F.Cu")
		(net "SAS2X28_B_HDD7_TX_+")
	)
	(segment
		(start 41.521126 -267.07592)
		(end 41.635426 -267.19022)
		(width 0.09525)
		(layer "F.Cu")
		(net "SAS2X28_B_HDD7_TX_+")
	)
	(segment
		(start 31.807658 -161.498788)
		(end 31.876746 -161.4297)
		(width 0.09525)
		(layer "F.Cu")
		(net "SAS2X28_B_HDD7_TX_+")
	)
	(segment
		(start 41.302686 -266.990068)
		(end 41.305988 -266.986766)
		(width 0.09525)
		(layer "F.Cu")
		(net "SAS2X28_B_HDD7_TX_+")
	)
	(segment
		(start 37.4142 -191.01689)
		(end 37.4142 -189.3697)
		(width 0.09525)
		(layer "F.Cu")
		(net "SAS2X28_B_HDD7_TX_+")
	)
	(segment
		(start 31.46171 -161.589212)
		(end 31.589472 -161.589212)
		(width 0.09525)
		(layer "F.Cu")
		(net "SAS2X28_B_HDD7_TX_+")
	)
	(segment
		(start 4.763262 -123.500388)
		(end 4.761738 -123.498864)
		(width 0.09525)
		(layer "F.Cu")
		(net "SAS2X28_B_HDD7_TX_+")
	)
	(segment
		(start 37.413946 -191.017144)
		(end 37.4142 -191.01689)
		(width 0.09525)
		(layer "F.Cu")
		(net "SAS2X28_B_HDD7_TX_+")
	)
	(segment
		(start 42.646346 -266.9921)
		(end 42.646346 -255.906016)
		(width 0.09525)
		(layer "F.Cu")
		(net "SAS2X28_B_HDD7_TX_+")
	)
	(segment
		(start 41.831768 -267.2715)
		(end 42.366946 -267.2715)
		(width 0.09525)
		(layer "F.Cu")
		(net "SAS2X28_B_HDD7_TX_+")
	)
	(segment
		(start 36.918646 -188.173106)
		(end 36.87064 -188.124846)
		(width 0.09525)
		(layer "F.Cu")
		(net "SAS2X28_B_HDD7_TX_+")
	)
	(segment
		(start 16.301212 -123.499118)
		(end 16.027908 -123.772168)
		(width 0.09525)
		(layer "F.Cu")
		(net "SAS2X28_B_HDD7_TX_+")
	)
	(segment
		(start 40.39997 -266.990068)
		(end 41.302686 -266.990068)
		(width 0.09525)
		(layer "F.Cu")
		(net "SAS2X28_B_HDD7_TX_+")
	)
	(segment
		(start 4.761738 -123.498864)
		(end 3.192526 -123.498864)
		(width 0.09525)
		(layer "F.Cu")
		(net "SAS2X28_B_HDD7_TX_+")
	)
	(via
		(at 31.876746 -161.4297)
		(size 0.5588)
		(drill 0.3048)
		(layers "F.Cu" "B.Cu")
		(net "SAS2X28_B_HDD7_TX_+")
	)
	(via
		(at 16.301212 -123.499118)
		(size 0.5588)
		(drill 0.3048)
		(layers "F.Cu" "B.Cu")
		(net "SAS2X28_B_HDD7_TX_+")
	)
	(arc
		(start 30.759146 -162.111182)
		(mid 30.797404 -161.918378)
		(end 30.906466 -161.75482)
		(width 0.09525)
		(layer "F.Cu")
		(net "SAS2X28_B_HDD7_TX_+")
	)
	(arc
		(start 37.77742 -250.34748)
		(mid 37.508419 -249.944847)
		(end 37.413946 -249.46991)
		(width 0.09525)
		(layer "F.Cu")
		(net "SAS2X28_B_HDD7_TX_+")
	)
	(arc
		(start 5.260594 -123.706382)
		(mid 5.032416 -123.553918)
		(end 4.763262 -123.500388)
		(width 0.09525)
		(layer "F.Cu")
		(net "SAS2X28_B_HDD7_TX_+")
	)
	(arc
		(start 16.027908 -123.772168)
		(mid 15.957768 -123.819127)
		(end 15.875 -123.835668)
		(width 0.09525)
		(layer "F.Cu")
		(net "SAS2X28_B_HDD7_TX_+")
	)
	(arc
		(start 30.782514 -181.53634)
		(mid 30.764992 -181.389611)
		(end 30.759146 -181.241954)
		(width 0.09525)
		(layer "F.Cu")
		(net "SAS2X28_B_HDD7_TX_+")
	)
	(arc
		(start 37.4142 -189.3697)
		(mid 37.285408 -188.722129)
		(end 36.918646 -188.173106)
		(width 0.09525)
		(layer "F.Cu")
		(net "SAS2X28_B_HDD7_TX_+")
	)
	(arc
		(start 41.305988 -266.986766)
		(mid 41.422436 -267.009929)
		(end 41.521126 -267.07592)
		(width 0.09525)
		(layer "F.Cu")
		(net "SAS2X28_B_HDD7_TX_+")
	)
	(arc
		(start 42.366946 -267.2715)
		(mid 42.564512 -267.189666)
		(end 42.646346 -266.9921)
		(width 0.09525)
		(layer "F.Cu")
		(net "SAS2X28_B_HDD7_TX_+")
	)
	(arc
		(start 30.93212 -161.72942)
		(mid 31.178052 -161.588099)
		(end 31.46171 -161.589212)
		(width 0.09525)
		(layer "F.Cu")
		(net "SAS2X28_B_HDD7_TX_+")
	)
	(arc
		(start 31.589472 -161.589212)
		(mid 31.707558 -161.565705)
		(end 31.807658 -161.498788)
		(width 0.09525)
		(layer "F.Cu")
		(net "SAS2X28_B_HDD7_TX_+")
	)
	(arc
		(start 41.635426 -267.19022)
		(mid 41.725508 -267.250411)
		(end 41.831768 -267.2715)
		(width 0.09525)
		(layer "F.Cu")
		(net "SAS2X28_B_HDD7_TX_+")
	)
	(arc
		(start 42.646346 -255.906016)
		(mid 42.519608 -255.26886)
		(end 42.158666 -254.728726)
		(width 0.09525)
		(layer "F.Cu")
		(net "SAS2X28_B_HDD7_TX_+")
	)
	(arc
		(start 31.304738 -182.559452)
		(mid 30.96281 -182.089145)
		(end 30.782514 -181.53634)
		(width 0.09525)
		(layer "F.Cu")
		(net "SAS2X28_B_HDD7_TX_+")
	)
	(arc
		(start 5.57276 -123.835668)
		(mid 5.403824 -123.802064)
		(end 5.260594 -123.706382)
		(width 0.09525)
		(layer "F.Cu")
		(net "SAS2X28_B_HDD7_TX_+")
	)
	(segment
		(start 31.835344 -161.471356)
		(end 31.876746 -161.4297)
		(width 0.1143)
		(layer "In5.Cu")
		(net "SAS2X28_B_HDD7_TX_+")
	)
	(segment
		(start 31.165546 -161.6329)
		(end 31.444946 -161.6329)
		(width 0.1143)
		(layer "In5.Cu")
		(net "SAS2X28_B_HDD7_TX_+")
	)
	(segment
		(start 28.657042 -132.366004)
		(end 28.657042 -158.894526)
		(width 0.1143)
		(layer "In5.Cu")
		(net "SAS2X28_B_HDD7_TX_+")
	)
	(segment
		(start 30.721046 -161.417)
		(end 30.775148 -161.471356)
		(width 0.1143)
		(layer "In5.Cu")
		(net "SAS2X28_B_HDD7_TX_+")
	)
	(segment
		(start 17.091152 -123.82627)
		(end 20.020026 -123.82627)
		(width 0.1143)
		(layer "In5.Cu")
		(net "SAS2X28_B_HDD7_TX_+")
	)
	(segment
		(start 28.981146 -159.6771)
		(end 30.721046 -161.417)
		(width 0.1143)
		(layer "In5.Cu")
		(net "SAS2X28_B_HDD7_TX_+")
	)
	(segment
		(start 20.922488 -124.199904)
		(end 28.351988 -131.629404)
		(width 0.1143)
		(layer "In5.Cu")
		(net "SAS2X28_B_HDD7_TX_+")
	)
	(arc
		(start 28.657042 -158.894526)
		(mid 28.741283 -159.318033)
		(end 28.981146 -159.6771)
		(width 0.1143)
		(layer "In5.Cu")
		(net "SAS2X28_B_HDD7_TX_+")
	)
	(arc
		(start 30.775148 -161.471356)
		(mid 30.954279 -161.590955)
		(end 31.165546 -161.6329)
		(width 0.1143)
		(layer "In5.Cu")
		(net "SAS2X28_B_HDD7_TX_+")
	)
	(arc
		(start 16.301212 -123.499118)
		(mid 16.66364 -123.741284)
		(end 17.091152 -123.82627)
		(width 0.1143)
		(layer "In5.Cu")
		(net "SAS2X28_B_HDD7_TX_+")
	)
	(arc
		(start 31.444946 -161.6329)
		(mid 31.656219 -161.590969)
		(end 31.835344 -161.471356)
		(width 0.1143)
		(layer "In5.Cu")
		(net "SAS2X28_B_HDD7_TX_+")
	)
	(arc
		(start 28.351988 -131.629404)
		(mid 28.577749 -131.967373)
		(end 28.657042 -132.366004)
		(width 0.1143)
		(layer "In5.Cu")
		(net "SAS2X28_B_HDD7_TX_+")
	)
	(arc
		(start 20.020026 -123.82627)
		(mid 20.508421 -123.923324)
		(end 20.922488 -124.199904)
		(width 0.1143)
		(layer "In5.Cu")
		(net "SAS2X28_B_HDD7_TX_+")
	)
	(via
		(at 53.593746 -493.2807)
		(size 0.5588)
		(drill 0.3048)
		(layers "F.Cu" "B.Cu")
		(net "12V_PRE_5")
	)
	(via
		(at 53.593746 -494.2205)
		(size 0.7112)
		(drill 0.3556)
		(layers "F.Cu" "B.Cu")
		(net "12V_PRE_5")
	)
	(segment
		(start 53.593746 -493.2807)
		(end 53.593746 -494.2205)
		(width 0.508)
		(layer "B.Cu")
		(net "12V_PRE_5")
	)
	(segment
		(start 230.780082 -247.495568)
		(end 230.780082 -246.479568)
		(width 0.111252)
		(layer "F.Cu")
		(net "DRIVE_ACT_2")
	)
	(segment
		(start 232.115614 -246.479568)
		(end 232.295446 -246.6594)
		(width 0.111252)
		(layer "F.Cu")
		(net "DRIVE_ACT_2")
	)
	(segment
		(start 230.780082 -246.479568)
		(end 232.115614 -246.479568)
		(width 0.111252)
		(layer "F.Cu")
		(net "DRIVE_ACT_2")
	)
	(segment
		(start 236.092746 -246.6594)
		(end 232.295446 -246.6594)
		(width 0.111252)
		(layer "F.Cu")
		(net "DRIVE_ACT_2")
	)
	(via
		(at 236.092746 -246.6594)
		(size 0.7112)
		(drill 0.3556)
		(layers "F.Cu" "B.Cu")
		(net "DRIVE_ACT_2")
	)
	(segment
		(start 216.999058 -377.519184)
		(end 216.999058 -376.325384)
		(width 0.111252)
		(layer "F.Cu")
		(net "HDD_PRSNT1")
	)
	(segment
		(start 216.999058 -376.325384)
		(end 216.999058 -375.2977)
		(width 0.111252)
		(layer "F.Cu")
		(net "HDD_PRSNT1")
	)
	(via
		(at 216.999058 -375.2977)
		(size 0.5588)
		(drill 0.3048)
		(layers "F.Cu" "B.Cu")
		(net "HDD_PRSNT1")
	)
	(via
		(at 7.594346 -462.5467)
		(size 0.5588)
		(drill 0.3048)
		(layers "F.Cu" "B.Cu")
		(net "HDD_PRSNT1")
	)
	(via
		(at 24.5364 -463.804)
		(size 0.5588)
		(drill 0.3048)
		(layers "F.Cu" "B.Cu")
		(net "HDD_PRSNT1")
	)
	(via
		(at 216.999058 -376.325384)
		(size 0.7112)
		(drill 0.3556)
		(layers "F.Cu" "B.Cu")
		(net "HDD_PRSNT1")
	)
	(via
		(at 9.423146 -206.0829)
		(size 0.5588)
		(drill 0.3048)
		(layers "F.Cu" "B.Cu")
		(net "HDD_PRSNT1")
	)
	(segment
		(start 10.927842 -463.925412)
		(end 9.544304 -462.541874)
		(width 0.111252)
		(layer "B.Cu")
		(net "HDD_PRSNT1")
	)
	(segment
		(start 6.549136 -461.50149)
		(end 2.812542 -461.50149)
		(width 0.111252)
		(layer "B.Cu")
		(net "HDD_PRSNT1")
	)
	(segment
		(start 8.841486 -205.50124)
		(end 2.812542 -205.50124)
		(width 0.111252)
		(layer "B.Cu")
		(net "HDD_PRSNT1")
	)
	(segment
		(start 2.812542 -461.50149)
		(end 2.80924 -461.504792)
		(width 0.111252)
		(layer "B.Cu")
		(net "HDD_PRSNT1")
	)
	(segment
		(start 7.594346 -462.5467)
		(end 6.549136 -461.50149)
		(width 0.111252)
		(layer "B.Cu")
		(net "HDD_PRSNT1")
	)
	(segment
		(start 24.5364 -463.804)
		(end 19.498564 -463.804)
		(width 0.111252)
		(layer "B.Cu")
		(net "HDD_PRSNT1")
	)
	(segment
		(start 9.423146 -206.0829)
		(end 8.841486 -205.50124)
		(width 0.111252)
		(layer "B.Cu")
		(net "HDD_PRSNT1")
	)
	(segment
		(start 7.599172 -462.541874)
		(end 7.594346 -462.5467)
		(width 0.111252)
		(layer "B.Cu")
		(net "HDD_PRSNT1")
	)
	(segment
		(start 19.377152 -463.925412)
		(end 10.927842 -463.925412)
		(width 0.111252)
		(layer "B.Cu")
		(net "HDD_PRSNT1")
	)
	(segment
		(start 2.812542 -205.50124)
		(end 2.80924 -205.504542)
		(width 0.111252)
		(layer "B.Cu")
		(net "HDD_PRSNT1")
	)
	(segment
		(start 9.544304 -462.541874)
		(end 7.599172 -462.541874)
		(width 0.111252)
		(layer "B.Cu")
		(net "HDD_PRSNT1")
	)
	(segment
		(start 19.498564 -463.804)
		(end 19.377152 -463.925412)
		(width 0.111252)
		(layer "B.Cu")
		(net "HDD_PRSNT1")
	)
	(segment
		(start 10.635234 -395.388592)
		(end 10.321544 -395.074902)
		(width 0.14605)
		(layer "In2.Cu")
		(net "HDD_PRSNT1")
	)
	(segment
		(start 9.625838 -211.95665)
		(end 9.140444 -211.471256)
		(width 0.14605)
		(layer "In2.Cu")
		(net "HDD_PRSNT1")
	)
	(segment
		(start 8.178038 -461.963008)
		(end 8.18769 -461.91424)
		(width 0.14605)
		(layer "In2.Cu")
		(net "HDD_PRSNT1")
	)
	(segment
		(start 11.483086 -265.097768)
		(end 12.2555 -264.325354)
		(width 0.14605)
		(layer "In2.Cu")
		(net "HDD_PRSNT1")
	)
	(segment
		(start 11.48334 -268.462506)
		(end 11.483086 -268.462252)
		(width 0.14605)
		(layer "In2.Cu")
		(net "HDD_PRSNT1")
	)
	(segment
		(start 11.48334 -366.533938)
		(end 11.48334 -268.462506)
		(width 0.14605)
		(layer "In2.Cu")
		(net "HDD_PRSNT1")
	)
	(segment
		(start 6.033262 -438.57037)
		(end 10.50036 -434.103272)
		(width 0.14605)
		(layer "In2.Cu")
		(net "HDD_PRSNT1")
	)
	(segment
		(start 9.625838 -217.245438)
		(end 9.625838 -211.95665)
		(width 0.14605)
		(layer "In2.Cu")
		(net "HDD_PRSNT1")
	)
	(segment
		(start 11.175238 -218.794838)
		(end 9.625838 -217.245438)
		(width 0.14605)
		(layer "In2.Cu")
		(net "HDD_PRSNT1")
	)
	(segment
		(start 8.18769 -457.893928)
		(end 8.178546 -457.8477)
		(width 0.14605)
		(layer "In2.Cu")
		(net "HDD_PRSNT1")
	)
	(segment
		(start 11.94435 -374.419876)
		(end 11.94435 -366.994948)
		(width 0.14605)
		(layer "In2.Cu")
		(net "HDD_PRSNT1")
	)
	(segment
		(start 10.50036 -434.103272)
		(end 10.50036 -407.456894)
		(width 0.14605)
		(layer "In2.Cu")
		(net "HDD_PRSNT1")
	)
	(segment
		(start 10.50036 -407.456894)
		(end 10.238994 -407.195528)
		(width 0.14605)
		(layer "In2.Cu")
		(net "HDD_PRSNT1")
	)
	(segment
		(start 10.635234 -399.617946)
		(end 10.635234 -395.388592)
		(width 0.14605)
		(layer "In2.Cu")
		(net "HDD_PRSNT1")
	)
	(segment
		(start 9.140444 -211.471256)
		(end 9.140444 -208.402428)
		(width 0.14605)
		(layer "In2.Cu")
		(net "HDD_PRSNT1")
	)
	(segment
		(start 7.594346 -462.5467)
		(end 8.178038 -461.963008)
		(width 0.14605)
		(layer "In2.Cu")
		(net "HDD_PRSNT1")
	)
	(segment
		(start 12.2555 -260.080252)
		(end 12.255246 -260.079998)
		(width 0.14605)
		(layer "In2.Cu")
		(net "HDD_PRSNT1")
	)
	(segment
		(start 12.2555 -264.325354)
		(end 12.2555 -260.080252)
		(width 0.14605)
		(layer "In2.Cu")
		(net "HDD_PRSNT1")
	)
	(segment
		(start 12.255246 -259.540756)
		(end 11.738102 -258.986528)
		(width 0.14605)
		(layer "In2.Cu")
		(net "HDD_PRSNT1")
	)
	(segment
		(start 11.738102 -257.79476)
		(end 11.175238 -257.231896)
		(width 0.14605)
		(layer "In2.Cu")
		(net "HDD_PRSNT1")
	)
	(segment
		(start 9.423146 -206.128112)
		(end 9.423146 -206.0829)
		(width 0.14605)
		(layer "In2.Cu")
		(net "HDD_PRSNT1")
	)
	(segment
		(start 9.140444 -208.402428)
		(end 9.432798 -208.110074)
		(width 0.14605)
		(layer "In2.Cu")
		(net "HDD_PRSNT1")
	)
	(segment
		(start 11.426698 -390.989312)
		(end 11.426698 -374.937528)
		(width 0.14605)
		(layer "In2.Cu")
		(net "HDD_PRSNT1")
	)
	(segment
		(start 8.178546 -457.8477)
		(end 6.033262 -455.702416)
		(width 0.14605)
		(layer "In2.Cu")
		(net "HDD_PRSNT1")
	)
	(segment
		(start 10.238994 -407.195528)
		(end 10.238994 -400.014186)
		(width 0.14605)
		(layer "In2.Cu")
		(net "HDD_PRSNT1")
	)
	(segment
		(start 9.432798 -208.110074)
		(end 9.432798 -206.137764)
		(width 0.14605)
		(layer "In2.Cu")
		(net "HDD_PRSNT1")
	)
	(segment
		(start 10.321544 -392.094466)
		(end 11.426698 -390.989312)
		(width 0.14605)
		(layer "In2.Cu")
		(net "HDD_PRSNT1")
	)
	(segment
		(start 8.18769 -461.91424)
		(end 8.18769 -457.893928)
		(width 0.14605)
		(layer "In2.Cu")
		(net "HDD_PRSNT1")
	)
	(segment
		(start 6.033262 -455.702416)
		(end 6.033262 -438.57037)
		(width 0.14605)
		(layer "In2.Cu")
		(net "HDD_PRSNT1")
	)
	(segment
		(start 10.321544 -395.074902)
		(end 10.321544 -392.094466)
		(width 0.14605)
		(layer "In2.Cu")
		(net "HDD_PRSNT1")
	)
	(segment
		(start 11.426698 -374.937528)
		(end 11.94435 -374.419876)
		(width 0.14605)
		(layer "In2.Cu")
		(net "HDD_PRSNT1")
	)
	(segment
		(start 11.175238 -257.231896)
		(end 11.175238 -218.794838)
		(width 0.14605)
		(layer "In2.Cu")
		(net "HDD_PRSNT1")
	)
	(segment
		(start 10.238994 -400.014186)
		(end 10.635234 -399.617946)
		(width 0.14605)
		(layer "In2.Cu")
		(net "HDD_PRSNT1")
	)
	(segment
		(start 11.738102 -258.986528)
		(end 11.738102 -257.79476)
		(width 0.14605)
		(layer "In2.Cu")
		(net "HDD_PRSNT1")
	)
	(segment
		(start 11.483086 -268.462252)
		(end 11.483086 -265.097768)
		(width 0.14605)
		(layer "In2.Cu")
		(net "HDD_PRSNT1")
	)
	(segment
		(start 12.255246 -260.079998)
		(end 12.255246 -259.540756)
		(width 0.14605)
		(layer "In2.Cu")
		(net "HDD_PRSNT1")
	)
	(segment
		(start 9.432798 -206.137764)
		(end 9.423146 -206.128112)
		(width 0.14605)
		(layer "In2.Cu")
		(net "HDD_PRSNT1")
	)
	(segment
		(start 11.94435 -366.994948)
		(end 11.48334 -366.533938)
		(width 0.14605)
		(layer "In2.Cu")
		(net "HDD_PRSNT1")
	)
	(segment
		(start 214.931498 -386.751576)
		(end 214.931498 -387.010148)
		(width 0.14605)
		(layer "In5.Cu")
		(net "HDD_PRSNT1")
	)
	(segment
		(start 25.068784 -464.336384)
		(end 137.605516 -464.336384)
		(width 0.14605)
		(layer "In5.Cu")
		(net "HDD_PRSNT1")
	)
	(segment
		(start 214.60587 -386.425948)
		(end 214.931498 -386.751576)
		(width 0.14605)
		(layer "In5.Cu")
		(net "HDD_PRSNT1")
	)
	(segment
		(start 213.819994 -387.211824)
		(end 213.819994 -386.751576)
		(width 0.14605)
		(layer "In5.Cu")
		(net "HDD_PRSNT1")
	)
	(segment
		(start 214.145622 -387.537452)
		(end 213.819994 -387.211824)
		(width 0.14605)
		(layer "In5.Cu")
		(net "HDD_PRSNT1")
	)
	(segment
		(start 24.5364 -463.804)
		(end 25.068784 -464.336384)
		(width 0.14605)
		(layer "In5.Cu")
		(net "HDD_PRSNT1")
	)
	(segment
		(start 213.819994 -386.751576)
		(end 214.145622 -386.425948)
		(width 0.14605)
		(layer "In5.Cu")
		(net "HDD_PRSNT1")
	)
	(segment
		(start 137.605516 -464.336384)
		(end 214.404194 -387.537452)
		(width 0.14605)
		(layer "In5.Cu")
		(net "HDD_PRSNT1")
	)
	(segment
		(start 214.145622 -386.425948)
		(end 214.60587 -386.425948)
		(width 0.14605)
		(layer "In5.Cu")
		(net "HDD_PRSNT1")
	)
	(segment
		(start 214.931498 -387.010148)
		(end 216.999058 -384.942588)
		(width 0.14605)
		(layer "In5.Cu")
		(net "HDD_PRSNT1")
	)
	(segment
		(start 216.999058 -384.942588)
		(end 216.999058 -375.2977)
		(width 0.14605)
		(layer "In5.Cu")
		(net "HDD_PRSNT1")
	)
	(segment
		(start 214.404194 -387.537452)
		(end 214.145622 -387.537452)
		(width 0.14605)
		(layer "In5.Cu")
		(net "HDD_PRSNT1")
	)
	(segment
		(start 18.16862 -308.487826)
		(end 18.168112 -308.487826)
		(width 0.09525)
		(layer "F.Cu")
		(net "SAS2X28_A_HDD7_RX_-")
	)
	(segment
		(start 31.887414 -263.458706)
		(end 31.732474 -263.6139)
		(width 0.09525)
		(layer "F.Cu")
		(net "SAS2X28_A_HDD7_RX_-")
	)
	(segment
		(start 18.20672 -351.642426)
		(end 18.58772 -352.023426)
		(width 0.09525)
		(layer "F.Cu")
		(net "SAS2X28_A_HDD7_RX_-")
	)
	(segment
		(start 21.2598 -317.1444)
		(end 20.758658 -317.645796)
		(width 0.09525)
		(layer "F.Cu")
		(net "SAS2X28_A_HDD7_RX_-")
	)
	(segment
		(start 31.65221 -263.694418)
		(end 18.19021 -277.156418)
		(width 0.09525)
		(layer "F.Cu")
		(net "SAS2X28_A_HDD7_RX_-")
	)
	(segment
		(start 17.678146 -278.393652)
		(end 17.678146 -307.304186)
		(width 0.09525)
		(layer "F.Cu")
		(net "SAS2X28_A_HDD7_RX_-")
	)
	(segment
		(start 19.7612 -318.0588)
		(end 18.402046 -318.0588)
		(width 0.09525)
		(layer "F.Cu")
		(net "SAS2X28_A_HDD7_RX_-")
	)
	(segment
		(start 18.58772 -352.023426)
		(end 18.587974 -352.023426)
		(width 0.09525)
		(layer "F.Cu")
		(net "SAS2X28_A_HDD7_RX_-")
	)
	(segment
		(start 20.75434 -357.396034)
		(end 19.169888 -358.980994)
		(width 0.09525)
		(layer "F.Cu")
		(net "SAS2X28_A_HDD7_RX_-")
	)
	(segment
		(start 21.8186 -314.076588)
		(end 21.8186 -315.795406)
		(width 0.09525)
		(layer "F.Cu")
		(net "SAS2X28_A_HDD7_RX_-")
	)
	(segment
		(start 18.206974 -351.642426)
		(end 18.20672 -351.642426)
		(width 0.09525)
		(layer "F.Cu")
		(net "SAS2X28_A_HDD7_RX_-")
	)
	(segment
		(start 17.779746 -318.825118)
		(end 17.779746 -350.610932)
		(width 0.09525)
		(layer "F.Cu")
		(net "SAS2X28_A_HDD7_RX_-")
	)
	(segment
		(start 22.222714 -353.453954)
		(end 22.222714 -355.1174)
		(width 0.09525)
		(layer "F.Cu")
		(net "SAS2X28_A_HDD7_RX_-")
	)
	(segment
		(start 16.347186 -359.644696)
		(end 16.094964 -359.896918)
		(width 0.09525)
		(layer "F.Cu")
		(net "SAS2X28_A_HDD7_RX_-")
	)
	(segment
		(start 15.314676 -368.464846)
		(end 8.74903 -375.030238)
		(width 0.09525)
		(layer "F.Cu")
		(net "SAS2X28_A_HDD7_RX_-")
	)
	(segment
		(start 21.538946 -356.611682)
		(end 20.761706 -357.389176)
		(width 0.09525)
		(layer "F.Cu")
		(net "SAS2X28_A_HDD7_RX_-")
	)
	(segment
		(start 21.649944 -356.50043)
		(end 21.62556 -356.524814)
		(width 0.09525)
		(layer "F.Cu")
		(net "SAS2X28_A_HDD7_RX_-")
	)
	(segment
		(start 31.953708 -263.392412)
		(end 31.887414 -263.458706)
		(width 0.09525)
		(layer "F.Cu")
		(net "SAS2X28_A_HDD7_RX_-")
	)
	(segment
		(start 31.732474 -263.6139)
		(end 31.699962 -263.646666)
		(width 0.09525)
		(layer "F.Cu")
		(net "SAS2X28_A_HDD7_RX_-")
	)
	(segment
		(start 19.496278 -352.3996)
		(end 21.165058 -352.3996)
		(width 0.09525)
		(layer "F.Cu")
		(net "SAS2X28_A_HDD7_RX_-")
	)
	(segment
		(start 21.62556 -356.524814)
		(end 21.538946 -356.611682)
		(width 0.09525)
		(layer "F.Cu")
		(net "SAS2X28_A_HDD7_RX_-")
	)
	(segment
		(start 8.74903 -375.030238)
		(end 8.508238 -375.27103)
		(width 0.09525)
		(layer "F.Cu")
		(net "SAS2X28_A_HDD7_RX_-")
	)
	(segment
		(start 8.473948 -375.305574)
		(end 8.251952 -375.52757)
		(width 0.09525)
		(layer "F.Cu")
		(net "SAS2X28_A_HDD7_RX_-")
	)
	(segment
		(start 31.65221 -263.694672)
		(end 31.65221 -263.694418)
		(width 0.09525)
		(layer "F.Cu")
		(net "SAS2X28_A_HDD7_RX_-")
	)
	(segment
		(start 18.168112 -308.487826)
		(end 20.448016 -310.76773)
		(width 0.09525)
		(layer "F.Cu")
		(net "SAS2X28_A_HDD7_RX_-")
	)
	(segment
		(start 15.768574 -360.684826)
		(end 15.768574 -367.36909)
		(width 0.09525)
		(layer "F.Cu")
		(net "SAS2X28_A_HDD7_RX_-")
	)
	(segment
		(start 18.287746 -359.3465)
		(end 17.067022 -359.3465)
		(width 0.09525)
		(layer "F.Cu")
		(net "SAS2X28_A_HDD7_RX_-")
	)
	(segment
		(start 20.761706 -357.389176)
		(end 20.754848 -357.396288)
		(width 0.09525)
		(layer "F.Cu")
		(net "SAS2X28_A_HDD7_RX_-")
	)
	(segment
		(start 18.19021 -277.156418)
		(end 18.190464 -277.156672)
		(width 0.09525)
		(layer "F.Cu")
		(net "SAS2X28_A_HDD7_RX_-")
	)
	(segment
		(start 8.508238 -375.27103)
		(end 8.473948 -375.305574)
		(width 0.09525)
		(layer "F.Cu")
		(net "SAS2X28_A_HDD7_RX_-")
	)
	(segment
		(start 21.717 -352.6282)
		(end 21.9964 -352.9076)
		(width 0.09525)
		(layer "F.Cu")
		(net "SAS2X28_A_HDD7_RX_-")
	)
	(segment
		(start 20.754848 -357.396288)
		(end 20.75434 -357.396034)
		(width 0.09525)
		(layer "F.Cu")
		(net "SAS2X28_A_HDD7_RX_-")
	)
	(segment
		(start 31.699962 -263.646666)
		(end 31.65221 -263.694672)
		(width 0.09525)
		(layer "F.Cu")
		(net "SAS2X28_A_HDD7_RX_-")
	)
	(segment
		(start 19.169888 -358.980994)
		(end 19.169888 -358.981248)
		(width 0.09525)
		(layer "F.Cu")
		(net "SAS2X28_A_HDD7_RX_-")
	)
	(via
		(at 7.873746 -376.4407)
		(size 0.5588)
		(drill 0.3048)
		(layers "F.Cu" "B.Cu")
		(net "SAS2X28_A_HDD7_RX_-")
	)
	(arc
		(start 17.779746 -350.610932)
		(mid 17.890717 -351.1692)
		(end 18.206974 -351.642426)
		(width 0.09525)
		(layer "F.Cu")
		(net "SAS2X28_A_HDD7_RX_-")
	)
	(arc
		(start 18.587974 -352.023426)
		(mid 19.004708 -352.301849)
		(end 19.496278 -352.3996)
		(width 0.09525)
		(layer "F.Cu")
		(net "SAS2X28_A_HDD7_RX_-")
	)
	(arc
		(start 17.678146 -307.304186)
		(mid 17.805648 -307.944802)
		(end 18.16862 -308.487826)
		(width 0.09525)
		(layer "F.Cu")
		(net "SAS2X28_A_HDD7_RX_-")
	)
	(arc
		(start 16.094964 -359.896918)
		(mid 15.853421 -360.258413)
		(end 15.768574 -360.684826)
		(width 0.09525)
		(layer "F.Cu")
		(net "SAS2X28_A_HDD7_RX_-")
	)
	(arc
		(start 17.067022 -359.3465)
		(mid 16.677438 -359.423993)
		(end 16.347186 -359.644696)
		(width 0.09525)
		(layer "F.Cu")
		(net "SAS2X28_A_HDD7_RX_-")
	)
	(arc
		(start 15.768574 -367.36909)
		(mid 15.650614 -367.962117)
		(end 15.314676 -368.464846)
		(width 0.09525)
		(layer "F.Cu")
		(net "SAS2X28_A_HDD7_RX_-")
	)
	(arc
		(start 21.8186 -315.795406)
		(mid 21.768345 -316.23041)
		(end 21.620226 -316.642496)
		(width 0.09525)
		(layer "F.Cu")
		(net "SAS2X28_A_HDD7_RX_-")
	)
	(arc
		(start 21.9964 -352.9076)
		(mid 22.163892 -353.158269)
		(end 22.222714 -353.453954)
		(width 0.09525)
		(layer "F.Cu")
		(net "SAS2X28_A_HDD7_RX_-")
	)
	(arc
		(start 32.829246 -263.0297)
		(mid 32.355402 -263.123971)
		(end 31.953708 -263.392412)
		(width 0.09525)
		(layer "F.Cu")
		(net "SAS2X28_A_HDD7_RX_-")
	)
	(arc
		(start 18.402046 -318.0588)
		(mid 18.20288 -318.098417)
		(end 18.034 -318.2112)
		(width 0.09525)
		(layer "F.Cu")
		(net "SAS2X28_A_HDD7_RX_-")
	)
	(arc
		(start 8.251952 -375.52757)
		(mid 7.97202 -375.946518)
		(end 7.873746 -376.4407)
		(width 0.09525)
		(layer "F.Cu")
		(net "SAS2X28_A_HDD7_RX_-")
	)
	(arc
		(start 20.448016 -310.76773)
		(mid 21.462389 -312.285847)
		(end 21.8186 -314.076588)
		(width 0.09525)
		(layer "F.Cu")
		(net "SAS2X28_A_HDD7_RX_-")
	)
	(arc
		(start 21.165058 -352.3996)
		(mid 21.463758 -352.459015)
		(end 21.717 -352.6282)
		(width 0.09525)
		(layer "F.Cu")
		(net "SAS2X28_A_HDD7_RX_-")
	)
	(arc
		(start 20.758658 -317.645796)
		(mid 20.301005 -317.951497)
		(end 19.7612 -318.0588)
		(width 0.09525)
		(layer "F.Cu")
		(net "SAS2X28_A_HDD7_RX_-")
	)
	(arc
		(start 21.620226 -316.642496)
		(mid 21.460479 -316.908147)
		(end 21.2598 -317.1444)
		(width 0.09525)
		(layer "F.Cu")
		(net "SAS2X28_A_HDD7_RX_-")
	)
	(arc
		(start 18.034 -318.2112)
		(mid 17.845795 -318.492868)
		(end 17.779746 -318.825118)
		(width 0.09525)
		(layer "F.Cu")
		(net "SAS2X28_A_HDD7_RX_-")
	)
	(arc
		(start 19.169888 -358.981248)
		(mid 18.765143 -359.251597)
		(end 18.287746 -359.3465)
		(width 0.09525)
		(layer "F.Cu")
		(net "SAS2X28_A_HDD7_RX_-")
	)
	(arc
		(start 18.190464 -277.156672)
		(mid 17.811281 -277.724204)
		(end 17.678146 -278.393652)
		(width 0.09525)
		(layer "F.Cu")
		(net "SAS2X28_A_HDD7_RX_-")
	)
	(arc
		(start 22.222714 -355.1174)
		(mid 22.073853 -355.865866)
		(end 21.649944 -356.50043)
		(width 0.09525)
		(layer "F.Cu")
		(net "SAS2X28_A_HDD7_RX_-")
	)
	(segment
		(start 7.692644 -373.551958)
		(end 6.49732 -372.356634)
		(width 0.09525)
		(layer "B.Cu")
		(net "SAS2X28_A_HDD7_RX_-")
	)
	(segment
		(start 4.701032 -372.500398)
		(end 4.699508 -372.498874)
		(width 0.09525)
		(layer "B.Cu")
		(net "SAS2X28_A_HDD7_RX_-")
	)
	(segment
		(start 8.127746 -375.827544)
		(end 8.127746 -374.60174)
		(width 0.09525)
		(layer "B.Cu")
		(net "SAS2X28_A_HDD7_RX_-")
	)
	(segment
		(start 6.49732 -372.356634)
		(end 6.447536 -372.307104)
		(width 0.09525)
		(layer "B.Cu")
		(net "SAS2X28_A_HDD7_RX_-")
	)
	(segment
		(start 6.095492 -372.1608)
		(end 5.520944 -372.1608)
		(width 0.09525)
		(layer "B.Cu")
		(net "SAS2X28_A_HDD7_RX_-")
	)
	(segment
		(start 6.447536 -372.307104)
		(end 6.447282 -372.30685)
		(width 0.09525)
		(layer "B.Cu")
		(net "SAS2X28_A_HDD7_RX_-")
	)
	(segment
		(start 4.699508 -372.498874)
		(end 2.811526 -372.498874)
		(width 0.09525)
		(layer "B.Cu")
		(net "SAS2X28_A_HDD7_RX_-")
	)
	(arc
		(start 8.127746 -374.60174)
		(mid 8.014565 -374.033593)
		(end 7.692644 -373.551958)
		(width 0.09525)
		(layer "B.Cu")
		(net "SAS2X28_A_HDD7_RX_-")
	)
	(arc
		(start 6.447282 -372.30685)
		(mid 6.285923 -372.198814)
		(end 6.095492 -372.1608)
		(width 0.09525)
		(layer "B.Cu")
		(net "SAS2X28_A_HDD7_RX_-")
	)
	(arc
		(start 5.520944 -372.1608)
		(mid 5.368921 -372.191039)
		(end 5.24002 -372.277132)
		(width 0.09525)
		(layer "B.Cu")
		(net "SAS2X28_A_HDD7_RX_-")
	)
	(arc
		(start 5.24002 -372.277132)
		(mid 4.99273 -372.442366)
		(end 4.701032 -372.500398)
		(width 0.09525)
		(layer "B.Cu")
		(net "SAS2X28_A_HDD7_RX_-")
	)
	(arc
		(start 7.873746 -376.4407)
		(mid 8.061717 -376.159382)
		(end 8.127746 -375.827544)
		(width 0.09525)
		(layer "B.Cu")
		(net "SAS2X28_A_HDD7_RX_-")
	)
	(via
		(at 219.506546 -81.667096)
		(size 0.7112)
		(drill 0.3556)
		(layers "F.Cu" "B.Cu")
		(net "12V_PRE_4")
	)
	(via
		(at 220.446346 -81.6737)
		(size 0.5588)
		(drill 0.3048)
		(layers "F.Cu" "B.Cu")
		(net "12V_PRE_4")
	)
	(segment
		(start 219.51315 -81.6737)
		(end 219.506546 -81.667096)
		(width 0.508)
		(layer "B.Cu")
		(net "12V_PRE_4")
	)
	(segment
		(start 220.446346 -81.6737)
		(end 219.51315 -81.6737)
		(width 0.508)
		(layer "B.Cu")
		(net "12V_PRE_4")
	)
	(segment
		(start 216.4842 -273.6342)
		(end 216.4842 -272.796)
		(width 0.111252)
		(layer "F.Cu")
		(net "HDD_PRSNT2")
	)
	(segment
		(start 216.492582 -273.739864)
		(end 216.4842 -273.6342)
		(width 0.111252)
		(layer "F.Cu")
		(net "HDD_PRSNT2")
	)
	(segment
		(start 216.4842 -272.796)
		(end 216.3064 -272.6182)
		(width 0.111252)
		(layer "F.Cu")
		(net "HDD_PRSNT2")
	)
	(segment
		(start 216.492582 -274.673568)
		(end 216.492582 -273.739864)
		(width 0.111252)
		(layer "F.Cu")
		(net "HDD_PRSNT2")
	)
	(via
		(at 12.166346 -456.8571)
		(size 0.5588)
		(drill 0.3048)
		(layers "F.Cu" "B.Cu")
		(net "HDD_PRSNT2")
	)
	(via
		(at 9.2202 -458.501242)
		(size 0.5588)
		(drill 0.3048)
		(layers "F.Cu" "B.Cu")
		(net "HDD_PRSNT2")
	)
	(via
		(at 216.3064 -272.6182)
		(size 0.7112)
		(drill 0.3556)
		(layers "F.Cu" "B.Cu")
		(net "HDD_PRSNT2")
	)
	(via
		(at 9.503664 -202.954382)
		(size 0.5588)
		(drill 0.3048)
		(layers "F.Cu" "B.Cu")
		(net "HDD_PRSNT2")
	)
	(via
		(at 216.492582 -273.739864)
		(size 0.5588)
		(drill 0.3048)
		(layers "F.Cu" "B.Cu")
		(net "HDD_PRSNT2")
	)
	(segment
		(start 2.812542 -458.501242)
		(end 9.2202 -458.501242)
		(width 0.111252)
		(layer "B.Cu")
		(net "HDD_PRSNT2")
	)
	(segment
		(start 2.80924 -458.504544)
		(end 2.812542 -458.501242)
		(width 0.111252)
		(layer "B.Cu")
		(net "HDD_PRSNT2")
	)
	(segment
		(start 9.050528 -202.501246)
		(end 2.812542 -202.501246)
		(width 0.111252)
		(layer "B.Cu")
		(net "HDD_PRSNT2")
	)
	(segment
		(start 9.503664 -202.954382)
		(end 9.050528 -202.501246)
		(width 0.111252)
		(layer "B.Cu")
		(net "HDD_PRSNT2")
	)
	(segment
		(start 9.2202 -458.501242)
		(end 10.522204 -458.501242)
		(width 0.111252)
		(layer "B.Cu")
		(net "HDD_PRSNT2")
	)
	(segment
		(start 2.812542 -202.501246)
		(end 2.80924 -202.504548)
		(width 0.111252)
		(layer "B.Cu")
		(net "HDD_PRSNT2")
	)
	(segment
		(start 10.522204 -458.501242)
		(end 12.166346 -456.8571)
		(width 0.111252)
		(layer "B.Cu")
		(net "HDD_PRSNT2")
	)
	(segment
		(start 11.877548 -391.176256)
		(end 11.877548 -375.124472)
		(width 0.14605)
		(layer "In2.Cu")
		(net "HDD_PRSNT2")
	)
	(segment
		(start 12.315952 -258.944364)
		(end 12.188952 -258.808474)
		(width 0.14605)
		(layer "In2.Cu")
		(net "HDD_PRSNT2")
	)
	(segment
		(start 12.70635 -264.512298)
		(end 12.70635 -259.893308)
		(width 0.14605)
		(layer "In2.Cu")
		(net "HDD_PRSNT2")
	)
	(segment
		(start 12.706096 -259.893054)
		(end 12.706096 -259.334508)
		(width 0.14605)
		(layer "In2.Cu")
		(net "HDD_PRSNT2")
	)
	(segment
		(start 9.932416 -203.383134)
		(end 9.503664 -202.954382)
		(width 0.14605)
		(layer "In2.Cu")
		(net "HDD_PRSNT2")
	)
	(segment
		(start 6.484112 -455.515472)
		(end 6.484112 -438.7723)
		(width 0.14605)
		(layer "In2.Cu")
		(net "HDD_PRSNT2")
	)
	(segment
		(start 11.877548 -375.124472)
		(end 12.3952 -374.60682)
		(width 0.14605)
		(layer "In2.Cu")
		(net "HDD_PRSNT2")
	)
	(segment
		(start 11.03249 -434.223922)
		(end 11.03249 -413.87522)
		(width 0.14605)
		(layer "In2.Cu")
		(net "HDD_PRSNT2")
	)
	(segment
		(start 9.2202 -458.501242)
		(end 9.2202 -458.25156)
		(width 0.14605)
		(layer "In2.Cu")
		(net "HDD_PRSNT2")
	)
	(segment
		(start 11.626088 -257.044952)
		(end 11.626088 -218.607894)
		(width 0.14605)
		(layer "In2.Cu")
		(net "HDD_PRSNT2")
	)
	(segment
		(start 9.591294 -208.589372)
		(end 9.932416 -208.24825)
		(width 0.14605)
		(layer "In2.Cu")
		(net "HDD_PRSNT2")
	)
	(segment
		(start 11.933936 -268.275308)
		(end 11.933936 -265.284712)
		(width 0.14605)
		(layer "In2.Cu")
		(net "HDD_PRSNT2")
	)
	(segment
		(start 12.188952 -258.808474)
		(end 12.188952 -257.607816)
		(width 0.14605)
		(layer "In2.Cu")
		(net "HDD_PRSNT2")
	)
	(segment
		(start 9.591294 -211.284312)
		(end 9.591294 -208.589372)
		(width 0.14605)
		(layer "In2.Cu")
		(net "HDD_PRSNT2")
	)
	(segment
		(start 6.484112 -438.7723)
		(end 11.03249 -434.223922)
		(width 0.14605)
		(layer "In2.Cu")
		(net "HDD_PRSNT2")
	)
	(segment
		(start 9.2202 -458.25156)
		(end 6.484112 -455.515472)
		(width 0.14605)
		(layer "In2.Cu")
		(net "HDD_PRSNT2")
	)
	(segment
		(start 11.626088 -218.607894)
		(end 10.879582 -217.861388)
		(width 0.14605)
		(layer "In2.Cu")
		(net "HDD_PRSNT2")
	)
	(segment
		(start 10.879582 -217.861388)
		(end 10.879582 -212.5726)
		(width 0.14605)
		(layer "In2.Cu")
		(net "HDD_PRSNT2")
	)
	(segment
		(start 11.93419 -366.346994)
		(end 11.93419 -268.275562)
		(width 0.14605)
		(layer "In2.Cu")
		(net "HDD_PRSNT2")
	)
	(segment
		(start 12.706096 -259.334508)
		(end 12.315952 -258.944364)
		(width 0.14605)
		(layer "In2.Cu")
		(net "HDD_PRSNT2")
	)
	(segment
		(start 11.206988 -395.322552)
		(end 10.772394 -394.887958)
		(width 0.14605)
		(layer "In2.Cu")
		(net "HDD_PRSNT2")
	)
	(segment
		(start 11.198098 -395.983206)
		(end 11.206988 -395.974316)
		(width 0.14605)
		(layer "In2.Cu")
		(net "HDD_PRSNT2")
	)
	(segment
		(start 11.198098 -413.709612)
		(end 11.198098 -395.983206)
		(width 0.14605)
		(layer "In2.Cu")
		(net "HDD_PRSNT2")
	)
	(segment
		(start 10.879582 -212.5726)
		(end 9.591294 -211.284312)
		(width 0.14605)
		(layer "In2.Cu")
		(net "HDD_PRSNT2")
	)
	(segment
		(start 11.933936 -265.284712)
		(end 12.70635 -264.512298)
		(width 0.14605)
		(layer "In2.Cu")
		(net "HDD_PRSNT2")
	)
	(segment
		(start 11.206988 -395.974316)
		(end 11.206988 -395.322552)
		(width 0.14605)
		(layer "In2.Cu")
		(net "HDD_PRSNT2")
	)
	(segment
		(start 9.932416 -208.24825)
		(end 9.932416 -203.383134)
		(width 0.14605)
		(layer "In2.Cu")
		(net "HDD_PRSNT2")
	)
	(segment
		(start 10.772394 -392.28141)
		(end 11.877548 -391.176256)
		(width 0.14605)
		(layer "In2.Cu")
		(net "HDD_PRSNT2")
	)
	(segment
		(start 12.70635 -259.893308)
		(end 12.706096 -259.893054)
		(width 0.14605)
		(layer "In2.Cu")
		(net "HDD_PRSNT2")
	)
	(segment
		(start 12.3952 -374.60682)
		(end 12.3952 -366.808004)
		(width 0.14605)
		(layer "In2.Cu")
		(net "HDD_PRSNT2")
	)
	(segment
		(start 12.188952 -257.607816)
		(end 11.626088 -257.044952)
		(width 0.14605)
		(layer "In2.Cu")
		(net "HDD_PRSNT2")
	)
	(segment
		(start 11.03249 -413.87522)
		(end 11.198098 -413.709612)
		(width 0.14605)
		(layer "In2.Cu")
		(net "HDD_PRSNT2")
	)
	(segment
		(start 11.93419 -268.275562)
		(end 11.933936 -268.275308)
		(width 0.14605)
		(layer "In2.Cu")
		(net "HDD_PRSNT2")
	)
	(segment
		(start 10.772394 -394.887958)
		(end 10.772394 -392.28141)
		(width 0.14605)
		(layer "In2.Cu")
		(net "HDD_PRSNT2")
	)
	(segment
		(start 12.3952 -366.808004)
		(end 11.93419 -366.346994)
		(width 0.14605)
		(layer "In2.Cu")
		(net "HDD_PRSNT2")
	)
	(segment
		(start 138.20394 -465.688934)
		(end 17.540224 -465.688934)
		(width 0.14605)
		(layer "In5.Cu")
		(net "HDD_PRSNT2")
	)
	(segment
		(start 229.008178 -284.959044)
		(end 229.008178 -374.846596)
		(width 0.14605)
		(layer "In5.Cu")
		(net "HDD_PRSNT2")
	)
	(segment
		(start 15.110714 -463.804762)
		(end 13.119354 -461.813402)
		(width 0.14605)
		(layer "In5.Cu")
		(net "HDD_PRSNT2")
	)
	(segment
		(start 17.540224 -465.688934)
		(end 15.656052 -463.804762)
		(width 0.14605)
		(layer "In5.Cu")
		(net "HDD_PRSNT2")
	)
	(segment
		(start 229.008178 -374.846596)
		(end 220.51899 -383.335784)
		(width 0.14605)
		(layer "In5.Cu")
		(net "HDD_PRSNT2")
	)
	(segment
		(start 216.492582 -273.739864)
		(end 217.788998 -273.739864)
		(width 0.14605)
		(layer "In5.Cu")
		(net "HDD_PRSNT2")
	)
	(segment
		(start 217.788998 -273.739864)
		(end 229.008178 -284.959044)
		(width 0.14605)
		(layer "In5.Cu")
		(net "HDD_PRSNT2")
	)
	(segment
		(start 13.119354 -461.813402)
		(end 13.119354 -457.810108)
		(width 0.14605)
		(layer "In5.Cu")
		(net "HDD_PRSNT2")
	)
	(segment
		(start 138.345672 -465.50961)
		(end 138.27887 -465.576412)
		(width 0.14605)
		(layer "In5.Cu")
		(net "HDD_PRSNT2")
	)
	(segment
		(start 138.27887 -465.576412)
		(end 138.20394 -465.688934)
		(width 0.14605)
		(layer "In5.Cu")
		(net "HDD_PRSNT2")
	)
	(segment
		(start 13.119354 -457.810108)
		(end 12.166346 -456.8571)
		(width 0.14605)
		(layer "In5.Cu")
		(net "HDD_PRSNT2")
	)
	(segment
		(start 219.5068 -384.34772)
		(end 219.5068 -384.348228)
		(width 0.14605)
		(layer "In5.Cu")
		(net "HDD_PRSNT2")
	)
	(segment
		(start 219.5068 -384.348228)
		(end 138.345672 -465.50961)
		(width 0.14605)
		(layer "In5.Cu")
		(net "HDD_PRSNT2")
	)
	(segment
		(start 220.51899 -383.335784)
		(end 219.5068 -384.34772)
		(width 0.14605)
		(layer "In5.Cu")
		(net "HDD_PRSNT2")
	)
	(segment
		(start 15.656052 -463.804762)
		(end 15.110714 -463.804762)
		(width 0.14605)
		(layer "In5.Cu")
		(net "HDD_PRSNT2")
	)
	(segment
		(start 4.693412 -128.500378)
		(end 4.691888 -128.498854)
		(width 0.09525)
		(layer "F.Cu")
		(net "SAS2X28_B_HDD1_TX_-")
	)
	(segment
		(start 223.96704 -370.551964)
		(end 223.260412 -370.551964)
		(width 0.09525)
		(layer "F.Cu")
		(net "SAS2X28_B_HDD1_TX_-")
	)
	(segment
		(start 225.399854 -370.789962)
		(end 224.437448 -370.789962)
		(width 0.09525)
		(layer "F.Cu")
		(net "SAS2X28_B_HDD1_TX_-")
	)
	(segment
		(start 6.407912 -128.16078)
		(end 5.513324 -128.16078)
		(width 0.09525)
		(layer "F.Cu")
		(net "SAS2X28_B_HDD1_TX_-")
	)
	(segment
		(start 224.437448 -370.789962)
		(end 224.434146 -370.78666)
		(width 0.09525)
		(layer "F.Cu")
		(net "SAS2X28_B_HDD1_TX_-")
	)
	(segment
		(start 224.203006 -370.690902)
		(end 224.132648 -370.620544)
		(width 0.09525)
		(layer "F.Cu")
		(net "SAS2X28_B_HDD1_TX_-")
	)
	(segment
		(start 4.691888 -128.498854)
		(end 3.192526 -128.498854)
		(width 0.09525)
		(layer "F.Cu")
		(net "SAS2X28_B_HDD1_TX_-")
	)
	(via
		(at 6.705346 -128.458214)
		(size 0.5588)
		(drill 0.3048)
		(layers "F.Cu" "B.Cu")
		(net "SAS2X28_B_HDD1_TX_-")
	)
	(via
		(at 222.974662 -370.837714)
		(size 0.5588)
		(drill 0.3048)
		(layers "F.Cu" "B.Cu")
		(net "SAS2X28_B_HDD1_TX_-")
	)
	(arc
		(start 224.132648 -370.620544)
		(mid 224.056666 -370.569775)
		(end 223.96704 -370.551964)
		(width 0.09525)
		(layer "F.Cu")
		(net "SAS2X28_B_HDD1_TX_-")
	)
	(arc
		(start 5.352288 -128.190498)
		(mid 5.268597 -128.233214)
		(end 5.19557 -128.292352)
		(width 0.09525)
		(layer "F.Cu")
		(net "SAS2X28_B_HDD1_TX_-")
	)
	(arc
		(start 5.513324 -128.16078)
		(mid 5.431445 -128.168256)
		(end 5.352288 -128.190498)
		(width 0.09525)
		(layer "F.Cu")
		(net "SAS2X28_B_HDD1_TX_-")
	)
	(arc
		(start 6.705346 -128.458214)
		(mid 6.61823 -128.247896)
		(end 6.407912 -128.16078)
		(width 0.09525)
		(layer "F.Cu")
		(net "SAS2X28_B_HDD1_TX_-")
	)
	(arc
		(start 223.260412 -370.551964)
		(mid 223.058356 -370.635658)
		(end 222.974662 -370.837714)
		(width 0.09525)
		(layer "F.Cu")
		(net "SAS2X28_B_HDD1_TX_-")
	)
	(arc
		(start 224.434146 -370.78666)
		(mid 224.309048 -370.761776)
		(end 224.203006 -370.690902)
		(width 0.09525)
		(layer "F.Cu")
		(net "SAS2X28_B_HDD1_TX_-")
	)
	(arc
		(start 5.19557 -128.292352)
		(mid 4.965178 -128.446295)
		(end 4.693412 -128.500378)
		(width 0.09525)
		(layer "F.Cu")
		(net "SAS2X28_B_HDD1_TX_-")
	)
	(segment
		(start 11.189716 -128.76403)
		(end 16.326866 -133.900926)
		(width 0.09525)
		(layer "B.Cu")
		(net "SAS2X28_B_HDD1_TX_-")
	)
	(segment
		(start 6.705346 -128.458214)
		(end 6.775196 -128.388364)
		(width 0.09525)
		(layer "B.Cu")
		(net "SAS2X28_B_HDD1_TX_-")
	)
	(segment
		(start 144.476978 -291.977064)
		(end 207.569308 -369.823492)
		(width 0.09525)
		(layer "B.Cu")
		(net "SAS2X28_B_HDD1_TX_-")
	)
	(segment
		(start 17.34566 -135.117078)
		(end 102.82682 -240.587276)
		(width 0.09525)
		(layer "B.Cu")
		(net "SAS2X28_B_HDD1_TX_-")
	)
	(segment
		(start 16.929354 -134.603236)
		(end 17.34566 -135.117078)
		(width 0.09525)
		(layer "B.Cu")
		(net "SAS2X28_B_HDD1_TX_-")
	)
	(segment
		(start 207.77962 -370.08308)
		(end 211.386166 -373.689626)
		(width 0.09525)
		(layer "B.Cu")
		(net "SAS2X28_B_HDD1_TX_-")
	)
	(segment
		(start 16.670528 -134.288276)
		(end 16.929354 -134.603236)
		(width 0.09525)
		(layer "B.Cu")
		(net "SAS2X28_B_HDD1_TX_-")
	)
	(segment
		(start 221.278196 -370.5225)
		(end 222.659448 -370.5225)
		(width 0.09525)
		(layer "B.Cu")
		(net "SAS2X28_B_HDD1_TX_-")
	)
	(segment
		(start 207.569308 -369.823492)
		(end 207.77962 -370.08308)
		(width 0.09525)
		(layer "B.Cu")
		(net "SAS2X28_B_HDD1_TX_-")
	)
	(segment
		(start 212.202522 -374.0277)
		(end 216.737946 -374.0277)
		(width 0.09525)
		(layer "B.Cu")
		(net "SAS2X28_B_HDD1_TX_-")
	)
	(segment
		(start 218.055698 -373.481854)
		(end 220.829124 -370.708428)
		(width 0.09525)
		(layer "B.Cu")
		(net "SAS2X28_B_HDD1_TX_-")
	)
	(segment
		(start 7.365746 -128.143762)
		(end 9.591294 -128.143762)
		(width 0.09525)
		(layer "B.Cu")
		(net "SAS2X28_B_HDD1_TX_-")
	)
	(segment
		(start 102.82682 -240.587276)
		(end 144.476978 -291.977064)
		(width 0.09525)
		(layer "B.Cu")
		(net "SAS2X28_B_HDD1_TX_-")
	)
	(segment
		(start 16.330422 -133.90499)
		(end 16.670528 -134.288276)
		(width 0.09525)
		(layer "B.Cu")
		(net "SAS2X28_B_HDD1_TX_-")
	)
	(segment
		(start 16.326866 -133.900926)
		(end 16.330422 -133.90499)
		(width 0.09525)
		(layer "B.Cu")
		(net "SAS2X28_B_HDD1_TX_-")
	)
	(arc
		(start 211.386166 -373.689626)
		(mid 211.760714 -373.939861)
		(end 212.202522 -374.0277)
		(width 0.09525)
		(layer "B.Cu")
		(net "SAS2X28_B_HDD1_TX_-")
	)
	(arc
		(start 216.737946 -374.0277)
		(mid 217.451114 -373.885842)
		(end 218.055698 -373.481854)
		(width 0.09525)
		(layer "B.Cu")
		(net "SAS2X28_B_HDD1_TX_-")
	)
	(arc
		(start 6.775196 -128.388364)
		(mid 7.046143 -128.207323)
		(end 7.365746 -128.143762)
		(width 0.09525)
		(layer "B.Cu")
		(net "SAS2X28_B_HDD1_TX_-")
	)
	(arc
		(start 222.659448 -370.5225)
		(mid 222.882338 -370.614824)
		(end 222.974662 -370.837714)
		(width 0.09525)
		(layer "B.Cu")
		(net "SAS2X28_B_HDD1_TX_-")
	)
	(arc
		(start 220.829124 -370.708428)
		(mid 221.03516 -370.570759)
		(end 221.278196 -370.5225)
		(width 0.09525)
		(layer "B.Cu")
		(net "SAS2X28_B_HDD1_TX_-")
	)
	(arc
		(start 9.591294 -128.143762)
		(mid 10.447577 -128.30683)
		(end 11.189716 -128.76403)
		(width 0.09525)
		(layer "B.Cu")
		(net "SAS2X28_B_HDD1_TX_-")
	)
	(segment
		(start 19.403568 -359.214674)
		(end 20.75434 -357.86314)
		(width 0.09525)
		(layer "F.Cu")
		(net "SAS2X28_A_HDD7_RX_+")
	)
	(segment
		(start 20.754594 -357.863648)
		(end 20.995386 -357.622856)
		(width 0.09525)
		(layer "F.Cu")
		(net "SAS2X28_A_HDD7_RX_+")
	)
	(segment
		(start 8.75411 -376.347482)
		(end 8.716772 -376.347482)
		(width 0.09525)
		(layer "F.Cu")
		(net "SAS2X28_A_HDD7_RX_+")
	)
	(segment
		(start 31.933642 -263.880346)
		(end 31.966662 -263.847072)
		(width 0.09525)
		(layer "F.Cu")
		(net "SAS2X28_A_HDD7_RX_+")
	)
	(segment
		(start 32.757618 -263.847072)
		(end 32.829246 -263.9187)
		(width 0.09525)
		(layer "F.Cu")
		(net "SAS2X28_A_HDD7_RX_+")
	)
	(segment
		(start 21.950426 -352.39452)
		(end 21.950426 -352.394774)
		(width 0.09525)
		(layer "F.Cu")
		(net "SAS2X28_A_HDD7_RX_+")
	)
	(segment
		(start 20.681696 -310.53405)
		(end 18.402046 -308.2544)
		(width 0.09525)
		(layer "F.Cu")
		(net "SAS2X28_A_HDD7_RX_+")
	)
	(segment
		(start 16.098774 -367.368836)
		(end 16.098774 -360.684826)
		(width 0.09525)
		(layer "F.Cu")
		(net "SAS2X28_A_HDD7_RX_+")
	)
	(segment
		(start 16.328644 -360.130598)
		(end 16.580358 -359.87863)
		(width 0.09525)
		(layer "F.Cu")
		(net "SAS2X28_A_HDD7_RX_+")
	)
	(segment
		(start 18.42389 -277.390098)
		(end 31.933642 -263.880346)
		(width 0.09525)
		(layer "F.Cu")
		(net "SAS2X28_A_HDD7_RX_+")
	)
	(segment
		(start 21.772626 -356.845108)
		(end 21.77288 -356.845108)
		(width 0.09525)
		(layer "F.Cu")
		(net "SAS2X28_A_HDD7_RX_+")
	)
	(segment
		(start 22.1488 -315.79566)
		(end 22.1488 -314.075826)
		(width 0.09525)
		(layer "F.Cu")
		(net "SAS2X28_A_HDD7_RX_+")
	)
	(segment
		(start 8.655304 -375.591578)
		(end 8.707628 -375.539)
		(width 0.09525)
		(layer "F.Cu")
		(net "SAS2X28_A_HDD7_RX_+")
	)
	(segment
		(start 20.75434 -357.86314)
		(end 20.754594 -357.863394)
		(width 0.09525)
		(layer "F.Cu")
		(net "SAS2X28_A_HDD7_RX_+")
	)
	(segment
		(start 18.008346 -307.303932)
		(end 18.008346 -278.393398)
		(width 0.09525)
		(layer "F.Cu")
		(net "SAS2X28_A_HDD7_RX_+")
	)
	(segment
		(start 8.707628 -375.539)
		(end 15.548102 -368.698526)
		(width 0.09525)
		(layer "F.Cu")
		(net "SAS2X28_A_HDD7_RX_+")
	)
	(segment
		(start 22.229826 -352.67392)
		(end 21.950426 -352.39452)
		(width 0.09525)
		(layer "F.Cu")
		(net "SAS2X28_A_HDD7_RX_+")
	)
	(segment
		(start 20.995386 -357.622856)
		(end 21.772626 -356.845108)
		(width 0.09525)
		(layer "F.Cu")
		(net "SAS2X28_A_HDD7_RX_+")
	)
	(segment
		(start 18.109946 -350.611186)
		(end 18.109946 -318.824864)
		(width 0.09525)
		(layer "F.Cu")
		(net "SAS2X28_A_HDD7_RX_+")
	)
	(segment
		(start 20.754594 -357.863394)
		(end 20.754594 -357.863648)
		(width 0.09525)
		(layer "F.Cu")
		(net "SAS2X28_A_HDD7_RX_+")
	)
	(segment
		(start 22.229826 -352.674174)
		(end 22.229826 -352.67392)
		(width 0.09525)
		(layer "F.Cu")
		(net "SAS2X28_A_HDD7_RX_+")
	)
	(segment
		(start 17.067784 -359.6767)
		(end 18.287746 -359.6767)
		(width 0.09525)
		(layer "F.Cu")
		(net "SAS2X28_A_HDD7_RX_+")
	)
	(segment
		(start 21.77288 -356.845108)
		(end 21.85924 -356.75824)
		(width 0.09525)
		(layer "F.Cu")
		(net "SAS2X28_A_HDD7_RX_+")
	)
	(segment
		(start 18.109946 -318.824864)
		(end 18.1102 -318.825118)
		(width 0.09525)
		(layer "F.Cu")
		(net "SAS2X28_A_HDD7_RX_+")
	)
	(segment
		(start 18.8214 -351.79)
		(end 18.4404 -351.409)
		(width 0.09525)
		(layer "F.Cu")
		(net "SAS2X28_A_HDD7_RX_+")
	)
	(segment
		(start 8.485886 -375.760996)
		(end 8.655304 -375.591578)
		(width 0.09525)
		(layer "F.Cu")
		(net "SAS2X28_A_HDD7_RX_+")
	)
	(segment
		(start 18.401792 -318.389)
		(end 19.760946 -318.389)
		(width 0.09525)
		(layer "F.Cu")
		(net "SAS2X28_A_HDD7_RX_+")
	)
	(segment
		(start 21.85924 -356.75824)
		(end 21.883624 -356.73411)
		(width 0.09525)
		(layer "F.Cu")
		(net "SAS2X28_A_HDD7_RX_+")
	)
	(segment
		(start 22.552914 -355.1174)
		(end 22.552914 -353.4537)
		(width 0.09525)
		(layer "F.Cu")
		(net "SAS2X28_A_HDD7_RX_+")
	)
	(segment
		(start 20.992338 -317.879476)
		(end 21.49348 -317.37808)
		(width 0.09525)
		(layer "F.Cu")
		(net "SAS2X28_A_HDD7_RX_+")
	)
	(segment
		(start 21.164804 -352.0694)
		(end 19.496024 -352.0694)
		(width 0.09525)
		(layer "F.Cu")
		(net "SAS2X28_A_HDD7_RX_+")
	)
	(via
		(at 8.75411 -376.347482)
		(size 0.5588)
		(drill 0.3048)
		(layers "F.Cu" "B.Cu")
		(net "SAS2X28_A_HDD7_RX_+")
	)
	(arc
		(start 21.950426 -352.394774)
		(mid 21.589979 -352.153961)
		(end 21.164804 -352.0694)
		(width 0.09525)
		(layer "F.Cu")
		(net "SAS2X28_A_HDD7_RX_+")
	)
	(arc
		(start 18.4404 -351.409)
		(mid 18.19582 -351.04296)
		(end 18.109946 -350.611186)
		(width 0.09525)
		(layer "F.Cu")
		(net "SAS2X28_A_HDD7_RX_+")
	)
	(arc
		(start 21.916136 -316.789308)
		(mid 22.089869 -316.305924)
		(end 22.1488 -315.79566)
		(width 0.09525)
		(layer "F.Cu")
		(net "SAS2X28_A_HDD7_RX_+")
	)
	(arc
		(start 16.580358 -359.87863)
		(mid 16.803991 -359.729203)
		(end 17.067784 -359.6767)
		(width 0.09525)
		(layer "F.Cu")
		(net "SAS2X28_A_HDD7_RX_+")
	)
	(arc
		(start 18.402046 -308.2544)
		(mid 18.110668 -307.818322)
		(end 18.008346 -307.303932)
		(width 0.09525)
		(layer "F.Cu")
		(net "SAS2X28_A_HDD7_RX_+")
	)
	(arc
		(start 8.716772 -376.347482)
		(mid 8.479873 -376.249355)
		(end 8.381746 -376.012456)
		(width 0.09525)
		(layer "F.Cu")
		(net "SAS2X28_A_HDD7_RX_+")
	)
	(arc
		(start 15.548102 -368.698526)
		(mid 15.955682 -368.088445)
		(end 16.098774 -367.368836)
		(width 0.09525)
		(layer "F.Cu")
		(net "SAS2X28_A_HDD7_RX_+")
	)
	(arc
		(start 8.381746 -376.012456)
		(mid 8.408814 -375.876374)
		(end 8.485886 -375.760996)
		(width 0.09525)
		(layer "F.Cu")
		(net "SAS2X28_A_HDD7_RX_+")
	)
	(arc
		(start 22.552914 -353.4537)
		(mid 22.468915 -353.031787)
		(end 22.229826 -352.674174)
		(width 0.09525)
		(layer "F.Cu")
		(net "SAS2X28_A_HDD7_RX_+")
	)
	(arc
		(start 18.287746 -359.6767)
		(mid 18.891616 -359.556676)
		(end 19.403568 -359.214674)
		(width 0.09525)
		(layer "F.Cu")
		(net "SAS2X28_A_HDD7_RX_+")
	)
	(arc
		(start 19.496024 -352.0694)
		(mid 19.130935 -351.996779)
		(end 18.8214 -351.79)
		(width 0.09525)
		(layer "F.Cu")
		(net "SAS2X28_A_HDD7_RX_+")
	)
	(arc
		(start 18.008346 -278.393398)
		(mid 18.116349 -277.85043)
		(end 18.42389 -277.390098)
		(width 0.09525)
		(layer "F.Cu")
		(net "SAS2X28_A_HDD7_RX_+")
	)
	(arc
		(start 16.098774 -360.684826)
		(mid 16.158558 -360.384833)
		(end 16.328644 -360.130598)
		(width 0.09525)
		(layer "F.Cu")
		(net "SAS2X28_A_HDD7_RX_+")
	)
	(arc
		(start 22.1488 -314.075826)
		(mid 21.767522 -312.159011)
		(end 20.681696 -310.53405)
		(width 0.09525)
		(layer "F.Cu")
		(net "SAS2X28_A_HDD7_RX_+")
	)
	(arc
		(start 21.49348 -317.37808)
		(mid 21.728794 -317.100914)
		(end 21.916136 -316.789308)
		(width 0.09525)
		(layer "F.Cu")
		(net "SAS2X28_A_HDD7_RX_+")
	)
	(arc
		(start 18.1102 -318.825118)
		(mid 18.151131 -318.619342)
		(end 18.26768 -318.44488)
		(width 0.09525)
		(layer "F.Cu")
		(net "SAS2X28_A_HDD7_RX_+")
	)
	(arc
		(start 21.883624 -356.73411)
		(mid 22.379057 -355.992314)
		(end 22.552914 -355.1174)
		(width 0.09525)
		(layer "F.Cu")
		(net "SAS2X28_A_HDD7_RX_+")
	)
	(arc
		(start 18.26768 -318.44488)
		(mid 18.329181 -318.4036)
		(end 18.401792 -318.389)
		(width 0.09525)
		(layer "F.Cu")
		(net "SAS2X28_A_HDD7_RX_+")
	)
	(arc
		(start 19.760946 -318.389)
		(mid 20.427327 -318.25673)
		(end 20.992338 -317.879476)
		(width 0.09525)
		(layer "F.Cu")
		(net "SAS2X28_A_HDD7_RX_+")
	)
	(arc
		(start 31.966662 -263.847072)
		(mid 32.36214 -263.68326)
		(end 32.757618 -263.847072)
		(width 0.09525)
		(layer "F.Cu")
		(net "SAS2X28_A_HDD7_RX_+")
	)
	(segment
		(start 7.926324 -373.318278)
		(end 6.730746 -372.1227)
		(width 0.09525)
		(layer "B.Cu")
		(net "SAS2X28_A_HDD7_RX_+")
	)
	(segment
		(start 4.699 -371.5004)
		(end 4.697476 -371.498876)
		(width 0.09525)
		(layer "B.Cu")
		(net "SAS2X28_A_HDD7_RX_+")
	)
	(segment
		(start 8.75411 -376.347482)
		(end 8.721344 -376.31497)
		(width 0.09525)
		(layer "B.Cu")
		(net "SAS2X28_A_HDD7_RX_+")
	)
	(segment
		(start 6.730746 -372.1227)
		(end 6.680962 -372.07317)
		(width 0.09525)
		(layer "B.Cu")
		(net "SAS2X28_A_HDD7_RX_+")
	)
	(segment
		(start 6.095746 -371.8306)
		(end 5.496052 -371.8306)
		(width 0.09525)
		(layer "B.Cu")
		(net "SAS2X28_A_HDD7_RX_+")
	)
	(segment
		(start 8.457946 -375.6787)
		(end 8.457946 -374.601994)
		(width 0.09525)
		(layer "B.Cu")
		(net "SAS2X28_A_HDD7_RX_+")
	)
	(segment
		(start 4.697476 -371.498876)
		(end 2.811526 -371.498876)
		(width 0.09525)
		(layer "B.Cu")
		(net "SAS2X28_A_HDD7_RX_+")
	)
	(arc
		(start 8.457946 -374.601994)
		(mid 8.319777 -373.90728)
		(end 7.926324 -373.318278)
		(width 0.09525)
		(layer "B.Cu")
		(net "SAS2X28_A_HDD7_RX_+")
	)
	(arc
		(start 5.496052 -371.8306)
		(mid 5.369982 -371.805523)
		(end 5.263134 -371.73408)
		(width 0.09525)
		(layer "B.Cu")
		(net "SAS2X28_A_HDD7_RX_+")
	)
	(arc
		(start 5.263134 -371.73408)
		(mid 5.004307 -371.561137)
		(end 4.699 -371.5004)
		(width 0.09525)
		(layer "B.Cu")
		(net "SAS2X28_A_HDD7_RX_+")
	)
	(arc
		(start 8.721344 -376.31497)
		(mid 8.52637 -376.023032)
		(end 8.457946 -375.6787)
		(width 0.09525)
		(layer "B.Cu")
		(net "SAS2X28_A_HDD7_RX_+")
	)
	(arc
		(start 6.680962 -372.07317)
		(mid 6.412478 -371.893681)
		(end 6.095746 -371.8306)
		(width 0.09525)
		(layer "B.Cu")
		(net "SAS2X28_A_HDD7_RX_+")
	)
	(via
		(at 221.106746 -184.0357)
		(size 0.7112)
		(drill 0.3556)
		(layers "F.Cu" "B.Cu")
		(net "12V_PRE_3")
	)
	(via
		(at 220.090746 -184.0357)
		(size 0.7112)
		(drill 0.4064)
		(layers "F.Cu" "B.Cu")
		(net "12V_PRE_3")
	)
	(segment
		(start 221.106746 -184.0357)
		(end 220.090746 -184.0357)
		(width 0.508)
		(layer "B.Cu")
		(net "12V_PRE_3")
	)
	(segment
		(start 223.835722 -370.221764)
		(end 223.30918 -370.221764)
		(width 0.09525)
		(layer "F.Cu")
		(net "SAS2X28_B_HDD1_TX_+")
	)
	(segment
		(start 225.399854 -369.990116)
		(end 224.406206 -369.990116)
		(width 0.09525)
		(layer "F.Cu")
		(net "SAS2X28_B_HDD1_TX_+")
	)
	(segment
		(start 6.37413 -127.83058)
		(end 5.474462 -127.83058)
		(width 0.09525)
		(layer "F.Cu")
		(net "SAS2X28_B_HDD1_TX_+")
	)
	(segment
		(start 224.406206 -369.990116)
		(end 224.402904 -369.986814)
		(width 0.09525)
		(layer "F.Cu")
		(net "SAS2X28_B_HDD1_TX_+")
	)
	(segment
		(start 4.67741 -127.50038)
		(end 4.675886 -127.498856)
		(width 0.09525)
		(layer "F.Cu")
		(net "SAS2X28_B_HDD1_TX_+")
	)
	(segment
		(start 4.675886 -127.498856)
		(end 3.192526 -127.498856)
		(width 0.09525)
		(layer "F.Cu")
		(net "SAS2X28_B_HDD1_TX_+")
	)
	(via
		(at 223.025716 -369.9383)
		(size 0.5588)
		(drill 0.3048)
		(layers "F.Cu" "B.Cu")
		(net "SAS2X28_B_HDD1_TX_+")
	)
	(via
		(at 6.705346 -127.499364)
		(size 0.5588)
		(drill 0.3048)
		(layers "F.Cu" "B.Cu")
		(net "SAS2X28_B_HDD1_TX_+")
	)
	(arc
		(start 6.705346 -127.499364)
		(mid 6.608335 -127.733569)
		(end 6.37413 -127.83058)
		(width 0.09525)
		(layer "F.Cu")
		(net "SAS2X28_B_HDD1_TX_+")
	)
	(arc
		(start 223.30918 -370.221764)
		(mid 223.108741 -370.138739)
		(end 223.025716 -369.9383)
		(width 0.09525)
		(layer "F.Cu")
		(net "SAS2X28_B_HDD1_TX_+")
	)
	(arc
		(start 224.225612 -370.06022)
		(mid 224.046729 -370.179746)
		(end 223.835722 -370.221764)
		(width 0.09525)
		(layer "F.Cu")
		(net "SAS2X28_B_HDD1_TX_+")
	)
	(arc
		(start 5.474462 -127.83058)
		(mid 5.444762 -127.829309)
		(end 5.41528 -127.8255)
		(width 0.09525)
		(layer "F.Cu")
		(net "SAS2X28_B_HDD1_TX_+")
	)
	(arc
		(start 224.402904 -369.986814)
		(mid 224.306966 -370.005897)
		(end 224.225612 -370.06022)
		(width 0.09525)
		(layer "F.Cu")
		(net "SAS2X28_B_HDD1_TX_+")
	)
	(arc
		(start 5.22859 -127.728726)
		(mid 4.975706 -127.559755)
		(end 4.67741 -127.50038)
		(width 0.09525)
		(layer "F.Cu")
		(net "SAS2X28_B_HDD1_TX_+")
	)
	(arc
		(start 5.41528 -127.8255)
		(mid 5.314443 -127.791565)
		(end 5.22859 -127.728726)
		(width 0.09525)
		(layer "F.Cu")
		(net "SAS2X28_B_HDD1_TX_+")
	)
	(segment
		(start 16.921734 -134.073646)
		(end 17.184624 -134.393178)
		(width 0.09525)
		(layer "B.Cu")
		(net "SAS2X28_B_HDD1_TX_+")
	)
	(segment
		(start 17.186148 -134.39521)
		(end 103.083614 -240.379504)
		(width 0.09525)
		(layer "B.Cu")
		(net "SAS2X28_B_HDD1_TX_+")
	)
	(segment
		(start 16.574008 -133.681724)
		(end 16.921734 -134.073646)
		(width 0.09525)
		(layer "B.Cu")
		(net "SAS2X28_B_HDD1_TX_+")
	)
	(segment
		(start 207.669892 -369.42268)
		(end 207.826102 -369.615466)
		(width 0.09525)
		(layer "B.Cu")
		(net "SAS2X28_B_HDD1_TX_+")
	)
	(segment
		(start 11.417554 -128.524762)
		(end 16.560292 -133.667246)
		(width 0.09525)
		(layer "B.Cu")
		(net "SAS2X28_B_HDD1_TX_+")
	)
	(segment
		(start 207.644746 -369.391692)
		(end 207.669892 -369.42268)
		(width 0.09525)
		(layer "B.Cu")
		(net "SAS2X28_B_HDD1_TX_+")
	)
	(segment
		(start 221.277942 -370.1923)
		(end 222.771716 -370.1923)
		(width 0.09525)
		(layer "B.Cu")
		(net "SAS2X28_B_HDD1_TX_+")
	)
	(segment
		(start 207.826102 -369.615466)
		(end 207.825848 -369.61572)
		(width 0.09525)
		(layer "B.Cu")
		(net "SAS2X28_B_HDD1_TX_+")
	)
	(segment
		(start 144.733518 -291.769038)
		(end 207.644746 -369.391692)
		(width 0.09525)
		(layer "B.Cu")
		(net "SAS2X28_B_HDD1_TX_+")
	)
	(segment
		(start 208.013046 -369.8494)
		(end 211.619846 -373.4562)
		(width 0.09525)
		(layer "B.Cu")
		(net "SAS2X28_B_HDD1_TX_+")
	)
	(segment
		(start 7.019544 -127.813562)
		(end 9.59231 -127.813562)
		(width 0.09525)
		(layer "B.Cu")
		(net "SAS2X28_B_HDD1_TX_+")
	)
	(segment
		(start 208.01457 -369.848384)
		(end 208.013046 -369.8494)
		(width 0.09525)
		(layer "B.Cu")
		(net "SAS2X28_B_HDD1_TX_+")
	)
	(segment
		(start 11.417554 -128.524508)
		(end 11.417554 -128.524762)
		(width 0.09525)
		(layer "B.Cu")
		(net "SAS2X28_B_HDD1_TX_+")
	)
	(segment
		(start 16.560292 -133.667246)
		(end 16.574008 -133.681724)
		(width 0.09525)
		(layer "B.Cu")
		(net "SAS2X28_B_HDD1_TX_+")
	)
	(segment
		(start 103.083614 -240.379504)
		(end 144.733518 -291.769038)
		(width 0.09525)
		(layer "B.Cu")
		(net "SAS2X28_B_HDD1_TX_+")
	)
	(segment
		(start 17.184624 -134.393178)
		(end 17.186148 -134.39521)
		(width 0.09525)
		(layer "B.Cu")
		(net "SAS2X28_B_HDD1_TX_+")
	)
	(segment
		(start 217.766646 -373.3038)
		(end 220.595444 -370.475002)
		(width 0.09525)
		(layer "B.Cu")
		(net "SAS2X28_B_HDD1_TX_+")
	)
	(segment
		(start 207.825848 -369.61572)
		(end 208.01457 -369.848384)
		(width 0.09525)
		(layer "B.Cu")
		(net "SAS2X28_B_HDD1_TX_+")
	)
	(segment
		(start 212.202522 -373.6975)
		(end 216.816178 -373.6975)
		(width 0.09525)
		(layer "B.Cu")
		(net "SAS2X28_B_HDD1_TX_+")
	)
	(arc
		(start 211.619846 -373.4562)
		(mid 211.88718 -373.634827)
		(end 212.202522 -373.6975)
		(width 0.09525)
		(layer "B.Cu")
		(net "SAS2X28_B_HDD1_TX_+")
	)
	(arc
		(start 222.771716 -370.1923)
		(mid 222.951321 -370.117905)
		(end 223.025716 -369.9383)
		(width 0.09525)
		(layer "B.Cu")
		(net "SAS2X28_B_HDD1_TX_+")
	)
	(arc
		(start 9.59231 -127.813562)
		(mid 10.570659 -128.000289)
		(end 11.417554 -128.524508)
		(width 0.09525)
		(layer "B.Cu")
		(net "SAS2X28_B_HDD1_TX_+")
	)
	(arc
		(start 220.595444 -370.475002)
		(mid 220.908577 -370.265773)
		(end 221.277942 -370.1923)
		(width 0.09525)
		(layer "B.Cu")
		(net "SAS2X28_B_HDD1_TX_+")
	)
	(arc
		(start 216.816178 -373.6975)
		(mid 217.330569 -373.595181)
		(end 217.766646 -373.3038)
		(width 0.09525)
		(layer "B.Cu")
		(net "SAS2X28_B_HDD1_TX_+")
	)
	(arc
		(start 6.705346 -127.499364)
		(mid 6.797372 -127.721536)
		(end 7.019544 -127.813562)
		(width 0.09525)
		(layer "B.Cu")
		(net "SAS2X28_B_HDD1_TX_+")
	)
	(segment
		(start 8.0264 -374.162066)
		(end 5.740146 -374.162066)
		(width 0.09525)
		(layer "F.Cu")
		(net "SAS2X28_A_HDD7_TX_-")
	)
	(segment
		(start 16.216376 -358.913176)
		(end 15.536672 -359.59288)
		(width 0.09525)
		(layer "F.Cu")
		(net "SAS2X28_A_HDD7_TX_-")
	)
	(segment
		(start 4.921758 -374.49887)
		(end 3.192526 -374.49887)
		(width 0.09525)
		(layer "F.Cu")
		(net "SAS2X28_A_HDD7_TX_-")
	)
	(segment
		(start 17.6657 -354.7491)
		(end 19.100546 -356.183946)
		(width 0.09525)
		(layer "F.Cu")
		(net "SAS2X28_A_HDD7_TX_-")
	)
	(segment
		(start 17.068546 -277.816564)
		(end 17.068546 -308.694836)
		(width 0.09525)
		(layer "F.Cu")
		(net "SAS2X28_A_HDD7_TX_-")
	)
	(segment
		(start 37.0332 -260.336792)
		(end 36.935664 -260.336792)
		(width 0.09525)
		(layer "F.Cu")
		(net "SAS2X28_A_HDD7_TX_-")
	)
	(segment
		(start 19.350736 -314.671964)
		(end 17.525746 -316.496954)
		(width 0.09525)
		(layer "F.Cu")
		(net "SAS2X28_A_HDD7_TX_-")
	)
	(segment
		(start 19.156172 -311.31002)
		(end 19.156426 -311.31002)
		(width 0.09525)
		(layer "F.Cu")
		(net "SAS2X28_A_HDD7_TX_-")
	)
	(segment
		(start 19.183096 -358.105202)
		(end 19.175222 -358.113076)
		(width 0.09525)
		(layer "F.Cu")
		(net "SAS2X28_A_HDD7_TX_-")
	)
	(segment
		(start 4.923282 -374.500394)
		(end 4.921758 -374.49887)
		(width 0.09525)
		(layer "F.Cu")
		(net "SAS2X28_A_HDD7_TX_-")
	)
	(segment
		(start 19.684746 -313.7027)
		(end 19.68246 -313.704478)
		(width 0.09525)
		(layer "F.Cu")
		(net "SAS2X28_A_HDD7_TX_-")
	)
	(segment
		(start 19.68246 -313.704478)
		(end 19.668236 -313.905392)
		(width 0.09525)
		(layer "F.Cu")
		(net "SAS2X28_A_HDD7_TX_-")
	)
	(segment
		(start 33.914334 -260.443218)
		(end 17.441672 -276.91588)
		(width 0.09525)
		(layer "F.Cu")
		(net "SAS2X28_A_HDD7_TX_-")
	)
	(segment
		(start 36.72586 -259.866892)
		(end 35.305746 -259.866892)
		(width 0.09525)
		(layer "F.Cu")
		(net "SAS2X28_A_HDD7_TX_-")
	)
	(segment
		(start 19.1008 -356.183946)
		(end 19.198336 -356.281482)
		(width 0.09525)
		(layer "F.Cu")
		(net "SAS2X28_A_HDD7_TX_-")
	)
	(segment
		(start 19.100546 -356.183946)
		(end 19.1008 -356.183946)
		(width 0.09525)
		(layer "F.Cu")
		(net "SAS2X28_A_HDD7_TX_-")
	)
	(segment
		(start 38.250114 -260.340094)
		(end 37.036502 -260.340094)
		(width 0.09525)
		(layer "F.Cu")
		(net "SAS2X28_A_HDD7_TX_-")
	)
	(segment
		(start 36.82746 -260.221222)
		(end 36.82746 -259.968492)
		(width 0.09525)
		(layer "F.Cu")
		(net "SAS2X28_A_HDD7_TX_-")
	)
	(segment
		(start 15.158974 -360.50474)
		(end 15.158974 -366.915954)
		(width 0.09525)
		(layer "F.Cu")
		(net "SAS2X28_A_HDD7_TX_-")
	)
	(segment
		(start 17.093946 -317.538608)
		(end 17.093946 -353.368864)
		(width 0.09525)
		(layer "F.Cu")
		(net "SAS2X28_A_HDD7_TX_-")
	)
	(segment
		(start 18.155666 -358.709976)
		(end 16.70685 -358.709976)
		(width 0.09525)
		(layer "F.Cu")
		(net "SAS2X28_A_HDD7_TX_-")
	)
	(segment
		(start 14.563598 -368.35334)
		(end 9.270492 -373.6467)
		(width 0.09525)
		(layer "F.Cu")
		(net "SAS2X28_A_HDD7_TX_-")
	)
	(segment
		(start 17.441672 -309.59552)
		(end 19.156172 -311.31002)
		(width 0.09525)
		(layer "F.Cu")
		(net "SAS2X28_A_HDD7_TX_-")
	)
	(segment
		(start 19.175222 -358.113076)
		(end 19.174968 -358.112822)
		(width 0.09525)
		(layer "F.Cu")
		(net "SAS2X28_A_HDD7_TX_-")
	)
	(segment
		(start 37.036502 -260.340094)
		(end 37.0332 -260.336792)
		(width 0.09525)
		(layer "F.Cu")
		(net "SAS2X28_A_HDD7_TX_-")
	)
	(segment
		(start 19.174968 -358.112822)
		(end 18.876772 -358.411272)
		(width 0.09525)
		(layer "F.Cu")
		(net "SAS2X28_A_HDD7_TX_-")
	)
	(segment
		(start 17.525746 -316.496954)
		(end 17.525492 -316.496954)
		(width 0.09525)
		(layer "F.Cu")
		(net "SAS2X28_A_HDD7_TX_-")
	)
	(segment
		(start 19.441922 -356.869746)
		(end 19.441922 -357.479346)
		(width 0.09525)
		(layer "F.Cu")
		(net "SAS2X28_A_HDD7_TX_-")
	)
	(segment
		(start 19.684746 -312.559446)
		(end 19.684746 -313.7027)
		(width 0.09525)
		(layer "F.Cu")
		(net "SAS2X28_A_HDD7_TX_-")
	)
	(segment
		(start 17.0942 -317.538862)
		(end 17.093946 -317.538608)
		(width 0.09525)
		(layer "F.Cu")
		(net "SAS2X28_A_HDD7_TX_-")
	)
	(segment
		(start 19.156426 -311.31002)
		(end 19.175222 -311.328816)
		(width 0.09525)
		(layer "F.Cu")
		(net "SAS2X28_A_HDD7_TX_-")
	)
	(arc
		(start 35.305746 -259.866892)
		(mid 34.552725 -260.016677)
		(end 33.914334 -260.443218)
		(width 0.09525)
		(layer "F.Cu")
		(net "SAS2X28_A_HDD7_TX_-")
	)
	(arc
		(start 36.862766 -260.306566)
		(mid 36.836656 -260.267396)
		(end 36.82746 -260.221222)
		(width 0.09525)
		(layer "F.Cu")
		(net "SAS2X28_A_HDD7_TX_-")
	)
	(arc
		(start 19.668236 -313.905392)
		(mid 19.585716 -314.320248)
		(end 19.350736 -314.671964)
		(width 0.09525)
		(layer "F.Cu")
		(net "SAS2X28_A_HDD7_TX_-")
	)
	(arc
		(start 16.70685 -358.709976)
		(mid 16.441392 -358.762779)
		(end 16.216376 -358.913176)
		(width 0.09525)
		(layer "F.Cu")
		(net "SAS2X28_A_HDD7_TX_-")
	)
	(arc
		(start 5.740146 -374.162066)
		(mid 5.739892 -374.162066)
		(end 5.739638 -374.162066)
		(width 0.09525)
		(layer "F.Cu")
		(net "SAS2X28_A_HDD7_TX_-")
	)
	(arc
		(start 17.093946 -353.368864)
		(mid 17.242532 -354.115858)
		(end 17.6657 -354.7491)
		(width 0.09525)
		(layer "F.Cu")
		(net "SAS2X28_A_HDD7_TX_-")
	)
	(arc
		(start 36.935664 -260.336792)
		(mid 36.8962 -260.328942)
		(end 36.862766 -260.306566)
		(width 0.09525)
		(layer "F.Cu")
		(net "SAS2X28_A_HDD7_TX_-")
	)
	(arc
		(start 5.403342 -374.301512)
		(mid 5.183089 -374.448681)
		(end 4.923282 -374.500394)
		(width 0.09525)
		(layer "F.Cu")
		(net "SAS2X28_A_HDD7_TX_-")
	)
	(arc
		(start 36.82746 -259.968492)
		(mid 36.808399 -259.909248)
		(end 36.758372 -259.872226)
		(width 0.09525)
		(layer "F.Cu")
		(net "SAS2X28_A_HDD7_TX_-")
	)
	(arc
		(start 17.068546 -308.694836)
		(mid 17.165509 -309.182302)
		(end 17.441672 -309.59552)
		(width 0.09525)
		(layer "F.Cu")
		(net "SAS2X28_A_HDD7_TX_-")
	)
	(arc
		(start 18.876772 -358.411272)
		(mid 18.545926 -358.632336)
		(end 18.155666 -358.709976)
		(width 0.09525)
		(layer "F.Cu")
		(net "SAS2X28_A_HDD7_TX_-")
	)
	(arc
		(start 15.536672 -359.59288)
		(mid 15.257129 -360.011245)
		(end 15.158974 -360.50474)
		(width 0.09525)
		(layer "F.Cu")
		(net "SAS2X28_A_HDD7_TX_-")
	)
	(arc
		(start 9.270492 -373.6467)
		(mid 8.699698 -374.028093)
		(end 8.0264 -374.162066)
		(width 0.09525)
		(layer "F.Cu")
		(net "SAS2X28_A_HDD7_TX_-")
	)
	(arc
		(start 19.441922 -357.479346)
		(mid 19.374746 -357.818007)
		(end 19.183096 -358.105202)
		(width 0.09525)
		(layer "F.Cu")
		(net "SAS2X28_A_HDD7_TX_-")
	)
	(arc
		(start 17.441672 -276.91588)
		(mid 17.165556 -277.329117)
		(end 17.068546 -277.816564)
		(width 0.09525)
		(layer "F.Cu")
		(net "SAS2X28_A_HDD7_TX_-")
	)
	(arc
		(start 19.175222 -311.328816)
		(mid 19.552327 -311.893477)
		(end 19.684746 -312.559446)
		(width 0.09525)
		(layer "F.Cu")
		(net "SAS2X28_A_HDD7_TX_-")
	)
	(arc
		(start 5.739638 -374.162066)
		(mid 5.557608 -374.19831)
		(end 5.403342 -374.301512)
		(width 0.09525)
		(layer "F.Cu")
		(net "SAS2X28_A_HDD7_TX_-")
	)
	(arc
		(start 36.758372 -259.872226)
		(mid 36.742333 -259.868238)
		(end 36.72586 -259.866892)
		(width 0.09525)
		(layer "F.Cu")
		(net "SAS2X28_A_HDD7_TX_-")
	)
	(arc
		(start 19.198336 -356.281482)
		(mid 19.378622 -356.551394)
		(end 19.441922 -356.869746)
		(width 0.09525)
		(layer "F.Cu")
		(net "SAS2X28_A_HDD7_TX_-")
	)
	(arc
		(start 17.525492 -316.496954)
		(mid 17.206272 -316.975029)
		(end 17.0942 -317.538862)
		(width 0.09525)
		(layer "F.Cu")
		(net "SAS2X28_A_HDD7_TX_-")
	)
	(arc
		(start 15.158974 -366.915954)
		(mid 15.004239 -367.693858)
		(end 14.563598 -368.35334)
		(width 0.09525)
		(layer "F.Cu")
		(net "SAS2X28_A_HDD7_TX_-")
	)
	(segment
		(start 217.068146 -372.597934)
		(end 216.833704 -372.597934)
		(width 0.09525)
		(layer "F.Cu")
		(net "SAS2X28_B_HDD1_RX_-")
	)
	(segment
		(start 217.697558 -372.312184)
		(end 217.654632 -372.354856)
		(width 0.09525)
		(layer "F.Cu")
		(net "SAS2X28_B_HDD1_RX_-")
	)
	(via
		(at 216.481152 -372.451884)
		(size 0.5588)
		(drill 0.3048)
		(layers "F.Cu" "B.Cu")
		(net "SAS2X28_B_HDD1_RX_-")
	)
	(arc
		(start 216.833704 -372.597934)
		(mid 216.642897 -372.55998)
		(end 216.481152 -372.451884)
		(width 0.09525)
		(layer "F.Cu")
		(net "SAS2X28_B_HDD1_RX_-")
	)
	(arc
		(start 217.654632 -372.354856)
		(mid 217.385565 -372.534734)
		(end 217.068146 -372.597934)
		(width 0.09525)
		(layer "F.Cu")
		(net "SAS2X28_B_HDD1_RX_-")
	)
	(segment
		(start 18.821654 -134.504938)
		(end 18.816828 -134.500366)
		(width 0.09525)
		(layer "B.Cu")
		(net "SAS2X28_B_HDD1_RX_-")
	)
	(segment
		(start 4.966716 -126.498858)
		(end 2.811526 -126.498858)
		(width 0.09525)
		(layer "B.Cu")
		(net "SAS2X28_B_HDD1_RX_-")
	)
	(segment
		(start 18.815304 -134.498334)
		(end 11.132058 -126.815088)
		(width 0.09525)
		(layer "B.Cu")
		(net "SAS2X28_B_HDD1_RX_-")
	)
	(segment
		(start 9.395714 -126.160784)
		(end 5.788152 -126.160784)
		(width 0.09525)
		(layer "B.Cu")
		(net "SAS2X28_B_HDD1_RX_-")
	)
	(segment
		(start 212.017864 -370.086382)
		(end 18.821654 -134.504938)
		(width 0.09525)
		(layer "B.Cu")
		(net "SAS2X28_B_HDD1_RX_-")
	)
	(segment
		(start 4.96824 -126.500382)
		(end 4.966716 -126.498858)
		(width 0.09525)
		(layer "B.Cu")
		(net "SAS2X28_B_HDD1_RX_-")
	)
	(segment
		(start 216.481152 -372.451884)
		(end 216.286334 -372.646702)
		(width 0.09525)
		(layer "B.Cu")
		(net "SAS2X28_B_HDD1_RX_-")
	)
	(segment
		(start 214.683086 -372.751604)
		(end 212.017864 -370.086382)
		(width 0.09525)
		(layer "B.Cu")
		(net "SAS2X28_B_HDD1_RX_-")
	)
	(segment
		(start 18.816828 -134.500366)
		(end 18.815304 -134.498334)
		(width 0.09525)
		(layer "B.Cu")
		(net "SAS2X28_B_HDD1_RX_-")
	)
	(arc
		(start 5.788152 -126.160784)
		(mid 5.502088 -126.217686)
		(end 5.259578 -126.379732)
		(width 0.09525)
		(layer "B.Cu")
		(net "SAS2X28_B_HDD1_RX_-")
	)
	(arc
		(start 214.956136 -372.928896)
		(mid 214.810327 -372.854546)
		(end 214.683086 -372.751604)
		(width 0.09525)
		(layer "B.Cu")
		(net "SAS2X28_B_HDD1_RX_-")
	)
	(arc
		(start 11.132058 -126.815088)
		(mid 10.322075 -126.333545)
		(end 9.395714 -126.160784)
		(width 0.09525)
		(layer "B.Cu")
		(net "SAS2X28_B_HDD1_RX_-")
	)
	(arc
		(start 216.286334 -372.646702)
		(mid 215.663063 -372.984943)
		(end 214.956136 -372.928896)
		(width 0.09525)
		(layer "B.Cu")
		(net "SAS2X28_B_HDD1_RX_-")
	)
	(arc
		(start 5.259578 -126.379732)
		(mid 5.125911 -126.469045)
		(end 4.96824 -126.500382)
		(width 0.09525)
		(layer "B.Cu")
		(net "SAS2X28_B_HDD1_RX_-")
	)
	(via
		(at 220.6625 -286.7025)
		(size 0.7112)
		(drill 0.3556)
		(layers "F.Cu" "B.Cu")
		(net "12V_PRE_2")
	)
	(via
		(at 219.582746 -286.7025)
		(size 0.5588)
		(drill 0.3048)
		(layers "F.Cu" "B.Cu")
		(net "12V_PRE_2")
	)
	(segment
		(start 219.582746 -286.7025)
		(end 220.6625 -286.7025)
		(width 0.508)
		(layer "B.Cu")
		(net "12V_PRE_2")
	)
	(segment
		(start 3.193542 -212.50148)
		(end 3.19024 -212.504782)
		(width 0.111252)
		(layer "F.Cu")
		(net "SAS_EXP_B_PWR10")
	)
	(segment
		(start 6.469126 -212.50148)
		(end 3.193542 -212.50148)
		(width 0.111252)
		(layer "F.Cu")
		(net "SAS_EXP_B_PWR10")
	)
	(segment
		(start 10.2616 -213.561168)
		(end 7.528814 -213.561168)
		(width 0.111252)
		(layer "F.Cu")
		(net "SAS_EXP_B_PWR10")
	)
	(segment
		(start 33.766506 -434.59146)
		(end 33.766506 -435.5592)
		(width 0.111252)
		(layer "F.Cu")
		(net "SAS_EXP_B_PWR10")
	)
	(segment
		(start 33.527746 -434.3527)
		(end 33.766506 -434.59146)
		(width 0.111252)
		(layer "F.Cu")
		(net "SAS_EXP_B_PWR10")
	)
	(segment
		(start 33.527746 -433.5272)
		(end 33.527746 -434.3527)
		(width 0.111252)
		(layer "F.Cu")
		(net "SAS_EXP_B_PWR10")
	)
	(segment
		(start 7.528814 -213.561168)
		(end 6.469126 -212.50148)
		(width 0.111252)
		(layer "F.Cu")
		(net "SAS_EXP_B_PWR10")
	)
	(via
		(at 10.2616 -213.561168)
		(size 0.5588)
		(drill 0.3048)
		(layers "F.Cu" "B.Cu")
		(net "SAS_EXP_B_PWR10")
	)
	(via
		(at 33.527746 -434.3527)
		(size 0.5588)
		(drill 0.3048)
		(layers "F.Cu" "B.Cu")
		(net "SAS_EXP_B_PWR10")
	)
	(via
		(at 33.426146 -435.3941)
		(size 0.7112)
		(drill 0.3556)
		(layers "F.Cu" "B.Cu")
		(net "SAS_EXP_B_PWR10")
	)
	(segment
		(start 33.527746 -434.3527)
		(end 33.426146 -434.4543)
		(width 0.111252)
		(layer "B.Cu")
		(net "SAS_EXP_B_PWR10")
	)
	(segment
		(start 33.426146 -434.4543)
		(end 33.426146 -435.3941)
		(width 0.111252)
		(layer "B.Cu")
		(net "SAS_EXP_B_PWR10")
	)
	(segment
		(start 34.26841 -431.574956)
		(end 34.284412 -431.590958)
		(width 0.14605)
		(layer "In5.Cu")
		(net "SAS_EXP_B_PWR10")
	)
	(segment
		(start 17.160494 -392.802364)
		(end 17.160494 -396.839694)
		(width 0.14605)
		(layer "In5.Cu")
		(net "SAS_EXP_B_PWR10")
	)
	(segment
		(start 10.28065 -213.620604)
		(end 10.28065 -215.17864)
		(width 0.14605)
		(layer "In5.Cu")
		(net "SAS_EXP_B_PWR10")
	)
	(segment
		(start 12.642596 -217.540586)
		(end 12.642596 -388.284466)
		(width 0.14605)
		(layer "In5.Cu")
		(net "SAS_EXP_B_PWR10")
	)
	(segment
		(start 34.284412 -431.590958)
		(end 34.284412 -431.988214)
		(width 0.14605)
		(layer "In5.Cu")
		(net "SAS_EXP_B_PWR10")
	)
	(segment
		(start 34.284412 -431.988214)
		(end 34.26841 -432.004216)
		(width 0.14605)
		(layer "In5.Cu")
		(net "SAS_EXP_B_PWR10")
	)
	(segment
		(start 34.26841 -411.61081)
		(end 34.26841 -431.574956)
		(width 0.14605)
		(layer "In5.Cu")
		(net "SAS_EXP_B_PWR10")
	)
	(segment
		(start 10.2616 -213.601554)
		(end 10.28065 -213.620604)
		(width 0.14605)
		(layer "In5.Cu")
		(net "SAS_EXP_B_PWR10")
	)
	(segment
		(start 10.28065 -215.17864)
		(end 12.642596 -217.540586)
		(width 0.14605)
		(layer "In5.Cu")
		(net "SAS_EXP_B_PWR10")
	)
	(segment
		(start 12.642596 -388.284466)
		(end 17.160494 -392.802364)
		(width 0.14605)
		(layer "In5.Cu")
		(net "SAS_EXP_B_PWR10")
	)
	(segment
		(start 21.2344 -400.9136)
		(end 23.5712 -400.9136)
		(width 0.14605)
		(layer "In5.Cu")
		(net "SAS_EXP_B_PWR10")
	)
	(segment
		(start 10.2616 -213.561168)
		(end 10.2616 -213.601554)
		(width 0.14605)
		(layer "In5.Cu")
		(net "SAS_EXP_B_PWR10")
	)
	(segment
		(start 34.26841 -433.612036)
		(end 33.527746 -434.3527)
		(width 0.14605)
		(layer "In5.Cu")
		(net "SAS_EXP_B_PWR10")
	)
	(segment
		(start 34.26841 -432.004216)
		(end 34.26841 -433.612036)
		(width 0.14605)
		(layer "In5.Cu")
		(net "SAS_EXP_B_PWR10")
	)
	(segment
		(start 23.5712 -400.9136)
		(end 34.26841 -411.61081)
		(width 0.14605)
		(layer "In5.Cu")
		(net "SAS_EXP_B_PWR10")
	)
	(segment
		(start 17.160494 -396.839694)
		(end 21.2344 -400.9136)
		(width 0.14605)
		(layer "In5.Cu")
		(net "SAS_EXP_B_PWR10")
	)
	(segment
		(start 16.763746 -317.538862)
		(end 16.763746 -353.369118)
		(width 0.09525)
		(layer "F.Cu")
		(net "SAS2X28_A_HDD7_TX_+")
	)
	(segment
		(start 19.111722 -356.87)
		(end 19.111722 -357.4796)
		(width 0.09525)
		(layer "F.Cu")
		(net "SAS2X28_A_HDD7_TX_+")
	)
	(segment
		(start 19.354546 -312.5597)
		(end 19.354546 -313.5757)
		(width 0.09525)
		(layer "F.Cu")
		(net "SAS2X28_A_HDD7_TX_+")
	)
	(segment
		(start 8.026146 -373.831866)
		(end 5.68452 -373.831866)
		(width 0.09525)
		(layer "F.Cu")
		(net "SAS2X28_A_HDD7_TX_+")
	)
	(segment
		(start 17.207992 -309.828946)
		(end 18.941542 -311.562496)
		(width 0.09525)
		(layer "F.Cu")
		(net "SAS2X28_A_HDD7_TX_+")
	)
	(segment
		(start 18.949416 -357.871522)
		(end 18.643346 -358.177592)
		(width 0.09525)
		(layer "F.Cu")
		(net "SAS2X28_A_HDD7_TX_+")
	)
	(segment
		(start 4.888738 -373.500396)
		(end 4.887214 -373.498872)
		(width 0.09525)
		(layer "F.Cu")
		(net "SAS2X28_A_HDD7_TX_+")
	)
	(segment
		(start 12.853162 -369.596416)
		(end 9.036812 -373.41302)
		(width 0.09525)
		(layer "F.Cu")
		(net "SAS2X28_A_HDD7_TX_+")
	)
	(segment
		(start 19.350736 -313.679586)
		(end 19.353022 -313.681872)
		(width 0.09525)
		(layer "F.Cu")
		(net "SAS2X28_A_HDD7_TX_+")
	)
	(segment
		(start 36.82746 -259.24891)
		(end 36.82746 -259.435092)
		(width 0.09525)
		(layer "F.Cu")
		(net "SAS2X28_A_HDD7_TX_+")
	)
	(segment
		(start 17.43202 -354.982526)
		(end 18.964656 -356.515162)
		(width 0.09525)
		(layer "F.Cu")
		(net "SAS2X28_A_HDD7_TX_+")
	)
	(segment
		(start 5.486908 -373.784114)
		(end 5.430774 -373.755158)
		(width 0.09525)
		(layer "F.Cu")
		(net "SAS2X28_A_HDD7_TX_+")
	)
	(segment
		(start 15.98295 -358.67975)
		(end 15.982696 -358.679496)
		(width 0.09525)
		(layer "F.Cu")
		(net "SAS2X28_A_HDD7_TX_+")
	)
	(segment
		(start 16.738346 -277.81631)
		(end 16.738346 -308.69509)
		(width 0.09525)
		(layer "F.Cu")
		(net "SAS2X28_A_HDD7_TX_+")
	)
	(segment
		(start 19.353022 -313.681872)
		(end 19.34337 -313.817508)
		(width 0.09525)
		(layer "F.Cu")
		(net "SAS2X28_A_HDD7_TX_+")
	)
	(segment
		(start 14.828774 -360.50474)
		(end 14.828774 -366.9157)
		(width 0.09525)
		(layer "F.Cu")
		(net "SAS2X28_A_HDD7_TX_+")
	)
	(segment
		(start 14.329918 -368.120168)
		(end 14.329664 -368.119914)
		(width 0.09525)
		(layer "F.Cu")
		(net "SAS2X28_A_HDD7_TX_+")
	)
	(segment
		(start 19.34337 -313.817508)
		(end 19.338036 -313.893708)
		(width 0.09525)
		(layer "F.Cu")
		(net "SAS2X28_A_HDD7_TX_+")
	)
	(segment
		(start 33.680654 -260.209538)
		(end 17.207992 -276.6822)
		(width 0.09525)
		(layer "F.Cu")
		(net "SAS2X28_A_HDD7_TX_+")
	)
	(segment
		(start 19.338036 -313.893708)
		(end 19.338036 -313.905392)
		(width 0.09525)
		(layer "F.Cu")
		(net "SAS2X28_A_HDD7_TX_+")
	)
	(segment
		(start 19.117056 -314.438284)
		(end 17.292066 -316.263274)
		(width 0.09525)
		(layer "F.Cu")
		(net "SAS2X28_A_HDD7_TX_+")
	)
	(segment
		(start 14.329664 -368.119914)
		(end 12.853162 -369.596416)
		(width 0.09525)
		(layer "F.Cu")
		(net "SAS2X28_A_HDD7_TX_+")
	)
	(segment
		(start 38.250114 -259.070094)
		(end 37.00653 -259.070094)
		(width 0.09525)
		(layer "F.Cu")
		(net "SAS2X28_A_HDD7_TX_+")
	)
	(segment
		(start 15.72895 -358.933242)
		(end 15.303246 -359.3592)
		(width 0.09525)
		(layer "F.Cu")
		(net "SAS2X28_A_HDD7_TX_+")
	)
	(segment
		(start 4.887214 -373.498872)
		(end 3.192526 -373.498872)
		(width 0.09525)
		(layer "F.Cu")
		(net "SAS2X28_A_HDD7_TX_+")
	)
	(segment
		(start 15.982696 -358.679496)
		(end 15.72895 -358.933242)
		(width 0.09525)
		(layer "F.Cu")
		(net "SAS2X28_A_HDD7_TX_+")
	)
	(segment
		(start 36.72586 -259.536692)
		(end 35.306 -259.536692)
		(width 0.09525)
		(layer "F.Cu")
		(net "SAS2X28_A_HDD7_TX_+")
	)
	(segment
		(start 9.036812 -373.41302)
		(end 9.037066 -373.41302)
		(width 0.09525)
		(layer "F.Cu")
		(net "SAS2X28_A_HDD7_TX_+")
	)
	(segment
		(start 18.155412 -358.379776)
		(end 16.706596 -358.379776)
		(width 0.09525)
		(layer "F.Cu")
		(net "SAS2X28_A_HDD7_TX_+")
	)
	(arc
		(start 37.00653 -259.070094)
		(mid 36.93792 -259.083759)
		(end 36.879784 -259.122672)
		(width 0.09525)
		(layer "F.Cu")
		(net "SAS2X28_A_HDD7_TX_+")
	)
	(arc
		(start 19.111722 -357.4796)
		(mid 19.069534 -357.691694)
		(end 18.949416 -357.871522)
		(width 0.09525)
		(layer "F.Cu")
		(net "SAS2X28_A_HDD7_TX_+")
	)
	(arc
		(start 16.706596 -358.379776)
		(mid 16.314967 -358.457845)
		(end 15.98295 -358.67975)
		(width 0.09525)
		(layer "F.Cu")
		(net "SAS2X28_A_HDD7_TX_+")
	)
	(arc
		(start 14.828774 -366.9157)
		(mid 14.699116 -367.567534)
		(end 14.329918 -368.120168)
		(width 0.09525)
		(layer "F.Cu")
		(net "SAS2X28_A_HDD7_TX_+")
	)
	(arc
		(start 16.738346 -308.69509)
		(mid 16.860458 -309.308698)
		(end 17.207992 -309.828946)
		(width 0.09525)
		(layer "F.Cu")
		(net "SAS2X28_A_HDD7_TX_+")
	)
	(arc
		(start 19.338036 -313.905392)
		(mid 19.280568 -314.193833)
		(end 19.117056 -314.438284)
		(width 0.09525)
		(layer "F.Cu")
		(net "SAS2X28_A_HDD7_TX_+")
	)
	(arc
		(start 5.68452 -373.831866)
		(mid 5.582869 -373.81976)
		(end 5.486908 -373.784114)
		(width 0.09525)
		(layer "F.Cu")
		(net "SAS2X28_A_HDD7_TX_+")
	)
	(arc
		(start 36.82746 -259.435092)
		(mid 36.807522 -259.495203)
		(end 36.755832 -259.531866)
		(width 0.09525)
		(layer "F.Cu")
		(net "SAS2X28_A_HDD7_TX_+")
	)
	(arc
		(start 36.755832 -259.531866)
		(mid 36.741029 -259.535418)
		(end 36.72586 -259.536692)
		(width 0.09525)
		(layer "F.Cu")
		(net "SAS2X28_A_HDD7_TX_+")
	)
	(arc
		(start 9.037066 -373.41302)
		(mid 8.57328 -373.723038)
		(end 8.026146 -373.831866)
		(width 0.09525)
		(layer "F.Cu")
		(net "SAS2X28_A_HDD7_TX_+")
	)
	(arc
		(start 35.306 -259.536692)
		(mid 34.426413 -259.711466)
		(end 33.680654 -260.209538)
		(width 0.09525)
		(layer "F.Cu")
		(net "SAS2X28_A_HDD7_TX_+")
	)
	(arc
		(start 17.292066 -316.263274)
		(mid 16.901018 -316.848519)
		(end 16.763746 -317.538862)
		(width 0.09525)
		(layer "F.Cu")
		(net "SAS2X28_A_HDD7_TX_+")
	)
	(arc
		(start 5.430774 -373.755158)
		(mid 5.379648 -373.723748)
		(end 5.334 -373.6848)
		(width 0.09525)
		(layer "F.Cu")
		(net "SAS2X28_A_HDD7_TX_+")
	)
	(arc
		(start 36.879784 -259.122672)
		(mid 36.841084 -259.18059)
		(end 36.82746 -259.24891)
		(width 0.09525)
		(layer "F.Cu")
		(net "SAS2X28_A_HDD7_TX_+")
	)
	(arc
		(start 19.354546 -313.5757)
		(mid 19.353537 -313.627676)
		(end 19.350736 -313.679586)
		(width 0.09525)
		(layer "F.Cu")
		(net "SAS2X28_A_HDD7_TX_+")
	)
	(arc
		(start 18.941542 -311.562496)
		(mid 19.247194 -312.020031)
		(end 19.354546 -312.5597)
		(width 0.09525)
		(layer "F.Cu")
		(net "SAS2X28_A_HDD7_TX_+")
	)
	(arc
		(start 15.303246 -359.3592)
		(mid 14.952095 -359.884779)
		(end 14.828774 -360.50474)
		(width 0.09525)
		(layer "F.Cu")
		(net "SAS2X28_A_HDD7_TX_+")
	)
	(arc
		(start 5.334 -373.6848)
		(mid 5.129712 -373.548299)
		(end 4.888738 -373.500396)
		(width 0.09525)
		(layer "F.Cu")
		(net "SAS2X28_A_HDD7_TX_+")
	)
	(arc
		(start 18.643346 -358.177592)
		(mid 18.419508 -358.327282)
		(end 18.155412 -358.379776)
		(width 0.09525)
		(layer "F.Cu")
		(net "SAS2X28_A_HDD7_TX_+")
	)
	(arc
		(start 16.763746 -353.369118)
		(mid 16.937482 -354.242255)
		(end 17.43202 -354.982526)
		(width 0.09525)
		(layer "F.Cu")
		(net "SAS2X28_A_HDD7_TX_+")
	)
	(arc
		(start 18.964656 -356.515162)
		(mid 19.07349 -356.677949)
		(end 19.111722 -356.87)
		(width 0.09525)
		(layer "F.Cu")
		(net "SAS2X28_A_HDD7_TX_+")
	)
	(arc
		(start 17.207992 -276.6822)
		(mid 16.860423 -277.202563)
		(end 16.738346 -277.81631)
		(width 0.09525)
		(layer "F.Cu")
		(net "SAS2X28_A_HDD7_TX_+")
	)
	(via
		(at 219.658946 -389.1407)
		(size 0.7112)
		(drill 0.3556)
		(layers "F.Cu" "B.Cu")
		(net "12V_PRE_1")
	)
	(via
		(at 220.268546 -389.9281)
		(size 0.5588)
		(drill 0.3048)
		(layers "F.Cu" "B.Cu")
		(net "12V_PRE_1")
	)
	(segment
		(start 220.268546 -389.9281)
		(end 219.725494 -389.152384)
		(width 0.508)
		(layer "B.Cu")
		(net "12V_PRE_1")
	)
	(segment
		(start 219.725494 -389.152384)
		(end 219.658946 -389.1407)
		(width 0.508)
		(layer "B.Cu")
		(net "12V_PRE_1")
	)
	(segment
		(start 215.703658 -372.552468)
		(end 215.617552 -372.466108)
		(width 0.09525)
		(layer "F.Cu")
		(net "SAS2X28_B_HDD1_RX_+")
	)
	(segment
		(start 217.068146 -372.928134)
		(end 216.610946 -372.928134)
		(width 0.09525)
		(layer "F.Cu")
		(net "SAS2X28_B_HDD1_RX_+")
	)
	(segment
		(start 217.697558 -373.201184)
		(end 217.676476 -373.180102)
		(width 0.09525)
		(layer "F.Cu")
		(net "SAS2X28_B_HDD1_RX_+")
	)
	(via
		(at 215.617552 -372.466108)
		(size 0.5588)
		(drill 0.3048)
		(layers "F.Cu" "B.Cu")
		(net "SAS2X28_B_HDD1_RX_+")
	)
	(arc
		(start 217.676476 -373.180102)
		(mid 217.397372 -372.993611)
		(end 217.068146 -372.928134)
		(width 0.09525)
		(layer "F.Cu")
		(net "SAS2X28_B_HDD1_RX_+")
	)
	(arc
		(start 216.610946 -372.928134)
		(mid 216.119927 -372.830558)
		(end 215.703658 -372.552468)
		(width 0.09525)
		(layer "F.Cu")
		(net "SAS2X28_B_HDD1_RX_+")
	)
	(segment
		(start 214.91829 -372.519702)
		(end 212.25129 -369.852702)
		(width 0.09525)
		(layer "B.Cu")
		(net "SAS2X28_B_HDD1_RX_+")
	)
	(segment
		(start 215.617552 -372.466108)
		(end 215.566244 -372.51767)
		(width 0.09525)
		(layer "B.Cu")
		(net "SAS2X28_B_HDD1_RX_+")
	)
	(segment
		(start 212.25256 -369.851432)
		(end 19.076924 -134.295388)
		(width 0.09525)
		(layer "B.Cu")
		(net "SAS2X28_B_HDD1_RX_+")
	)
	(segment
		(start 19.055334 -134.271258)
		(end 11.357356 -126.57328)
		(width 0.09525)
		(layer "B.Cu")
		(net "SAS2X28_B_HDD1_RX_+")
	)
	(segment
		(start 19.076924 -134.295388)
		(end 19.055334 -134.271258)
		(width 0.09525)
		(layer "B.Cu")
		(net "SAS2X28_B_HDD1_RX_+")
	)
	(segment
		(start 4.98856 -125.49886)
		(end 2.811526 -125.49886)
		(width 0.09525)
		(layer "B.Cu")
		(net "SAS2X28_B_HDD1_RX_+")
	)
	(segment
		(start 5.298694 -125.650498)
		(end 5.260594 -125.612398)
		(width 0.09525)
		(layer "B.Cu")
		(net "SAS2X28_B_HDD1_RX_+")
	)
	(segment
		(start 212.25129 -369.852702)
		(end 212.25256 -369.851432)
		(width 0.09525)
		(layer "B.Cu")
		(net "SAS2X28_B_HDD1_RX_+")
	)
	(segment
		(start 9.397238 -125.830584)
		(end 5.733542 -125.830584)
		(width 0.09525)
		(layer "B.Cu")
		(net "SAS2X28_B_HDD1_RX_+")
	)
	(segment
		(start 4.990084 -125.500384)
		(end 4.98856 -125.49886)
		(width 0.09525)
		(layer "B.Cu")
		(net "SAS2X28_B_HDD1_RX_+")
	)
	(arc
		(start 215.074754 -372.621556)
		(mid 214.991178 -372.578834)
		(end 214.91829 -372.519702)
		(width 0.09525)
		(layer "B.Cu")
		(net "SAS2X28_B_HDD1_RX_+")
	)
	(arc
		(start 215.566244 -372.51767)
		(mid 215.33591 -372.642582)
		(end 215.074754 -372.621556)
		(width 0.09525)
		(layer "B.Cu")
		(net "SAS2X28_B_HDD1_RX_+")
	)
	(arc
		(start 11.357356 -126.57328)
		(mid 10.443789 -126.026451)
		(end 9.397238 -125.830584)
		(width 0.09525)
		(layer "B.Cu")
		(net "SAS2X28_B_HDD1_RX_+")
	)
	(arc
		(start 5.733542 -125.830584)
		(mid 5.498217 -125.783775)
		(end 5.298694 -125.650498)
		(width 0.09525)
		(layer "B.Cu")
		(net "SAS2X28_B_HDD1_RX_+")
	)
	(arc
		(start 5.260594 -125.612398)
		(mid 5.136483 -125.52947)
		(end 4.990084 -125.500384)
		(width 0.09525)
		(layer "B.Cu")
		(net "SAS2X28_B_HDD1_RX_+")
	)
	(segment
		(start 27.304746 -273.3167)
		(end 27.431746 -273.1897)
		(width 0.111252)
		(layer "F.Cu")
		(net "SAS2X28_A_HDD7_FLT")
	)
	(segment
		(start 28.447746 -273.3167)
		(end 28.447746 -274.1422)
		(width 0.111252)
		(layer "F.Cu")
		(net "SAS2X28_A_HDD7_FLT")
	)
	(segment
		(start 28.320746 -273.1897)
		(end 28.447746 -273.3167)
		(width 0.111252)
		(layer "F.Cu")
		(net "SAS2X28_A_HDD7_FLT")
	)
	(segment
		(start 27.106372 -273.3167)
		(end 27.304746 -273.3167)
		(width 0.111252)
		(layer "F.Cu")
		(net "SAS2X28_A_HDD7_FLT")
	)
	(segment
		(start 26.707846 -273.6596)
		(end 27.050746 -273.3167)
		(width 0.111252)
		(layer "F.Cu")
		(net "SAS2X28_A_HDD7_FLT")
	)
	(segment
		(start 25.742646 -273.6596)
		(end 26.707846 -273.6596)
		(width 0.111252)
		(layer "F.Cu")
		(net "SAS2X28_A_HDD7_FLT")
	)
	(segment
		(start 27.431746 -273.1897)
		(end 28.320746 -273.1897)
		(width 0.111252)
		(layer "F.Cu")
		(net "SAS2X28_A_HDD7_FLT")
	)
	(segment
		(start 27.050746 -273.3167)
		(end 27.106372 -273.3167)
		(width 0.111252)
		(layer "F.Cu")
		(net "SAS2X28_A_HDD7_FLT")
	)
	(via
		(at 27.106372 -273.3167)
		(size 0.5588)
		(drill 0.3048)
		(layers "F.Cu" "B.Cu")
		(net "SAS2X28_A_HDD7_FLT")
	)
	(via
		(at 11.8618 -392.885422)
		(size 0.5588)
		(drill 0.3048)
		(layers "F.Cu" "B.Cu")
		(net "SAS2X28_A_HDD7_FLT")
	)
	(via
		(at 28.22956 -272.963386)
		(size 0.7112)
		(drill 0.3556)
		(layers "F.Cu" "B.Cu")
		(net "SAS2X28_A_HDD7_FLT")
	)
	(segment
		(start 8.686546 -394.403326)
		(end 8.36422 -394.081)
		(width 0.111252)
		(layer "B.Cu")
		(net "SAS2X28_A_HDD7_FLT")
	)
	(segment
		(start 11.8618 -392.885422)
		(end 11.8618 -393.984988)
		(width 0.111252)
		(layer "B.Cu")
		(net "SAS2X28_A_HDD7_FLT")
	)
	(segment
		(start 4.726432 -393.498832)
		(end 2.811526 -393.498832)
		(width 0.111252)
		(layer "B.Cu")
		(net "SAS2X28_A_HDD7_FLT")
	)
	(segment
		(start 8.36422 -394.081)
		(end 5.3086 -394.081)
		(width 0.111252)
		(layer "B.Cu")
		(net "SAS2X28_A_HDD7_FLT")
	)
	(segment
		(start 11.8618 -393.984988)
		(end 11.443462 -394.403326)
		(width 0.111252)
		(layer "B.Cu")
		(net "SAS2X28_A_HDD7_FLT")
	)
	(segment
		(start 5.3086 -394.081)
		(end 4.726432 -393.498832)
		(width 0.111252)
		(layer "B.Cu")
		(net "SAS2X28_A_HDD7_FLT")
	)
	(segment
		(start 27.459686 -272.963386)
		(end 28.22956 -272.963386)
		(width 0.111252)
		(layer "B.Cu")
		(net "SAS2X28_A_HDD7_FLT")
	)
	(segment
		(start 27.106372 -273.3167)
		(end 27.459686 -272.963386)
		(width 0.111252)
		(layer "B.Cu")
		(net "SAS2X28_A_HDD7_FLT")
	)
	(segment
		(start 11.443462 -394.403326)
		(end 8.686546 -394.403326)
		(width 0.111252)
		(layer "B.Cu")
		(net "SAS2X28_A_HDD7_FLT")
	)
	(segment
		(start 49.81575 -279.10155)
		(end 41.0337 -270.3195)
		(width 0.14605)
		(layer "In5.Cu")
		(net "SAS2X28_A_HDD7_FLT")
	)
	(segment
		(start 46.992286 -445.59855)
		(end 83.410552 -409.180284)
		(width 0.14605)
		(layer "In5.Cu")
		(net "SAS2X28_A_HDD7_FLT")
	)
	(segment
		(start 26.05405 -445.59855)
		(end 46.992286 -445.59855)
		(width 0.14605)
		(layer "In5.Cu")
		(net "SAS2X28_A_HDD7_FLT")
	)
	(segment
		(start 15.09014 -402.178774)
		(end 15.09014 -431.70348)
		(width 0.14605)
		(layer "In5.Cu")
		(net "SAS2X28_A_HDD7_FLT")
	)
	(segment
		(start 33.419034 -270.3195)
		(end 32.6009 -271.137634)
		(width 0.14605)
		(layer "In5.Cu")
		(net "SAS2X28_A_HDD7_FLT")
	)
	(segment
		(start 83.410552 -331.324712)
		(end 49.885346 -297.799506)
		(width 0.14605)
		(layer "In5.Cu")
		(net "SAS2X28_A_HDD7_FLT")
	)
	(segment
		(start 15.09014 -431.70348)
		(end 9.782048 -437.011572)
		(width 0.14605)
		(layer "In5.Cu")
		(net "SAS2X28_A_HDD7_FLT")
	)
	(segment
		(start 31.441644 -275.713952)
		(end 29.503624 -275.713952)
		(width 0.14605)
		(layer "In5.Cu")
		(net "SAS2X28_A_HDD7_FLT")
	)
	(segment
		(start 11.8618 -392.885422)
		(end 11.8618 -393.065508)
		(width 0.14605)
		(layer "In5.Cu")
		(net "SAS2X28_A_HDD7_FLT")
	)
	(segment
		(start 10.802366 -442.061346)
		(end 11.437366 -442.061346)
		(width 0.14605)
		(layer "In5.Cu")
		(net "SAS2X28_A_HDD7_FLT")
	)
	(segment
		(start 32.6009 -271.137634)
		(end 32.6009 -274.554696)
		(width 0.14605)
		(layer "In5.Cu")
		(net "SAS2X28_A_HDD7_FLT")
	)
	(segment
		(start 13.247624 -442.810646)
		(end 17.972024 -447.535046)
		(width 0.14605)
		(layer "In5.Cu")
		(net "SAS2X28_A_HDD7_FLT")
	)
	(segment
		(start 17.972024 -447.535046)
		(end 24.117554 -447.535046)
		(width 0.14605)
		(layer "In5.Cu")
		(net "SAS2X28_A_HDD7_FLT")
	)
	(segment
		(start 13.14323 -442.810646)
		(end 13.247624 -442.810646)
		(width 0.14605)
		(layer "In5.Cu")
		(net "SAS2X28_A_HDD7_FLT")
	)
	(segment
		(start 49.885346 -279.269698)
		(end 49.81575 -279.10155)
		(width 0.14605)
		(layer "In5.Cu")
		(net "SAS2X28_A_HDD7_FLT")
	)
	(segment
		(start 9.782048 -437.011572)
		(end 9.782048 -441.041028)
		(width 0.14605)
		(layer "In5.Cu")
		(net "SAS2X28_A_HDD7_FLT")
	)
	(segment
		(start 41.0337 -270.3195)
		(end 33.419034 -270.3195)
		(width 0.14605)
		(layer "In5.Cu")
		(net "SAS2X28_A_HDD7_FLT")
	)
	(segment
		(start 11.437366 -442.061346)
		(end 12.183364 -442.807344)
		(width 0.14605)
		(layer "In5.Cu")
		(net "SAS2X28_A_HDD7_FLT")
	)
	(segment
		(start 24.117554 -447.535046)
		(end 26.05405 -445.59855)
		(width 0.14605)
		(layer "In5.Cu")
		(net "SAS2X28_A_HDD7_FLT")
	)
	(segment
		(start 49.885346 -297.799506)
		(end 49.885346 -279.269698)
		(width 0.14605)
		(layer "In5.Cu")
		(net "SAS2X28_A_HDD7_FLT")
	)
	(segment
		(start 13.139928 -442.807344)
		(end 13.14323 -442.810646)
		(width 0.14605)
		(layer "In5.Cu")
		(net "SAS2X28_A_HDD7_FLT")
	)
	(segment
		(start 32.6009 -274.554696)
		(end 31.441644 -275.713952)
		(width 0.14605)
		(layer "In5.Cu")
		(net "SAS2X28_A_HDD7_FLT")
	)
	(segment
		(start 9.782048 -441.041028)
		(end 10.802366 -442.061346)
		(width 0.14605)
		(layer "In5.Cu")
		(net "SAS2X28_A_HDD7_FLT")
	)
	(segment
		(start 15.344902 -401.924012)
		(end 15.09014 -402.178774)
		(width 0.14605)
		(layer "In5.Cu")
		(net "SAS2X28_A_HDD7_FLT")
	)
	(segment
		(start 12.183364 -442.807344)
		(end 13.139928 -442.807344)
		(width 0.14605)
		(layer "In5.Cu")
		(net "SAS2X28_A_HDD7_FLT")
	)
	(segment
		(start 83.410552 -409.180284)
		(end 83.410552 -331.324712)
		(width 0.14605)
		(layer "In5.Cu")
		(net "SAS2X28_A_HDD7_FLT")
	)
	(segment
		(start 29.503624 -275.713952)
		(end 27.106372 -273.3167)
		(width 0.14605)
		(layer "In5.Cu")
		(net "SAS2X28_A_HDD7_FLT")
	)
	(segment
		(start 11.8618 -393.065508)
		(end 15.344902 -396.54861)
		(width 0.14605)
		(layer "In5.Cu")
		(net "SAS2X28_A_HDD7_FLT")
	)
	(segment
		(start 15.344902 -396.54861)
		(end 15.344902 -401.924012)
		(width 0.14605)
		(layer "In5.Cu")
		(net "SAS2X28_A_HDD7_FLT")
	)
	(segment
		(start 217.644726 -476.059754)
		(end 217.570812 -475.98584)
		(width 0.09525)
		(layer "F.Cu")
		(net "SAS2X28_B_HDD0_RX_+")
	)
	(segment
		(start 217.296746 -475.872302)
		(end 216.915746 -475.872302)
		(width 0.09525)
		(layer "F.Cu")
		(net "SAS2X28_B_HDD0_RX_+")
	)
	(segment
		(start 216.28989 -475.613222)
		(end 215.925146 -475.248224)
		(width 0.09525)
		(layer "F.Cu")
		(net "SAS2X28_B_HDD0_RX_+")
	)
	(segment
		(start 218.202256 -476.151702)
		(end 217.866722 -476.151702)
		(width 0.09525)
		(layer "F.Cu")
		(net "SAS2X28_B_HDD0_RX_+")
	)
	(via
		(at 215.925146 -475.248224)
		(size 0.5588)
		(drill 0.3048)
		(layers "F.Cu" "B.Cu")
		(net "SAS2X28_B_HDD0_RX_+")
	)
	(arc
		(start 216.915746 -475.872302)
		(mid 216.577042 -475.805023)
		(end 216.28989 -475.613222)
		(width 0.09525)
		(layer "F.Cu")
		(net "SAS2X28_B_HDD0_RX_+")
	)
	(arc
		(start 217.866722 -476.151702)
		(mid 217.746581 -476.127804)
		(end 217.644726 -476.059754)
		(width 0.09525)
		(layer "F.Cu")
		(net "SAS2X28_B_HDD0_RX_+")
	)
	(arc
		(start 217.570812 -475.98584)
		(mid 217.445069 -475.901822)
		(end 217.296746 -475.872302)
		(width 0.09525)
		(layer "F.Cu")
		(net "SAS2X28_B_HDD0_RX_+")
	)
	(segment
		(start 5.390388 -129.674874)
		(end 5.319268 -129.603754)
		(width 0.09525)
		(layer "B.Cu")
		(net "SAS2X28_B_HDD0_RX_+")
	)
	(segment
		(start 214.580216 -475.054676)
		(end 207.872838 -463.656934)
		(width 0.09525)
		(layer "B.Cu")
		(net "SAS2X28_B_HDD0_RX_+")
	)
	(segment
		(start 6.822694 -130.222752)
		(end 6.756908 -130.15722)
		(width 0.09525)
		(layer "B.Cu")
		(net "SAS2X28_B_HDD0_RX_+")
	)
	(segment
		(start 5.449062 -129.733802)
		(end 5.390388 -129.674874)
		(width 0.09525)
		(layer "B.Cu")
		(net "SAS2X28_B_HDD0_RX_+")
	)
	(segment
		(start 207.872838 -463.656934)
		(end 49.148746 -193.9417)
		(width 0.09525)
		(layer "B.Cu")
		(net "SAS2X28_B_HDD0_RX_+")
	)
	(segment
		(start 5.069586 -129.500376)
		(end 2.81305 -129.500376)
		(width 0.09525)
		(layer "B.Cu")
		(net "SAS2X28_B_HDD0_RX_+")
	)
	(segment
		(start 214.720678 -475.293182)
		(end 214.580216 -475.054676)
		(width 0.09525)
		(layer "B.Cu")
		(net "SAS2X28_B_HDD0_RX_+")
	)
	(segment
		(start 6.061964 -129.80924)
		(end 5.63118 -129.80924)
		(width 0.09525)
		(layer "B.Cu")
		(net "SAS2X28_B_HDD0_RX_+")
	)
	(segment
		(start 49.148746 -193.9417)
		(end 7.392416 -132.446014)
		(width 0.09525)
		(layer "B.Cu")
		(net "SAS2X28_B_HDD0_RX_+")
	)
	(segment
		(start 6.94944 -130.349752)
		(end 6.94944 -130.349498)
		(width 0.09525)
		(layer "B.Cu")
		(net "SAS2X28_B_HDD0_RX_+")
	)
	(segment
		(start 6.94944 -130.349498)
		(end 6.822694 -130.222752)
		(width 0.09525)
		(layer "B.Cu")
		(net "SAS2X28_B_HDD0_RX_+")
	)
	(segment
		(start 215.74887 -475.4245)
		(end 214.95004 -475.4245)
		(width 0.09525)
		(layer "B.Cu")
		(net "SAS2X28_B_HDD0_RX_+")
	)
	(segment
		(start 2.81305 -129.500376)
		(end 2.811526 -129.498852)
		(width 0.09525)
		(layer "B.Cu")
		(net "SAS2X28_B_HDD0_RX_+")
	)
	(segment
		(start 7.238746 -132.07492)
		(end 7.238746 -131.048252)
		(width 0.09525)
		(layer "B.Cu")
		(net "SAS2X28_B_HDD0_RX_+")
	)
	(arc
		(start 215.925146 -475.248224)
		(mid 215.890186 -475.353595)
		(end 215.799162 -475.417134)
		(width 0.09525)
		(layer "B.Cu")
		(net "SAS2X28_B_HDD0_RX_+")
	)
	(arc
		(start 215.799162 -475.417134)
		(mid 215.774284 -475.422656)
		(end 215.74887 -475.4245)
		(width 0.09525)
		(layer "B.Cu")
		(net "SAS2X28_B_HDD0_RX_+")
	)
	(arc
		(start 5.63118 -129.80924)
		(mid 5.532618 -129.789635)
		(end 5.449062 -129.733802)
		(width 0.09525)
		(layer "B.Cu")
		(net "SAS2X28_B_HDD0_RX_+")
	)
	(arc
		(start 7.238746 -131.048252)
		(mid 7.163622 -130.670196)
		(end 6.94944 -130.349752)
		(width 0.09525)
		(layer "B.Cu")
		(net "SAS2X28_B_HDD0_RX_+")
	)
	(arc
		(start 214.95004 -475.4245)
		(mid 214.817865 -475.389366)
		(end 214.720678 -475.293182)
		(width 0.09525)
		(layer "B.Cu")
		(net "SAS2X28_B_HDD0_RX_+")
	)
	(arc
		(start 5.319268 -129.603754)
		(mid 5.204713 -129.527211)
		(end 5.069586 -129.500376)
		(width 0.09525)
		(layer "B.Cu")
		(net "SAS2X28_B_HDD0_RX_+")
	)
	(arc
		(start 7.392416 -132.446014)
		(mid 7.278682 -132.275754)
		(end 7.238746 -132.07492)
		(width 0.09525)
		(layer "B.Cu")
		(net "SAS2X28_B_HDD0_RX_+")
	)
	(arc
		(start 6.756908 -130.15722)
		(mid 6.690215 -130.095726)
		(end 6.618732 -130.039872)
		(width 0.09525)
		(layer "B.Cu")
		(net "SAS2X28_B_HDD0_RX_+")
	)
	(arc
		(start 6.618732 -130.039872)
		(mid 6.363285 -129.869188)
		(end 6.061964 -129.80924)
		(width 0.09525)
		(layer "B.Cu")
		(net "SAS2X28_B_HDD0_RX_+")
	)
	(via
		(at 219.561156 -493.7887)
		(size 0.7112)
		(drill 0.3556)
		(layers "F.Cu" "B.Cu")
		(net "12V_PRE_0")
	)
	(via
		(at 219.561156 -492.7727)
		(size 0.7112)
		(drill 0.4064)
		(layers "F.Cu" "B.Cu")
		(net "12V_PRE_0")
	)
	(segment
		(start 219.561156 -493.7887)
		(end 219.561156 -492.7727)
		(width 0.508)
		(layer "B.Cu")
		(net "12V_PRE_0")
	)
	(segment
		(start 27.114246 -274.1422)
		(end 27.797506 -274.1422)
		(width 0.111252)
		(layer "F.Cu")
		(net "SAS2X28_B_HDD7_FLT")
	)
	(segment
		(start 26.504646 -274.7518)
		(end 26.796746 -274.4597)
		(width 0.111252)
		(layer "F.Cu")
		(net "SAS2X28_B_HDD7_FLT")
	)
	(segment
		(start 26.796746 -274.4597)
		(end 27.114246 -274.1422)
		(width 0.111252)
		(layer "F.Cu")
		(net "SAS2X28_B_HDD7_FLT")
	)
	(segment
		(start 25.742646 -274.7518)
		(end 26.504646 -274.7518)
		(width 0.111252)
		(layer "F.Cu")
		(net "SAS2X28_B_HDD7_FLT")
	)
	(via
		(at 41.8338 -275.6916)
		(size 0.5588)
		(drill 0.3048)
		(layers "F.Cu" "B.Cu")
		(net "SAS2X28_B_HDD7_FLT")
	)
	(via
		(at 27.812746 -274.4597)
		(size 0.7112)
		(drill 0.3556)
		(layers "F.Cu" "B.Cu")
		(net "SAS2X28_B_HDD7_FLT")
	)
	(via
		(at 92.582746 -279.1587)
		(size 0.5588)
		(drill 0.3048)
		(layers "F.Cu" "B.Cu")
		(net "SAS2X28_B_HDD7_FLT")
	)
	(via
		(at 26.796746 -274.4597)
		(size 0.5588)
		(drill 0.3048)
		(layers "F.Cu" "B.Cu")
		(net "SAS2X28_B_HDD7_FLT")
	)
	(via
		(at 9.270746 -143.8529)
		(size 0.5588)
		(drill 0.3048)
		(layers "F.Cu" "B.Cu")
		(net "SAS2X28_B_HDD7_FLT")
	)
	(via
		(at 8.013446 -143.7767)
		(size 0.7112)
		(drill 0.3556)
		(layers "F.Cu" "B.Cu")
		(net "SAS2X28_B_HDD7_FLT")
	)
	(segment
		(start 27.9527 -274.4597)
		(end 27.812746 -274.4597)
		(width 0.111252)
		(layer "B.Cu")
		(net "SAS2X28_B_HDD7_FLT")
	)
	(segment
		(start 5.645404 -143.1925)
		(end 5.4229 -143.1925)
		(width 0.111252)
		(layer "B.Cu")
		(net "SAS2X28_B_HDD7_FLT")
	)
	(segment
		(start 2.81305 -143.500348)
		(end 2.811526 -143.498824)
		(width 0.111252)
		(layer "B.Cu")
		(net "SAS2X28_B_HDD7_FLT")
	)
	(segment
		(start 9.194546 -143.7767)
		(end 8.013446 -143.7767)
		(width 0.111252)
		(layer "B.Cu")
		(net "SAS2X28_B_HDD7_FLT")
	)
	(segment
		(start 6.033262 -143.187674)
		(end 5.65023 -143.187674)
		(width 0.111252)
		(layer "B.Cu")
		(net "SAS2X28_B_HDD7_FLT")
	)
	(segment
		(start 9.270746 -143.8529)
		(end 9.194546 -143.7767)
		(width 0.111252)
		(layer "B.Cu")
		(net "SAS2X28_B_HDD7_FLT")
	)
	(segment
		(start 41.506902 -276.018498)
		(end 29.511498 -276.018498)
		(width 0.111252)
		(layer "B.Cu")
		(net "SAS2X28_B_HDD7_FLT")
	)
	(segment
		(start 5.115052 -143.500348)
		(end 2.81305 -143.500348)
		(width 0.111252)
		(layer "B.Cu")
		(net "SAS2X28_B_HDD7_FLT")
	)
	(segment
		(start 8.013446 -143.7767)
		(end 6.716014 -143.7767)
		(width 0.111252)
		(layer "B.Cu")
		(net "SAS2X28_B_HDD7_FLT")
	)
	(segment
		(start 5.4229 -143.1925)
		(end 5.115052 -143.500348)
		(width 0.111252)
		(layer "B.Cu")
		(net "SAS2X28_B_HDD7_FLT")
	)
	(segment
		(start 27.812746 -274.4597)
		(end 26.796746 -274.4597)
		(width 0.111252)
		(layer "B.Cu")
		(net "SAS2X28_B_HDD7_FLT")
	)
	(segment
		(start 6.716014 -143.7767)
		(end 6.68909 -143.749776)
		(width 0.111252)
		(layer "B.Cu")
		(net "SAS2X28_B_HDD7_FLT")
	)
	(segment
		(start 41.8338 -275.6916)
		(end 41.506902 -276.018498)
		(width 0.111252)
		(layer "B.Cu")
		(net "SAS2X28_B_HDD7_FLT")
	)
	(segment
		(start 6.68909 -143.749776)
		(end 6.595364 -143.749776)
		(width 0.111252)
		(layer "B.Cu")
		(net "SAS2X28_B_HDD7_FLT")
	)
	(segment
		(start 6.595364 -143.749776)
		(end 6.033262 -143.187674)
		(width 0.111252)
		(layer "B.Cu")
		(net "SAS2X28_B_HDD7_FLT")
	)
	(segment
		(start 29.511498 -276.018498)
		(end 27.9527 -274.4597)
		(width 0.111252)
		(layer "B.Cu")
		(net "SAS2X28_B_HDD7_FLT")
	)
	(segment
		(start 5.65023 -143.187674)
		(end 5.645404 -143.1925)
		(width 0.111252)
		(layer "B.Cu")
		(net "SAS2X28_B_HDD7_FLT")
	)
	(segment
		(start 42.48658 -276.4917)
		(end 54.1147 -276.4917)
		(width 0.14605)
		(layer "In2.Cu")
		(net "SAS2X28_B_HDD7_FLT")
	)
	(segment
		(start 41.8338 -275.6916)
		(end 41.8338 -275.83892)
		(width 0.14605)
		(layer "In2.Cu")
		(net "SAS2X28_B_HDD7_FLT")
	)
	(segment
		(start 61.1251 -276.8854)
		(end 83.578446 -276.8854)
		(width 0.14605)
		(layer "In2.Cu")
		(net "SAS2X28_B_HDD7_FLT")
	)
	(segment
		(start 85.851746 -279.1587)
		(end 92.582746 -279.1587)
		(width 0.14605)
		(layer "In2.Cu")
		(net "SAS2X28_B_HDD7_FLT")
	)
	(segment
		(start 54.1147 -276.4917)
		(end 56.515 -278.892)
		(width 0.14605)
		(layer "In2.Cu")
		(net "SAS2X28_B_HDD7_FLT")
	)
	(segment
		(start 56.515 -278.892)
		(end 59.1185 -278.892)
		(width 0.14605)
		(layer "In2.Cu")
		(net "SAS2X28_B_HDD7_FLT")
	)
	(segment
		(start 83.578446 -276.8854)
		(end 85.851746 -279.1587)
		(width 0.14605)
		(layer "In2.Cu")
		(net "SAS2X28_B_HDD7_FLT")
	)
	(segment
		(start 41.8338 -275.83892)
		(end 42.48658 -276.4917)
		(width 0.14605)
		(layer "In2.Cu")
		(net "SAS2X28_B_HDD7_FLT")
	)
	(segment
		(start 59.1185 -278.892)
		(end 61.1251 -276.8854)
		(width 0.14605)
		(layer "In2.Cu")
		(net "SAS2X28_B_HDD7_FLT")
	)
	(segment
		(start 87.893652 -102.277164)
		(end 25.190958 -102.277164)
		(width 0.14605)
		(layer "In5.Cu")
		(net "SAS2X28_B_HDD7_FLT")
	)
	(segment
		(start 92.582746 -279.1587)
		(end 92.582746 -106.966258)
		(width 0.14605)
		(layer "In5.Cu")
		(net "SAS2X28_B_HDD7_FLT")
	)
	(segment
		(start 12.490704 -140.632942)
		(end 9.270746 -143.8529)
		(width 0.14605)
		(layer "In5.Cu")
		(net "SAS2X28_B_HDD7_FLT")
	)
	(segment
		(start 13.839952 -134.20598)
		(end 12.490704 -135.555228)
		(width 0.14605)
		(layer "In5.Cu")
		(net "SAS2X28_B_HDD7_FLT")
	)
	(segment
		(start 12.490704 -135.555228)
		(end 12.490704 -140.632942)
		(width 0.14605)
		(layer "In5.Cu")
		(net "SAS2X28_B_HDD7_FLT")
	)
	(segment
		(start 13.401548 -128.652016)
		(end 13.839952 -129.09042)
		(width 0.14605)
		(layer "In5.Cu")
		(net "SAS2X28_B_HDD7_FLT")
	)
	(segment
		(start 13.839952 -129.09042)
		(end 13.839952 -134.20598)
		(width 0.14605)
		(layer "In5.Cu")
		(net "SAS2X28_B_HDD7_FLT")
	)
	(segment
		(start 13.401548 -114.066574)
		(end 13.401548 -128.652016)
		(width 0.14605)
		(layer "In5.Cu")
		(net "SAS2X28_B_HDD7_FLT")
	)
	(segment
		(start 92.582746 -106.966258)
		(end 87.893652 -102.277164)
		(width 0.14605)
		(layer "In5.Cu")
		(net "SAS2X28_B_HDD7_FLT")
	)
	(segment
		(start 25.190958 -102.277164)
		(end 13.401548 -114.066574)
		(width 0.14605)
		(layer "In5.Cu")
		(net "SAS2X28_B_HDD7_FLT")
	)
	(segment
		(start 8.438896 -417.100512)
		(end 8.889746 -417.100512)
		(width 0.09525)
		(layer "F.Cu")
		(net "SAS2X28_A_HDD0_RX_+")
	)
	(segment
		(start 9.41197 -417.447222)
		(end 13.47597 -421.511222)
		(width 0.09525)
		(layer "F.Cu")
		(net "SAS2X28_A_HDD0_RX_+")
	)
	(segment
		(start 33.259014 -463.028792)
		(end 33.380172 -462.90738)
		(width 0.09525)
		(layer "F.Cu")
		(net "SAS2X28_A_HDD0_RX_+")
	)
	(segment
		(start 213.2584 -468.63)
		(end 213.697312 -469.068912)
		(width 0.09525)
		(layer "F.Cu")
		(net "SAS2X28_A_HDD0_RX_+")
	)
	(segment
		(start 34.263838 -462.4959)
		(end 67.178174 -462.4959)
		(width 0.09525)
		(layer "F.Cu")
		(net "SAS2X28_A_HDD0_RX_+")
	)
	(segment
		(start 33.380172 -462.90738)
		(end 33.457642 -462.82991)
		(width 0.09525)
		(layer "F.Cu")
		(net "SAS2X28_A_HDD0_RX_+")
	)
	(segment
		(start 68.833746 -463.1817)
		(end 71.794116 -466.141816)
		(width 0.09525)
		(layer "F.Cu")
		(net "SAS2X28_A_HDD0_RX_+")
	)
	(segment
		(start 14.541246 -422.839134)
		(end 14.541246 -460.596488)
		(width 0.09525)
		(layer "F.Cu")
		(net "SAS2X28_A_HDD0_RX_+")
	)
	(segment
		(start 18.8976 -463.338164)
		(end 32.511746 -463.338164)
		(width 0.09525)
		(layer "F.Cu")
		(net "SAS2X28_A_HDD0_RX_+")
	)
	(segment
		(start 215.773 -469.928702)
		(end 218.202256 -469.928702)
		(width 0.09525)
		(layer "F.Cu")
		(net "SAS2X28_A_HDD0_RX_+")
	)
	(segment
		(start 13.47597 -421.511222)
		(end 14.355064 -422.390062)
		(width 0.09525)
		(layer "F.Cu")
		(net "SAS2X28_A_HDD0_RX_+")
	)
	(segment
		(start 8.160512 -417.748466)
		(end 8.090662 -417.678616)
		(width 0.09525)
		(layer "F.Cu")
		(net "SAS2X28_A_HDD0_RX_+")
	)
	(segment
		(start 73.405746 -466.809582)
		(end 210.6422 -466.809582)
		(width 0.09525)
		(layer "F.Cu")
		(net "SAS2X28_A_HDD0_RX_+")
	)
	(segment
		(start 212.000846 -467.372192)
		(end 213.2584 -468.63)
		(width 0.09525)
		(layer "F.Cu")
		(net "SAS2X28_A_HDD0_RX_+")
	)
	(segment
		(start 9.189212 -417.224718)
		(end 9.41197 -417.447222)
		(width 0.09525)
		(layer "F.Cu")
		(net "SAS2X28_A_HDD0_RX_+")
	)
	(via
		(at 8.388604 -417.842954)
		(size 0.5588)
		(drill 0.3048)
		(layers "F.Cu" "B.Cu")
		(net "SAS2X28_A_HDD0_RX_+")
	)
	(arc
		(start 210.6422 -466.809582)
		(mid 211.377487 -466.955746)
		(end 212.000846 -467.372192)
		(width 0.09525)
		(layer "F.Cu")
		(net "SAS2X28_A_HDD0_RX_+")
	)
	(arc
		(start 213.697312 -469.068912)
		(mid 214.649646 -469.705241)
		(end 215.773 -469.928702)
		(width 0.09525)
		(layer "F.Cu")
		(net "SAS2X28_A_HDD0_RX_+")
	)
	(arc
		(start 32.511746 -463.338164)
		(mid 32.916158 -463.257815)
		(end 33.259014 -463.028792)
		(width 0.09525)
		(layer "F.Cu")
		(net "SAS2X28_A_HDD0_RX_+")
	)
	(arc
		(start 8.388604 -417.842954)
		(mid 8.265158 -417.818399)
		(end 8.160512 -417.748466)
		(width 0.09525)
		(layer "F.Cu")
		(net "SAS2X28_A_HDD0_RX_+")
	)
	(arc
		(start 68.219066 -462.739994)
		(mid 68.544387 -462.935827)
		(end 68.833746 -463.1817)
		(width 0.09525)
		(layer "F.Cu")
		(net "SAS2X28_A_HDD0_RX_+")
	)
	(arc
		(start 14.541246 -460.596488)
		(mid 14.665479 -461.221231)
		(end 15.019274 -461.750918)
		(width 0.09525)
		(layer "F.Cu")
		(net "SAS2X28_A_HDD0_RX_+")
	)
	(arc
		(start 67.178174 -462.4959)
		(mid 67.712739 -462.557741)
		(end 68.219066 -462.739994)
		(width 0.09525)
		(layer "F.Cu")
		(net "SAS2X28_A_HDD0_RX_+")
	)
	(arc
		(start 8.090662 -417.678616)
		(mid 8.017102 -417.560523)
		(end 8.003286 -417.422076)
		(width 0.09525)
		(layer "F.Cu")
		(net "SAS2X28_A_HDD0_RX_+")
	)
	(arc
		(start 33.457642 -462.82991)
		(mid 33.827499 -462.582653)
		(end 34.263838 -462.4959)
		(width 0.09525)
		(layer "F.Cu")
		(net "SAS2X28_A_HDD0_RX_+")
	)
	(arc
		(start 71.794116 -466.141816)
		(mid 72.533523 -466.635965)
		(end 73.405746 -466.809582)
		(width 0.09525)
		(layer "F.Cu")
		(net "SAS2X28_A_HDD0_RX_+")
	)
	(arc
		(start 8.090662 -417.244784)
		(mid 8.250433 -417.138028)
		(end 8.438896 -417.100512)
		(width 0.09525)
		(layer "F.Cu")
		(net "SAS2X28_A_HDD0_RX_+")
	)
	(arc
		(start 8.003286 -417.422076)
		(mid 8.032286 -417.326189)
		(end 8.090662 -417.244784)
		(width 0.09525)
		(layer "F.Cu")
		(net "SAS2X28_A_HDD0_RX_+")
	)
	(arc
		(start 8.889746 -417.100512)
		(mid 9.051825 -417.132845)
		(end 9.189212 -417.224718)
		(width 0.09525)
		(layer "F.Cu")
		(net "SAS2X28_A_HDD0_RX_+")
	)
	(arc
		(start 15.019274 -461.750918)
		(mid 16.798841 -462.934533)
		(end 18.8976 -463.338164)
		(width 0.09525)
		(layer "F.Cu")
		(net "SAS2X28_A_HDD0_RX_+")
	)
	(arc
		(start 14.355064 -422.390062)
		(mid 14.492787 -422.596084)
		(end 14.541246 -422.839134)
		(width 0.09525)
		(layer "F.Cu")
		(net "SAS2X28_A_HDD0_RX_+")
	)
	(segment
		(start 8.097266 -417.139628)
		(end 8.097266 -416.1917)
		(width 0.09525)
		(layer "B.Cu")
		(net "SAS2X28_A_HDD0_RX_+")
	)
	(segment
		(start 6.088888 -413.836612)
		(end 5.6388 -413.836612)
		(width 0.09525)
		(layer "B.Cu")
		(net "SAS2X28_A_HDD0_RX_+")
	)
	(segment
		(start 7.626604 -415.055812)
		(end 7.619746 -415.0487)
		(width 0.09525)
		(layer "B.Cu")
		(net "SAS2X28_A_HDD0_RX_+")
	)
	(segment
		(start 7.619746 -415.0487)
		(end 6.793992 -414.222946)
		(width 0.09525)
		(layer "B.Cu")
		(net "SAS2X28_A_HDD0_RX_+")
	)
	(segment
		(start 4.827016 -413.500316)
		(end 4.825492 -413.498792)
		(width 0.09525)
		(layer "B.Cu")
		(net "SAS2X28_A_HDD0_RX_+")
	)
	(segment
		(start 6.793992 -414.222946)
		(end 6.705854 -414.135062)
		(width 0.09525)
		(layer "B.Cu")
		(net "SAS2X28_A_HDD0_RX_+")
	)
	(segment
		(start 4.825492 -413.498792)
		(end 2.811526 -413.498792)
		(width 0.09525)
		(layer "B.Cu")
		(net "SAS2X28_A_HDD0_RX_+")
	)
	(segment
		(start 5.632196 -413.836358)
		(end 5.611368 -413.835342)
		(width 0.09525)
		(layer "B.Cu")
		(net "SAS2X28_A_HDD0_RX_+")
	)
	(arc
		(start 5.611368 -413.835342)
		(mid 5.397871 -413.785587)
		(end 5.216906 -413.66186)
		(width 0.09525)
		(layer "B.Cu")
		(net "SAS2X28_A_HDD0_RX_+")
	)
	(arc
		(start 8.388604 -417.842954)
		(mid 8.17299 -417.520265)
		(end 8.097266 -417.139628)
		(width 0.09525)
		(layer "B.Cu")
		(net "SAS2X28_A_HDD0_RX_+")
	)
	(arc
		(start 5.6388 -413.836612)
		(mid 5.635498 -413.836494)
		(end 5.632196 -413.836358)
		(width 0.09525)
		(layer "B.Cu")
		(net "SAS2X28_A_HDD0_RX_+")
	)
	(arc
		(start 6.705854 -414.135062)
		(mid 6.422591 -413.933702)
		(end 6.088888 -413.836612)
		(width 0.09525)
		(layer "B.Cu")
		(net "SAS2X28_A_HDD0_RX_+")
	)
	(arc
		(start 8.097266 -416.1917)
		(mid 7.97496 -415.576914)
		(end 7.626604 -415.055812)
		(width 0.09525)
		(layer "B.Cu")
		(net "SAS2X28_A_HDD0_RX_+")
	)
	(arc
		(start 5.216906 -413.66186)
		(mid 5.038023 -413.542334)
		(end 4.827016 -413.500316)
		(width 0.09525)
		(layer "B.Cu")
		(net "SAS2X28_A_HDD0_RX_+")
	)
	(segment
		(start 45.719746 -248.0437)
		(end 45.719746 -247.0277)
		(width 0.111252)
		(layer "F.Cu")
		(net "DRIVE_ACT_7")
	)
	(segment
		(start 47.751746 -247.4087)
		(end 47.256446 -246.9134)
		(width 0.111252)
		(layer "F.Cu")
		(net "DRIVE_ACT_7")
	)
	(segment
		(start 45.834046 -246.9134)
		(end 47.256446 -246.9134)
		(width 0.111252)
		(layer "F.Cu")
		(net "DRIVE_ACT_7")
	)
	(segment
		(start 45.719746 -247.0277)
		(end 45.834046 -246.9134)
		(width 0.111252)
		(layer "F.Cu")
		(net "DRIVE_ACT_7")
	)
	(segment
		(start 47.878746 -249.4407)
		(end 47.751746 -249.3137)
		(width 0.111252)
		(layer "F.Cu")
		(net "DRIVE_ACT_7")
	)
	(segment
		(start 47.751746 -249.3137)
		(end 47.751746 -247.4087)
		(width 0.111252)
		(layer "F.Cu")
		(net "DRIVE_ACT_7")
	)
	(via
		(at 47.878746 -249.4407)
		(size 0.7112)
		(drill 0.3556)
		(layers "F.Cu" "B.Cu")
		(net "DRIVE_ACT_7")
	)
	(segment
		(start 223.773746 -473.551758)
		(end 220.751146 -473.551758)
		(width 0.09525)
		(layer "F.Cu")
		(net "SAS2X28_B_HDD0_TX_-")
	)
	(segment
		(start 4.802632 -132.498846)
		(end 3.192526 -132.498846)
		(width 0.09525)
		(layer "F.Cu")
		(net "SAS2X28_B_HDD0_TX_-")
	)
	(segment
		(start 8.762746 -132.160772)
		(end 7.197344 -132.160772)
		(width 0.09525)
		(layer "F.Cu")
		(net "SAS2X28_B_HDD0_TX_-")
	)
	(segment
		(start 6.732524 -132.393182)
		(end 6.446774 -132.393182)
		(width 0.09525)
		(layer "F.Cu")
		(net "SAS2X28_B_HDD0_TX_-")
	)
	(segment
		(start 225.399854 -473.79001)
		(end 225.396552 -473.786708)
		(width 0.09525)
		(layer "F.Cu")
		(net "SAS2X28_B_HDD0_TX_-")
	)
	(segment
		(start 4.804156 -132.50037)
		(end 4.802632 -132.498846)
		(width 0.09525)
		(layer "F.Cu")
		(net "SAS2X28_B_HDD0_TX_-")
	)
	(segment
		(start 5.981954 -132.160772)
		(end 5.624068 -132.160772)
		(width 0.09525)
		(layer "F.Cu")
		(net "SAS2X28_B_HDD0_TX_-")
	)
	(segment
		(start 224.220278 -473.707968)
		(end 224.144078 -473.631768)
		(width 0.09525)
		(layer "F.Cu")
		(net "SAS2X28_B_HDD0_TX_-")
	)
	(segment
		(start 225.396552 -473.786708)
		(end 224.383346 -473.786708)
		(width 0.09525)
		(layer "F.Cu")
		(net "SAS2X28_B_HDD0_TX_-")
	)
	(via
		(at 220.196156 -473.86621)
		(size 0.5588)
		(drill 0.3048)
		(layers "F.Cu" "B.Cu")
		(net "SAS2X28_B_HDD0_TX_-")
	)
	(via
		(at 9.270746 -132.4737)
		(size 0.5588)
		(drill 0.3048)
		(layers "F.Cu" "B.Cu")
		(net "SAS2X28_B_HDD0_TX_-")
	)
	(arc
		(start 7.197344 -132.160772)
		(mid 7.067009 -132.190708)
		(end 6.964934 -132.277104)
		(width 0.09525)
		(layer "F.Cu")
		(net "SAS2X28_B_HDD0_TX_-")
	)
	(arc
		(start 6.964934 -132.277104)
		(mid 6.862817 -132.363335)
		(end 6.732524 -132.393182)
		(width 0.09525)
		(layer "F.Cu")
		(net "SAS2X28_B_HDD0_TX_-")
	)
	(arc
		(start 224.144078 -473.631768)
		(mid 224.137612 -473.628822)
		(end 224.131124 -473.625926)
		(width 0.09525)
		(layer "F.Cu")
		(net "SAS2X28_B_HDD0_TX_-")
	)
	(arc
		(start 9.270746 -132.4737)
		(mid 9.061083 -132.245245)
		(end 8.762746 -132.160772)
		(width 0.09525)
		(layer "F.Cu")
		(net "SAS2X28_B_HDD0_TX_-")
	)
	(arc
		(start 224.131124 -473.625926)
		(mid 223.956246 -473.570486)
		(end 223.773746 -473.551758)
		(width 0.09525)
		(layer "F.Cu")
		(net "SAS2X28_B_HDD0_TX_-")
	)
	(arc
		(start 224.383346 -473.786708)
		(mid 224.2928 -473.765996)
		(end 224.220278 -473.707968)
		(width 0.09525)
		(layer "F.Cu")
		(net "SAS2X28_B_HDD0_TX_-")
	)
	(arc
		(start 6.446774 -132.393182)
		(mid 6.316456 -132.363385)
		(end 6.214364 -132.277104)
		(width 0.09525)
		(layer "F.Cu")
		(net "SAS2X28_B_HDD0_TX_-")
	)
	(arc
		(start 6.214364 -132.277104)
		(mid 6.11229 -132.190705)
		(end 5.981954 -132.160772)
		(width 0.09525)
		(layer "F.Cu")
		(net "SAS2X28_B_HDD0_TX_-")
	)
	(arc
		(start 220.751146 -473.551758)
		(mid 220.432211 -473.635838)
		(end 220.196156 -473.86621)
		(width 0.09525)
		(layer "F.Cu")
		(net "SAS2X28_B_HDD0_TX_-")
	)
	(arc
		(start 5.624068 -132.160772)
		(mid 5.480696 -132.189291)
		(end 5.359146 -132.2705)
		(width 0.09525)
		(layer "F.Cu")
		(net "SAS2X28_B_HDD0_TX_-")
	)
	(arc
		(start 5.359146 -132.2705)
		(mid 5.104514 -132.440639)
		(end 4.804156 -132.50037)
		(width 0.09525)
		(layer "F.Cu")
		(net "SAS2X28_B_HDD0_TX_-")
	)
	(segment
		(start 207.149446 -455.450448)
		(end 216.71534 -471.291158)
		(width 0.09525)
		(layer "B.Cu")
		(net "SAS2X28_B_HDD0_TX_-")
	)
	(segment
		(start 41.018714 -180.354224)
		(end 43.902884 -185.130186)
		(width 0.09525)
		(layer "B.Cu")
		(net "SAS2X28_B_HDD0_TX_-")
	)
	(segment
		(start 73.999852 -234.96778)
		(end 101.143308 -279.914858)
		(width 0.09525)
		(layer "B.Cu")
		(net "SAS2X28_B_HDD0_TX_-")
	)
	(segment
		(start 217.280236 -472.223084)
		(end 217.446352 -472.496896)
		(width 0.09525)
		(layer "B.Cu")
		(net "SAS2X28_B_HDD0_TX_-")
	)
	(segment
		(start 101.143308 -279.914858)
		(end 124.151898 -318.014858)
		(width 0.09525)
		(layer "B.Cu")
		(net "SAS2X28_B_HDD0_TX_-")
	)
	(segment
		(start 43.902884 -185.130186)
		(end 49.664366 -193.61531)
		(width 0.09525)
		(layer "B.Cu")
		(net "SAS2X28_B_HDD0_TX_-")
	)
	(segment
		(start 219.328492 -473.6719)
		(end 219.727018 -473.6719)
		(width 0.09525)
		(layer "B.Cu")
		(net "SAS2X28_B_HDD0_TX_-")
	)
	(segment
		(start 49.664366 -193.61531)
		(end 73.999852 -234.96778)
		(width 0.09525)
		(layer "B.Cu")
		(net "SAS2X28_B_HDD0_TX_-")
	)
	(segment
		(start 216.71534 -471.291158)
		(end 217.280236 -472.223084)
		(width 0.09525)
		(layer "B.Cu")
		(net "SAS2X28_B_HDD0_TX_-")
	)
	(segment
		(start 10.029698 -132.402834)
		(end 21.187918 -147.516596)
		(width 0.09525)
		(layer "B.Cu")
		(net "SAS2X28_B_HDD0_TX_-")
	)
	(segment
		(start 31.792672 -165.076886)
		(end 32.215074 -165.776402)
		(width 0.09525)
		(layer "B.Cu")
		(net "SAS2X28_B_HDD0_TX_-")
	)
	(segment
		(start 206.451708 -454.296018)
		(end 207.149446 -455.450448)
		(width 0.09525)
		(layer "B.Cu")
		(net "SAS2X28_B_HDD0_TX_-")
	)
	(segment
		(start 9.270746 -132.4737)
		(end 9.270746 -132.448554)
		(width 0.09525)
		(layer "B.Cu")
		(net "SAS2X28_B_HDD0_TX_-")
	)
	(segment
		(start 32.215074 -165.776402)
		(end 32.21736 -165.780466)
		(width 0.09525)
		(layer "B.Cu")
		(net "SAS2X28_B_HDD0_TX_-")
	)
	(segment
		(start 9.955784 -132.327142)
		(end 10.029698 -132.399786)
		(width 0.09525)
		(layer "B.Cu")
		(net "SAS2X28_B_HDD0_TX_-")
	)
	(segment
		(start 124.151898 -318.014858)
		(end 165.857682 -387.075934)
		(width 0.09525)
		(layer "B.Cu")
		(net "SAS2X28_B_HDD0_TX_-")
	)
	(segment
		(start 10.029698 -132.399786)
		(end 10.029698 -132.402834)
		(width 0.09525)
		(layer "B.Cu")
		(net "SAS2X28_B_HDD0_TX_-")
	)
	(segment
		(start 40.075866 -178.79314)
		(end 40.466518 -179.440078)
		(width 0.09525)
		(layer "B.Cu")
		(net "SAS2X28_B_HDD0_TX_-")
	)
	(segment
		(start 165.857682 -387.075934)
		(end 206.451708 -454.296018)
		(width 0.09525)
		(layer "B.Cu")
		(net "SAS2X28_B_HDD0_TX_-")
	)
	(segment
		(start 21.187918 -147.516596)
		(end 31.792672 -165.076886)
		(width 0.09525)
		(layer "B.Cu")
		(net "SAS2X28_B_HDD0_TX_-")
	)
	(segment
		(start 40.466518 -179.440078)
		(end 41.018714 -180.354224)
		(width 0.09525)
		(layer "B.Cu")
		(net "SAS2X28_B_HDD0_TX_-")
	)
	(segment
		(start 217.446352 -472.496896)
		(end 217.447368 -472.498674)
		(width 0.09525)
		(layer "B.Cu")
		(net "SAS2X28_B_HDD0_TX_-")
	)
	(segment
		(start 9.686544 -132.057902)
		(end 9.955784 -132.327142)
		(width 0.09525)
		(layer "B.Cu")
		(net "SAS2X28_B_HDD0_TX_-")
	)
	(segment
		(start 32.21736 -165.780466)
		(end 40.075866 -178.79314)
		(width 0.09525)
		(layer "B.Cu")
		(net "SAS2X28_B_HDD0_TX_-")
	)
	(arc
		(start 217.90533 -473.08262)
		(mid 218.558325 -473.518748)
		(end 219.328492 -473.6719)
		(width 0.09525)
		(layer "B.Cu")
		(net "SAS2X28_B_HDD0_TX_-")
	)
	(arc
		(start 217.447368 -472.498674)
		(mid 217.65877 -472.804434)
		(end 217.90533 -473.08262)
		(width 0.09525)
		(layer "B.Cu")
		(net "SAS2X28_B_HDD0_TX_-")
	)
	(arc
		(start 9.432544 -132.057902)
		(mid 9.559544 -132.005297)
		(end 9.686544 -132.057902)
		(width 0.09525)
		(layer "B.Cu")
		(net "SAS2X28_B_HDD0_TX_-")
	)
	(arc
		(start 219.727018 -473.6719)
		(mid 219.980909 -473.722402)
		(end 220.196156 -473.86621)
		(width 0.09525)
		(layer "B.Cu")
		(net "SAS2X28_B_HDD0_TX_-")
	)
	(arc
		(start 9.270746 -132.448554)
		(mid 9.312799 -132.237141)
		(end 9.432544 -132.057902)
		(width 0.09525)
		(layer "B.Cu")
		(net "SAS2X28_B_HDD0_TX_-")
	)
	(segment
		(start 217.362024 -475.542102)
		(end 217.087704 -475.542102)
		(width 0.09525)
		(layer "F.Cu")
		(net "SAS2X28_B_HDD0_RX_-")
	)
	(segment
		(start 217.598752 -475.400624)
		(end 217.524584 -475.474792)
		(width 0.09525)
		(layer "F.Cu")
		(net "SAS2X28_B_HDD0_RX_-")
	)
	(segment
		(start 218.202256 -475.262702)
		(end 217.931746 -475.262702)
		(width 0.09525)
		(layer "F.Cu")
		(net "SAS2X28_B_HDD0_RX_-")
	)
	(via
		(at 216.788746 -475.243144)
		(size 0.5588)
		(drill 0.3048)
		(layers "F.Cu" "B.Cu")
		(net "SAS2X28_B_HDD0_RX_-")
	)
	(arc
		(start 217.524584 -475.474792)
		(mid 217.450001 -475.524627)
		(end 217.362024 -475.542102)
		(width 0.09525)
		(layer "F.Cu")
		(net "SAS2X28_B_HDD0_RX_-")
	)
	(arc
		(start 217.087704 -475.542102)
		(mid 216.876309 -475.454539)
		(end 216.788746 -475.243144)
		(width 0.09525)
		(layer "F.Cu")
		(net "SAS2X28_B_HDD0_RX_-")
	)
	(arc
		(start 217.931746 -475.262702)
		(mid 217.751534 -475.298548)
		(end 217.598752 -475.400624)
		(width 0.09525)
		(layer "F.Cu")
		(net "SAS2X28_B_HDD0_RX_-")
	)
	(segment
		(start 5.310124 -130.214116)
		(end 5.16382 -130.36042)
		(width 0.09525)
		(layer "B.Cu")
		(net "SAS2X28_B_HDD0_RX_-")
	)
	(segment
		(start 215.899746 -475.7547)
		(end 214.949786 -475.7547)
		(width 0.09525)
		(layer "B.Cu")
		(net "SAS2X28_B_HDD0_RX_-")
	)
	(segment
		(start 7.049516 -132.545328)
		(end 7.04596 -132.539994)
		(width 0.09525)
		(layer "B.Cu")
		(net "SAS2X28_B_HDD0_RX_-")
	)
	(segment
		(start 214.27948 -475.195392)
		(end 207.58785 -463.824574)
		(width 0.09525)
		(layer "B.Cu")
		(net "SAS2X28_B_HDD0_RX_-")
	)
	(segment
		(start 214.375238 -475.357444)
		(end 214.27948 -475.195392)
		(width 0.09525)
		(layer "B.Cu")
		(net "SAS2X28_B_HDD0_RX_-")
	)
	(segment
		(start 4.826 -130.500374)
		(end 4.824476 -130.49885)
		(width 0.09525)
		(layer "B.Cu")
		(net "SAS2X28_B_HDD0_RX_-")
	)
	(segment
		(start 6.908546 -132.07492)
		(end 6.908546 -131.047998)
		(width 0.09525)
		(layer "B.Cu")
		(net "SAS2X28_B_HDD0_RX_-")
	)
	(segment
		(start 6.716014 -130.583178)
		(end 6.433566 -130.30073)
		(width 0.09525)
		(layer "B.Cu")
		(net "SAS2X28_B_HDD0_RX_-")
	)
	(segment
		(start 207.58785 -463.824574)
		(end 48.8696 -194.118484)
		(width 0.09525)
		(layer "B.Cu")
		(net "SAS2X28_B_HDD0_RX_-")
	)
	(segment
		(start 214.435944 -475.460822)
		(end 214.375238 -475.357444)
		(width 0.09525)
		(layer "B.Cu")
		(net "SAS2X28_B_HDD0_RX_-")
	)
	(segment
		(start 48.8696 -194.118484)
		(end 7.119874 -132.63245)
		(width 0.09525)
		(layer "B.Cu")
		(net "SAS2X28_B_HDD0_RX_-")
	)
	(segment
		(start 6.13029 -130.13944)
		(end 5.490464 -130.13944)
		(width 0.09525)
		(layer "B.Cu")
		(net "SAS2X28_B_HDD0_RX_-")
	)
	(segment
		(start 216.788746 -475.243144)
		(end 216.544144 -475.487746)
		(width 0.09525)
		(layer "B.Cu")
		(net "SAS2X28_B_HDD0_RX_-")
	)
	(segment
		(start 4.824476 -130.49885)
		(end 2.811526 -130.49885)
		(width 0.09525)
		(layer "B.Cu")
		(net "SAS2X28_B_HDD0_RX_-")
	)
	(arc
		(start 7.04596 -132.539994)
		(mid 6.943595 -132.317403)
		(end 6.908546 -132.07492)
		(width 0.09525)
		(layer "B.Cu")
		(net "SAS2X28_B_HDD0_RX_-")
	)
	(arc
		(start 214.949786 -475.7547)
		(mid 214.653874 -475.675965)
		(end 214.435944 -475.460822)
		(width 0.09525)
		(layer "B.Cu")
		(net "SAS2X28_B_HDD0_RX_-")
	)
	(arc
		(start 6.330188 -130.222244)
		(mid 6.238474 -130.160963)
		(end 6.13029 -130.13944)
		(width 0.09525)
		(layer "B.Cu")
		(net "SAS2X28_B_HDD0_RX_-")
	)
	(arc
		(start 216.544144 -475.487746)
		(mid 216.248492 -475.685295)
		(end 215.899746 -475.7547)
		(width 0.09525)
		(layer "B.Cu")
		(net "SAS2X28_B_HDD0_RX_-")
	)
	(arc
		(start 6.433566 -130.30073)
		(mid 6.384546 -130.257973)
		(end 6.330188 -130.222244)
		(width 0.09525)
		(layer "B.Cu")
		(net "SAS2X28_B_HDD0_RX_-")
	)
	(arc
		(start 5.490464 -130.13944)
		(mid 5.392874 -130.158852)
		(end 5.310124 -130.214116)
		(width 0.09525)
		(layer "B.Cu")
		(net "SAS2X28_B_HDD0_RX_-")
	)
	(arc
		(start 6.908546 -131.047998)
		(mid 6.858508 -130.79644)
		(end 6.716014 -130.583178)
		(width 0.09525)
		(layer "B.Cu")
		(net "SAS2X28_B_HDD0_RX_-")
	)
	(arc
		(start 7.119874 -132.63245)
		(mid 7.082396 -132.590745)
		(end 7.049516 -132.545328)
		(width 0.09525)
		(layer "B.Cu")
		(net "SAS2X28_B_HDD0_RX_-")
	)
	(arc
		(start 5.16382 -130.36042)
		(mid 5.008827 -130.463983)
		(end 4.826 -130.500374)
		(width 0.09525)
		(layer "B.Cu")
		(net "SAS2X28_B_HDD0_RX_-")
	)
	(segment
		(start 8.762746 -131.830572)
		(end 5.610098 -131.830572)
		(width 0.09525)
		(layer "F.Cu")
		(net "SAS2X28_B_HDD0_TX_+")
	)
	(segment
		(start 223.773746 -473.221558)
		(end 220.510354 -473.221558)
		(width 0.09525)
		(layer "F.Cu")
		(net "SAS2X28_B_HDD0_TX_+")
	)
	(segment
		(start 4.890516 -131.498848)
		(end 3.192526 -131.498848)
		(width 0.09525)
		(layer "F.Cu")
		(net "SAS2X28_B_HDD0_TX_+")
	)
	(segment
		(start 225.396552 -472.986862)
		(end 224.408746 -472.986862)
		(width 0.09525)
		(layer "F.Cu")
		(net "SAS2X28_B_HDD0_TX_+")
	)
	(segment
		(start 4.89204 -131.500372)
		(end 4.890516 -131.498848)
		(width 0.09525)
		(layer "F.Cu")
		(net "SAS2X28_B_HDD0_TX_+")
	)
	(segment
		(start 225.399854 -472.990164)
		(end 225.396552 -472.986862)
		(width 0.09525)
		(layer "F.Cu")
		(net "SAS2X28_B_HDD0_TX_+")
	)
	(via
		(at 9.270746 -131.51485)
		(size 0.5588)
		(drill 0.3048)
		(layers "F.Cu" "B.Cu")
		(net "SAS2X28_B_HDD0_TX_+")
	)
	(via
		(at 220.196156 -472.90736)
		(size 0.5588)
		(drill 0.3048)
		(layers "F.Cu" "B.Cu")
		(net "SAS2X28_B_HDD0_TX_+")
	)
	(arc
		(start 220.510354 -473.221558)
		(mid 220.288182 -473.129532)
		(end 220.196156 -472.90736)
		(width 0.09525)
		(layer "F.Cu")
		(net "SAS2X28_B_HDD0_TX_+")
	)
	(arc
		(start 5.384546 -131.7371)
		(mid 5.351357 -131.705674)
		(end 5.316474 -131.67614)
		(width 0.09525)
		(layer "F.Cu")
		(net "SAS2X28_B_HDD0_TX_+")
	)
	(arc
		(start 224.408746 -472.986862)
		(mid 224.294443 -473.012329)
		(end 224.201736 -473.08389)
		(width 0.09525)
		(layer "F.Cu")
		(net "SAS2X28_B_HDD0_TX_+")
	)
	(arc
		(start 224.085404 -473.151962)
		(mid 223.933404 -473.203899)
		(end 223.773746 -473.221558)
		(width 0.09525)
		(layer "F.Cu")
		(net "SAS2X28_B_HDD0_TX_+")
	)
	(arc
		(start 5.316474 -131.67614)
		(mid 5.121742 -131.546024)
		(end 4.89204 -131.500372)
		(width 0.09525)
		(layer "F.Cu")
		(net "SAS2X28_B_HDD0_TX_+")
	)
	(arc
		(start 9.270746 -131.51485)
		(mid 9.061786 -131.745163)
		(end 8.762746 -131.830572)
		(width 0.09525)
		(layer "F.Cu")
		(net "SAS2X28_B_HDD0_TX_+")
	)
	(arc
		(start 5.565902 -131.82727)
		(mid 5.467867 -131.796976)
		(end 5.384546 -131.7371)
		(width 0.09525)
		(layer "F.Cu")
		(net "SAS2X28_B_HDD0_TX_+")
	)
	(arc
		(start 224.201736 -473.08389)
		(mid 224.145131 -473.120592)
		(end 224.085404 -473.151962)
		(width 0.09525)
		(layer "F.Cu")
		(net "SAS2X28_B_HDD0_TX_+")
	)
	(arc
		(start 5.610098 -131.830572)
		(mid 5.587942 -131.829696)
		(end 5.565902 -131.82727)
		(width 0.09525)
		(layer "F.Cu")
		(net "SAS2X28_B_HDD0_TX_+")
	)
	(segment
		(start 31.979108 -164.746686)
		(end 21.462746 -147.3327)
		(width 0.09525)
		(layer "B.Cu")
		(net "SAS2X28_B_HDD0_TX_+")
	)
	(segment
		(start 10.263886 -132.164074)
		(end 10.261092 -132.16382)
		(width 0.09525)
		(layer "B.Cu")
		(net "SAS2X28_B_HDD0_TX_+")
	)
	(segment
		(start 49.943512 -193.438526)
		(end 44.181014 -184.951878)
		(width 0.09525)
		(layer "B.Cu")
		(net "SAS2X28_B_HDD0_TX_+")
	)
	(segment
		(start 124.4346 -317.84417)
		(end 112.668812 -298.3611)
		(width 0.09525)
		(layer "B.Cu")
		(net "SAS2X28_B_HDD0_TX_+")
	)
	(segment
		(start 44.181014 -184.951878)
		(end 41.437814 -180.409088)
		(width 0.09525)
		(layer "B.Cu")
		(net "SAS2X28_B_HDD0_TX_+")
	)
	(segment
		(start 101.42601 -279.74417)
		(end 86.128098 -254.411988)
		(width 0.09525)
		(layer "B.Cu")
		(net "SAS2X28_B_HDD0_TX_+")
	)
	(segment
		(start 216.998042 -471.120216)
		(end 207.432148 -455.27976)
		(width 0.09525)
		(layer "B.Cu")
		(net "SAS2X28_B_HDD0_TX_+")
	)
	(segment
		(start 86.128098 -254.411988)
		(end 74.566018 -235.26623)
		(width 0.09525)
		(layer "B.Cu")
		(net "SAS2X28_B_HDD0_TX_+")
	)
	(segment
		(start 41.437814 -180.409088)
		(end 40.74922 -179.269136)
		(width 0.09525)
		(layer "B.Cu")
		(net "SAS2X28_B_HDD0_TX_+")
	)
	(segment
		(start 217.562684 -472.051888)
		(end 216.998042 -471.120216)
		(width 0.09525)
		(layer "B.Cu")
		(net "SAS2X28_B_HDD0_TX_+")
	)
	(segment
		(start 217.7288 -472.3257)
		(end 217.562684 -472.051888)
		(width 0.09525)
		(layer "B.Cu")
		(net "SAS2X28_B_HDD0_TX_+")
	)
	(segment
		(start 10.261092 -132.16382)
		(end 10.187432 -132.09143)
		(width 0.09525)
		(layer "B.Cu")
		(net "SAS2X28_B_HDD0_TX_+")
	)
	(segment
		(start 74.28357 -234.798616)
		(end 49.943512 -193.438526)
		(width 0.09525)
		(layer "B.Cu")
		(net "SAS2X28_B_HDD0_TX_+")
	)
	(segment
		(start 40.74922 -179.269136)
		(end 40.358822 -178.622452)
		(width 0.09525)
		(layer "B.Cu")
		(net "SAS2X28_B_HDD0_TX_+")
	)
	(segment
		(start 220.196156 -472.90736)
		(end 220.196156 -473.109036)
		(width 0.09525)
		(layer "B.Cu")
		(net "SAS2X28_B_HDD0_TX_+")
	)
	(segment
		(start 207.432148 -455.27976)
		(end 206.73441 -454.12533)
		(width 0.09525)
		(layer "B.Cu")
		(net "SAS2X28_B_HDD0_TX_+")
	)
	(segment
		(start 206.73441 -454.12533)
		(end 166.140384 -386.905246)
		(width 0.09525)
		(layer "B.Cu")
		(net "SAS2X28_B_HDD0_TX_+")
	)
	(segment
		(start 21.462746 -147.3327)
		(end 10.263886 -132.164074)
		(width 0.09525)
		(layer "B.Cu")
		(net "SAS2X28_B_HDD0_TX_+")
	)
	(segment
		(start 166.140384 -386.905246)
		(end 124.4346 -317.84417)
		(width 0.09525)
		(layer "B.Cu")
		(net "SAS2X28_B_HDD0_TX_+")
	)
	(segment
		(start 112.668812 -298.3611)
		(end 101.42601 -279.74417)
		(width 0.09525)
		(layer "B.Cu")
		(net "SAS2X28_B_HDD0_TX_+")
	)
	(segment
		(start 219.963746 -473.341446)
		(end 219.328492 -473.341446)
		(width 0.09525)
		(layer "B.Cu")
		(net "SAS2X28_B_HDD0_TX_+")
	)
	(segment
		(start 74.566018 -235.26623)
		(end 74.28357 -234.798616)
		(width 0.09525)
		(layer "B.Cu")
		(net "SAS2X28_B_HDD0_TX_+")
	)
	(segment
		(start 32.500316 -165.609778)
		(end 31.979108 -164.746686)
		(width 0.09525)
		(layer "B.Cu")
		(net "SAS2X28_B_HDD0_TX_+")
	)
	(segment
		(start 10.187432 -132.09143)
		(end 9.85139 -131.755388)
		(width 0.09525)
		(layer "B.Cu")
		(net "SAS2X28_B_HDD0_TX_+")
	)
	(segment
		(start 40.358822 -178.622452)
		(end 32.500316 -165.609778)
		(width 0.09525)
		(layer "B.Cu")
		(net "SAS2X28_B_HDD0_TX_+")
	)
	(arc
		(start 218.13901 -472.84894)
		(mid 217.918162 -472.599663)
		(end 217.7288 -472.3257)
		(width 0.09525)
		(layer "B.Cu")
		(net "SAS2X28_B_HDD0_TX_+")
	)
	(arc
		(start 220.196156 -473.109036)
		(mid 220.128085 -473.273375)
		(end 219.963746 -473.341446)
		(width 0.09525)
		(layer "B.Cu")
		(net "SAS2X28_B_HDD0_TX_+")
	)
	(arc
		(start 219.328492 -473.341446)
		(mid 218.68478 -473.213457)
		(end 218.13901 -472.84894)
		(width 0.09525)
		(layer "B.Cu")
		(net "SAS2X28_B_HDD0_TX_+")
	)
	(arc
		(start 9.85139 -131.755388)
		(mid 9.584988 -131.577384)
		(end 9.270746 -131.51485)
		(width 0.09525)
		(layer "B.Cu")
		(net "SAS2X28_B_HDD0_TX_+")
	)
	(segment
		(start 102.679246 -14.2367)
		(end 103.631746 -14.2367)
		(width 0.111252)
		(layer "F.Cu")
		(net "SW_PWR_HDD14")
	)
	(segment
		(start 102.679246 -12.7762)
		(end 102.679246 -12.9667)
		(width 0.111252)
		(layer "F.Cu")
		(net "SW_PWR_HDD14")
	)
	(segment
		(start 103.250746 -11.1887)
		(end 103.250746 -12.2047)
		(width 0.111252)
		(layer "F.Cu")
		(net "SW_PWR_HDD14")
	)
	(segment
		(start 102.679246 -12.9667)
		(end 103.377746 -12.9667)
		(width 0.111252)
		(layer "F.Cu")
		(net "SW_PWR_HDD14")
	)
	(segment
		(start 101.599746 -10.8712)
		(end 102.933246 -10.8712)
		(width 0.111252)
		(layer "F.Cu")
		(net "SW_PWR_HDD14")
	)
	(segment
		(start 103.250746 -12.2047)
		(end 102.679246 -12.7762)
		(width 0.111252)
		(layer "F.Cu")
		(net "SW_PWR_HDD14")
	)
	(segment
		(start 102.933246 -10.8712)
		(end 103.250746 -11.1887)
		(width 0.111252)
		(layer "F.Cu")
		(net "SW_PWR_HDD14")
	)
	(segment
		(start 103.377746 -12.9667)
		(end 104.139746 -13.7287)
		(width 0.111252)
		(layer "F.Cu")
		(net "SW_PWR_HDD14")
	)
	(segment
		(start 103.631746 -14.2367)
		(end 104.139746 -13.7287)
		(width 0.111252)
		(layer "F.Cu")
		(net "SW_PWR_HDD14")
	)
	(via
		(at 104.139746 -13.7287)
		(size 0.7112)
		(drill 0.3556)
		(layers "F.Cu" "B.Cu")
		(net "SW_PWR_HDD14")
	)
	(segment
		(start 8.438896 -416.770312)
		(end 8.89 -416.770312)
		(width 0.09525)
		(layer "F.Cu")
		(net "SAS2X28_A_HDD0_RX_-")
	)
	(segment
		(start 9.645396 -417.213542)
		(end 13.70965 -421.277542)
		(width 0.09525)
		(layer "F.Cu")
		(net "SAS2X28_A_HDD0_RX_-")
	)
	(segment
		(start 210.6422 -466.479382)
		(end 210.6422 -466.479636)
		(width 0.09525)
		(layer "F.Cu")
		(net "SAS2X28_A_HDD0_RX_-")
	)
	(segment
		(start 33.146492 -462.673954)
		(end 33.224216 -462.59623)
		(width 0.09525)
		(layer "F.Cu")
		(net "SAS2X28_A_HDD0_RX_-")
	)
	(segment
		(start 32.511746 -463.007964)
		(end 32.511746 -463.008218)
		(width 0.09525)
		(layer "F.Cu")
		(net "SAS2X28_A_HDD0_RX_-")
	)
	(segment
		(start 213.491826 -468.39632)
		(end 213.49208 -468.39632)
		(width 0.09525)
		(layer "F.Cu")
		(net "SAS2X28_A_HDD0_RX_-")
	)
	(segment
		(start 9.422892 -416.991038)
		(end 9.645396 -417.213542)
		(width 0.09525)
		(layer "F.Cu")
		(net "SAS2X28_A_HDD0_RX_-")
	)
	(segment
		(start 13.70965 -421.277542)
		(end 14.58849 -422.156128)
		(width 0.09525)
		(layer "F.Cu")
		(net "SAS2X28_A_HDD0_RX_-")
	)
	(segment
		(start 34.263838 -462.165446)
		(end 34.264092 -462.1657)
		(width 0.09525)
		(layer "F.Cu")
		(net "SAS2X28_A_HDD0_RX_-")
	)
	(segment
		(start 215.773254 -469.598502)
		(end 217.042746 -469.598502)
		(width 0.09525)
		(layer "F.Cu")
		(net "SAS2X28_A_HDD0_RX_-")
	)
	(segment
		(start 73.406 -466.479382)
		(end 210.6422 -466.479382)
		(width 0.09525)
		(layer "F.Cu")
		(net "SAS2X28_A_HDD0_RX_-")
	)
	(segment
		(start 14.871446 -422.838626)
		(end 14.871446 -460.596234)
		(width 0.09525)
		(layer "F.Cu")
		(net "SAS2X28_A_HDD0_RX_-")
	)
	(segment
		(start 34.264092 -462.1657)
		(end 67.178428 -462.1657)
		(width 0.09525)
		(layer "F.Cu")
		(net "SAS2X28_A_HDD0_RX_-")
	)
	(segment
		(start 34.263584 -462.1657)
		(end 34.263838 -462.165446)
		(width 0.09525)
		(layer "F.Cu")
		(net "SAS2X28_A_HDD0_RX_-")
	)
	(segment
		(start 212.234526 -467.138512)
		(end 213.491826 -468.39632)
		(width 0.09525)
		(layer "F.Cu")
		(net "SAS2X28_A_HDD0_RX_-")
	)
	(segment
		(start 218.068398 -469.173814)
		(end 218.202256 -469.039702)
		(width 0.09525)
		(layer "F.Cu")
		(net "SAS2X28_A_HDD0_RX_-")
	)
	(segment
		(start 33.025334 -462.795366)
		(end 33.146492 -462.673954)
		(width 0.09525)
		(layer "F.Cu")
		(net "SAS2X28_A_HDD0_RX_-")
	)
	(segment
		(start 69.067426 -462.94802)
		(end 72.027796 -465.908136)
		(width 0.09525)
		(layer "F.Cu")
		(net "SAS2X28_A_HDD0_RX_-")
	)
	(segment
		(start 213.49208 -468.39632)
		(end 213.930992 -468.835232)
		(width 0.09525)
		(layer "F.Cu")
		(net "SAS2X28_A_HDD0_RX_-")
	)
	(segment
		(start 7.649464 -417.577778)
		(end 7.675372 -417.379404)
		(width 0.09525)
		(layer "F.Cu")
		(net "SAS2X28_A_HDD0_RX_-")
	)
	(segment
		(start 18.8976 -463.007964)
		(end 32.511746 -463.007964)
		(width 0.09525)
		(layer "F.Cu")
		(net "SAS2X28_A_HDD0_RX_-")
	)
	(via
		(at 7.525004 -417.830508)
		(size 0.5588)
		(drill 0.3048)
		(layers "F.Cu" "B.Cu")
		(net "SAS2X28_A_HDD0_RX_-")
	)
	(arc
		(start 68.365878 -462.444084)
		(mid 68.737141 -462.667526)
		(end 69.067426 -462.94802)
		(width 0.09525)
		(layer "F.Cu")
		(net "SAS2X28_A_HDD0_RX_-")
	)
	(arc
		(start 14.58849 -422.156128)
		(mid 14.797855 -422.469231)
		(end 14.871446 -422.838626)
		(width 0.09525)
		(layer "F.Cu")
		(net "SAS2X28_A_HDD0_RX_-")
	)
	(arc
		(start 14.871446 -460.596234)
		(mid 14.970594 -461.094684)
		(end 15.252954 -461.517238)
		(width 0.09525)
		(layer "F.Cu")
		(net "SAS2X28_A_HDD0_RX_-")
	)
	(arc
		(start 8.89 -416.770312)
		(mid 9.178411 -416.827663)
		(end 9.422892 -416.991038)
		(width 0.09525)
		(layer "F.Cu")
		(net "SAS2X28_A_HDD0_RX_-")
	)
	(arc
		(start 7.856982 -417.011104)
		(mid 8.123981 -416.832794)
		(end 8.438896 -416.770312)
		(width 0.09525)
		(layer "F.Cu")
		(net "SAS2X28_A_HDD0_RX_-")
	)
	(arc
		(start 7.675372 -417.379404)
		(mid 7.735685 -417.180217)
		(end 7.856982 -417.011104)
		(width 0.09525)
		(layer "F.Cu")
		(net "SAS2X28_A_HDD0_RX_-")
	)
	(arc
		(start 210.6422 -466.479636)
		(mid 211.503873 -466.650735)
		(end 212.234526 -467.138512)
		(width 0.09525)
		(layer "F.Cu")
		(net "SAS2X28_A_HDD0_RX_-")
	)
	(arc
		(start 15.252954 -461.517238)
		(mid 16.925293 -462.629296)
		(end 18.8976 -463.007964)
		(width 0.09525)
		(layer "F.Cu")
		(net "SAS2X28_A_HDD0_RX_-")
	)
	(arc
		(start 67.178428 -462.1657)
		(mid 67.788249 -462.236231)
		(end 68.365878 -462.444084)
		(width 0.09525)
		(layer "F.Cu")
		(net "SAS2X28_A_HDD0_RX_-")
	)
	(arc
		(start 7.525004 -417.830508)
		(mid 7.608134 -417.714435)
		(end 7.649464 -417.577778)
		(width 0.09525)
		(layer "F.Cu")
		(net "SAS2X28_A_HDD0_RX_-")
	)
	(arc
		(start 217.042746 -469.598502)
		(mid 217.597821 -469.488184)
		(end 218.068398 -469.173814)
		(width 0.09525)
		(layer "F.Cu")
		(net "SAS2X28_A_HDD0_RX_-")
	)
	(arc
		(start 33.224216 -462.59623)
		(mid 33.701082 -462.277598)
		(end 34.263584 -462.1657)
		(width 0.09525)
		(layer "F.Cu")
		(net "SAS2X28_A_HDD0_RX_-")
	)
	(arc
		(start 32.511746 -463.008218)
		(mid 32.789703 -462.952853)
		(end 33.025334 -462.795366)
		(width 0.09525)
		(layer "F.Cu")
		(net "SAS2X28_A_HDD0_RX_-")
	)
	(arc
		(start 213.930992 -468.835232)
		(mid 214.776201 -469.400109)
		(end 215.773254 -469.598502)
		(width 0.09525)
		(layer "F.Cu")
		(net "SAS2X28_A_HDD0_RX_-")
	)
	(arc
		(start 72.027796 -465.908136)
		(mid 72.660078 -466.330833)
		(end 73.406 -466.479382)
		(width 0.09525)
		(layer "F.Cu")
		(net "SAS2X28_A_HDD0_RX_-")
	)
	(segment
		(start 4.919218 -414.49879)
		(end 2.811526 -414.49879)
		(width 0.09525)
		(layer "B.Cu")
		(net "SAS2X28_A_HDD0_RX_-")
	)
	(segment
		(start 7.766812 -416.1917)
		(end 7.766812 -416.183826)
		(width 0.09525)
		(layer "B.Cu")
		(net "SAS2X28_A_HDD0_RX_-")
	)
	(segment
		(start 6.560566 -414.456626)
		(end 6.472428 -414.368742)
		(width 0.09525)
		(layer "B.Cu")
		(net "SAS2X28_A_HDD0_RX_-")
	)
	(segment
		(start 7.393432 -415.289238)
		(end 7.386066 -415.282126)
		(width 0.09525)
		(layer "B.Cu")
		(net "SAS2X28_A_HDD0_RX_-")
	)
	(segment
		(start 7.767066 -416.191446)
		(end 7.766812 -416.1917)
		(width 0.09525)
		(layer "B.Cu")
		(net "SAS2X28_A_HDD0_RX_-")
	)
	(segment
		(start 7.386066 -415.282126)
		(end 6.560566 -414.456626)
		(width 0.09525)
		(layer "B.Cu")
		(net "SAS2X28_A_HDD0_RX_-")
	)
	(segment
		(start 5.355844 -414.277556)
		(end 5.2832 -414.3502)
		(width 0.09525)
		(layer "B.Cu")
		(net "SAS2X28_A_HDD0_RX_-")
	)
	(segment
		(start 7.767066 -417.246054)
		(end 7.767066 -416.191446)
		(width 0.09525)
		(layer "B.Cu")
		(net "SAS2X28_A_HDD0_RX_-")
	)
	(segment
		(start 6.050534 -414.164526)
		(end 5.62864 -414.164526)
		(width 0.09525)
		(layer "B.Cu")
		(net "SAS2X28_A_HDD0_RX_-")
	)
	(segment
		(start 4.920742 -414.500314)
		(end 4.919218 -414.49879)
		(width 0.09525)
		(layer "B.Cu")
		(net "SAS2X28_A_HDD0_RX_-")
	)
	(arc
		(start 7.760716 -416.063176)
		(mid 7.643934 -415.644482)
		(end 7.393432 -415.289238)
		(width 0.09525)
		(layer "B.Cu")
		(net "SAS2X28_A_HDD0_RX_-")
	)
	(arc
		(start 7.766812 -416.183826)
		(mid 7.76529 -416.123424)
		(end 7.760716 -416.063176)
		(width 0.09525)
		(layer "B.Cu")
		(net "SAS2X28_A_HDD0_RX_-")
	)
	(arc
		(start 5.2832 -414.3502)
		(mid 5.116903 -414.461316)
		(end 4.920742 -414.500314)
		(width 0.09525)
		(layer "B.Cu")
		(net "SAS2X28_A_HDD0_RX_-")
	)
	(arc
		(start 5.62864 -414.164526)
		(mid 5.480991 -414.193895)
		(end 5.355844 -414.277556)
		(width 0.09525)
		(layer "B.Cu")
		(net "SAS2X28_A_HDD0_RX_-")
	)
	(arc
		(start 6.472428 -414.368742)
		(mid 6.278767 -414.230906)
		(end 6.050534 -414.164526)
		(width 0.09525)
		(layer "B.Cu")
		(net "SAS2X28_A_HDD0_RX_-")
	)
	(arc
		(start 7.525004 -417.830508)
		(mid 7.704176 -417.562358)
		(end 7.767066 -417.246054)
		(width 0.09525)
		(layer "B.Cu")
		(net "SAS2X28_A_HDD0_RX_-")
	)
	(segment
		(start 35.940746 -112.741202)
		(end 35.112198 -112.741202)
		(width 0.111252)
		(layer "F.Cu")
		(net "SW_PWR_HDD13")
	)
	(segment
		(start 35.112198 -112.741202)
		(end 34.925 -112.9284)
		(width 0.111252)
		(layer "F.Cu")
		(net "SW_PWR_HDD13")
	)
	(segment
		(start 38.353746 -112.741202)
		(end 37.210746 -112.741202)
		(width 0.111252)
		(layer "F.Cu")
		(net "SW_PWR_HDD13")
	)
	(segment
		(start 37.210746 -112.741202)
		(end 35.940746 -112.741202)
		(width 0.111252)
		(layer "F.Cu")
		(net "SW_PWR_HDD13")
	)
	(via
		(at 34.925 -112.9284)
		(size 0.7112)
		(drill 0.3556)
		(layers "F.Cu" "B.Cu")
		(net "SW_PWR_HDD13")
	)
	(segment
		(start 26.737056 -366.947704)
		(end 26.669746 -367.015014)
		(width 0.09525)
		(layer "F.Cu")
		(net "SAS2X28_A_HDD6_RX_+")
	)
	(segment
		(start 32.42056 -366.964214)
		(end 32.37865 -366.922304)
		(width 0.09525)
		(layer "F.Cu")
		(net "SAS2X28_A_HDD6_RX_+")
	)
	(segment
		(start 32.277812 -366.880648)
		(end 26.899108 -366.880648)
		(width 0.09525)
		(layer "F.Cu")
		(net "SAS2X28_A_HDD6_RX_+")
	)
	(via
		(at 26.669746 -367.015014)
		(size 0.5588)
		(drill 0.3048)
		(layers "F.Cu" "B.Cu")
		(net "SAS2X28_A_HDD6_RX_+")
	)
	(arc
		(start 32.37865 -366.922304)
		(mid 32.332357 -366.891498)
		(end 32.277812 -366.880648)
		(width 0.09525)
		(layer "F.Cu")
		(net "SAS2X28_A_HDD6_RX_+")
	)
	(arc
		(start 26.899108 -366.880648)
		(mid 26.811418 -366.898073)
		(end 26.737056 -366.947704)
		(width 0.09525)
		(layer "F.Cu")
		(net "SAS2X28_A_HDD6_RX_+")
	)
	(segment
		(start 11.957558 -384.853942)
		(end 11.957812 -384.853434)
		(width 0.09525)
		(layer "B.Cu")
		(net "SAS2X28_A_HDD6_RX_+")
	)
	(segment
		(start 28.156916 -366.807496)
		(end 28.136088 -366.828324)
		(width 0.09525)
		(layer "B.Cu")
		(net "SAS2X28_A_HDD6_RX_+")
	)
	(segment
		(start 10.058146 -386.753354)
		(end 11.957558 -384.853942)
		(width 0.09525)
		(layer "B.Cu")
		(net "SAS2X28_A_HDD6_RX_+")
	)
	(segment
		(start 2.811526 -383.498852)
		(end 4.93776 -383.498852)
		(width 0.09525)
		(layer "B.Cu")
		(net "SAS2X28_A_HDD6_RX_+")
	)
	(segment
		(start 7.05612 -384.9497)
		(end 7.05612 -385.711446)
		(width 0.09525)
		(layer "B.Cu")
		(net "SAS2X28_A_HDD6_RX_+")
	)
	(segment
		(start 7.46633 -386.70103)
		(end 7.732014 -386.966714)
		(width 0.09525)
		(layer "B.Cu")
		(net "SAS2X28_A_HDD6_RX_+")
	)
	(segment
		(start 8.947658 -387.286754)
		(end 8.947658 -387.2865)
		(width 0.09525)
		(layer "B.Cu")
		(net "SAS2X28_A_HDD6_RX_+")
	)
	(segment
		(start 13.36929 -376.82805)
		(end 14.180566 -376.01652)
		(width 0.09525)
		(layer "B.Cu")
		(net "SAS2X28_A_HDD6_RX_+")
	)
	(segment
		(start 13.311632 -376.885962)
		(end 13.311886 -376.885708)
		(width 0.09525)
		(layer "B.Cu")
		(net "SAS2X28_A_HDD6_RX_+")
	)
	(segment
		(start 14.180566 -376.01652)
		(end 25.143714 -365.053372)
		(width 0.09525)
		(layer "B.Cu")
		(net "SAS2X28_A_HDD6_RX_+")
	)
	(segment
		(start 12.496546 -383.5527)
		(end 12.496546 -378.8537)
		(width 0.09525)
		(layer "B.Cu")
		(net "SAS2X28_A_HDD6_RX_+")
	)
	(segment
		(start 6.660134 -384.15087)
		(end 6.713728 -384.204464)
		(width 0.09525)
		(layer "B.Cu")
		(net "SAS2X28_A_HDD6_RX_+")
	)
	(segment
		(start 6.653276 -384.143758)
		(end 6.660134 -384.15087)
		(width 0.09525)
		(layer "B.Cu")
		(net "SAS2X28_A_HDD6_RX_+")
	)
	(segment
		(start 6.713728 -384.204464)
		(end 6.771386 -384.261868)
		(width 0.09525)
		(layer "B.Cu")
		(net "SAS2X28_A_HDD6_RX_+")
	)
	(segment
		(start 27.685746 -367.015014)
		(end 26.669746 -367.015014)
		(width 0.09525)
		(layer "B.Cu")
		(net "SAS2X28_A_HDD6_RX_+")
	)
	(segment
		(start 8.504682 -387.286754)
		(end 8.947658 -387.286754)
		(width 0.09525)
		(layer "B.Cu")
		(net "SAS2X28_A_HDD6_RX_+")
	)
	(segment
		(start 26.42743 -364.4265)
		(end 27.686 -364.4265)
		(width 0.09525)
		(layer "B.Cu")
		(net "SAS2X28_A_HDD6_RX_+")
	)
	(segment
		(start 25.143714 -365.053372)
		(end 25.30602 -364.890812)
		(width 0.09525)
		(layer "B.Cu")
		(net "SAS2X28_A_HDD6_RX_+")
	)
	(segment
		(start 27.685746 -367.01476)
		(end 27.685746 -367.015014)
		(width 0.09525)
		(layer "B.Cu")
		(net "SAS2X28_A_HDD6_RX_+")
	)
	(segment
		(start 9.93267 -386.878576)
		(end 10.058146 -386.753354)
		(width 0.09525)
		(layer "B.Cu")
		(net "SAS2X28_A_HDD6_RX_+")
	)
	(segment
		(start 28.269946 -365.010446)
		(end 28.269946 -366.5347)
		(width 0.09525)
		(layer "B.Cu")
		(net "SAS2X28_A_HDD6_RX_+")
	)
	(segment
		(start 5.678678 -383.8067)
		(end 5.841746 -383.8067)
		(width 0.09525)
		(layer "B.Cu")
		(net "SAS2X28_A_HDD6_RX_+")
	)
	(segment
		(start 13.311886 -376.885708)
		(end 13.36929 -376.82805)
		(width 0.09525)
		(layer "B.Cu")
		(net "SAS2X28_A_HDD6_RX_+")
	)
	(segment
		(start 4.93776 -383.498852)
		(end 4.939284 -383.500376)
		(width 0.09525)
		(layer "B.Cu")
		(net "SAS2X28_A_HDD6_RX_+")
	)
	(arc
		(start 6.771386 -384.261868)
		(mid 6.982167 -384.577463)
		(end 7.05612 -384.9497)
		(width 0.09525)
		(layer "B.Cu")
		(net "SAS2X28_A_HDD6_RX_+")
	)
	(arc
		(start 8.947658 -387.2865)
		(mid 9.480712 -387.180469)
		(end 9.93267 -386.878576)
		(width 0.09525)
		(layer "B.Cu")
		(net "SAS2X28_A_HDD6_RX_+")
	)
	(arc
		(start 5.841746 -383.8067)
		(mid 6.281157 -383.894221)
		(end 6.653276 -384.143758)
		(width 0.09525)
		(layer "B.Cu")
		(net "SAS2X28_A_HDD6_RX_+")
	)
	(arc
		(start 5.255006 -383.631186)
		(mid 5.449388 -383.761068)
		(end 5.678678 -383.8067)
		(width 0.09525)
		(layer "B.Cu")
		(net "SAS2X28_A_HDD6_RX_+")
	)
	(arc
		(start 28.136088 -366.828324)
		(mid 27.929469 -366.966382)
		(end 27.685746 -367.01476)
		(width 0.09525)
		(layer "B.Cu")
		(net "SAS2X28_A_HDD6_RX_+")
	)
	(arc
		(start 4.939284 -383.500376)
		(mid 5.110164 -383.534366)
		(end 5.255006 -383.631186)
		(width 0.09525)
		(layer "B.Cu")
		(net "SAS2X28_A_HDD6_RX_+")
	)
	(arc
		(start 12.496546 -383.553208)
		(mid 12.496546 -383.552954)
		(end 12.496546 -383.5527)
		(width 0.09525)
		(layer "B.Cu")
		(net "SAS2X28_A_HDD6_RX_+")
	)
	(arc
		(start 7.05612 -385.711446)
		(mid 7.162786 -386.247042)
		(end 7.46633 -386.70103)
		(width 0.09525)
		(layer "B.Cu")
		(net "SAS2X28_A_HDD6_RX_+")
	)
	(arc
		(start 25.30602 -364.890812)
		(mid 25.820542 -364.547112)
		(end 26.42743 -364.4265)
		(width 0.09525)
		(layer "B.Cu")
		(net "SAS2X28_A_HDD6_RX_+")
	)
	(arc
		(start 7.732014 -386.966714)
		(mid 8.086517 -387.203585)
		(end 8.504682 -387.286754)
		(width 0.09525)
		(layer "B.Cu")
		(net "SAS2X28_A_HDD6_RX_+")
	)
	(arc
		(start 28.269946 -366.5347)
		(mid 28.240577 -366.682349)
		(end 28.156916 -366.807496)
		(width 0.09525)
		(layer "B.Cu")
		(net "SAS2X28_A_HDD6_RX_+")
	)
	(arc
		(start 27.686 -364.4265)
		(mid 28.098912 -364.597534)
		(end 28.269946 -365.010446)
		(width 0.09525)
		(layer "B.Cu")
		(net "SAS2X28_A_HDD6_RX_+")
	)
	(arc
		(start 12.496546 -378.8537)
		(mid 12.708376 -377.788759)
		(end 13.311632 -376.885962)
		(width 0.09525)
		(layer "B.Cu")
		(net "SAS2X28_A_HDD6_RX_+")
	)
	(arc
		(start 11.957812 -384.853434)
		(mid 12.356545 -384.256927)
		(end 12.496546 -383.553208)
		(width 0.09525)
		(layer "B.Cu")
		(net "SAS2X28_A_HDD6_RX_+")
	)
	(segment
		(start 34.512504 -459.783688)
		(end 32.638492 -461.6577)
		(width 0.09525)
		(layer "F.Cu")
		(net "SAS2X28_A_HDD0_TX_+")
	)
	(segment
		(start 223.249998 -465.07019)
		(end 221.758256 -465.07019)
		(width 0.09525)
		(layer "F.Cu")
		(net "SAS2X28_A_HDD0_TX_+")
	)
	(segment
		(start 15.092172 -420.40302)
		(end 10.964926 -416.275774)
		(width 0.09525)
		(layer "F.Cu")
		(net "SAS2X28_A_HDD0_TX_+")
	)
	(segment
		(start 72.470518 -464.785964)
		(end 67.523868 -459.839314)
		(width 0.09525)
		(layer "F.Cu")
		(net "SAS2X28_A_HDD0_TX_+")
	)
	(segment
		(start 15.811246 -460.054198)
		(end 15.811246 -421.787574)
		(width 0.09525)
		(layer "F.Cu")
		(net "SAS2X28_A_HDD0_TX_+")
	)
	(segment
		(start 15.341092 -420.651432)
		(end 15.092172 -420.40302)
		(width 0.09525)
		(layer "F.Cu")
		(net "SAS2X28_A_HDD0_TX_+")
	)
	(segment
		(start 65.598548 -459.0415)
		(end 36.30422 -459.0415)
		(width 0.09525)
		(layer "F.Cu")
		(net "SAS2X28_A_HDD0_TX_+")
	)
	(segment
		(start 221.288864 -465.539582)
		(end 74.28992 -465.539582)
		(width 0.09525)
		(layer "F.Cu")
		(net "SAS2X28_A_HDD0_TX_+")
	)
	(segment
		(start 9.889998 -415.830512)
		(end 5.461 -415.830512)
		(width 0.09525)
		(layer "F.Cu")
		(net "SAS2X28_A_HDD0_TX_+")
	)
	(segment
		(start 4.66217 -415.498788)
		(end 3.192526 -415.498788)
		(width 0.09525)
		(layer "F.Cu")
		(net "SAS2X28_A_HDD0_TX_+")
	)
	(segment
		(start 4.663694 -415.500312)
		(end 4.66217 -415.498788)
		(width 0.09525)
		(layer "F.Cu")
		(net "SAS2X28_A_HDD0_TX_+")
	)
	(segment
		(start 31.648146 -462.068164)
		(end 18.8976 -462.068164)
		(width 0.09525)
		(layer "F.Cu")
		(net "SAS2X28_A_HDD0_TX_+")
	)
	(arc
		(start 16.107156 -460.902304)
		(mid 15.887376 -460.50331)
		(end 15.811246 -460.054198)
		(width 0.09525)
		(layer "F.Cu")
		(net "SAS2X28_A_HDD0_TX_+")
	)
	(arc
		(start 221.315534 -465.53755)
		(mid 221.302233 -465.539019)
		(end 221.288864 -465.539582)
		(width 0.09525)
		(layer "F.Cu")
		(net "SAS2X28_A_HDD0_TX_+")
	)
	(arc
		(start 221.758256 -465.07019)
		(mid 221.566977 -465.149421)
		(end 221.487746 -465.3407)
		(width 0.09525)
		(layer "F.Cu")
		(net "SAS2X28_A_HDD0_TX_+")
	)
	(arc
		(start 5.197856 -415.721546)
		(mid 4.95278 -415.557792)
		(end 4.663694 -415.500312)
		(width 0.09525)
		(layer "F.Cu")
		(net "SAS2X28_A_HDD0_TX_+")
	)
	(arc
		(start 221.487746 -465.3407)
		(mid 221.465618 -465.431748)
		(end 221.40418 -465.502498)
		(width 0.09525)
		(layer "F.Cu")
		(net "SAS2X28_A_HDD0_TX_+")
	)
	(arc
		(start 15.811246 -421.787574)
		(mid 15.689155 -421.172749)
		(end 15.341092 -420.651432)
		(width 0.09525)
		(layer "F.Cu")
		(net "SAS2X28_A_HDD0_TX_+")
	)
	(arc
		(start 32.638492 -461.6577)
		(mid 32.184147 -461.96144)
		(end 31.648146 -462.068164)
		(width 0.09525)
		(layer "F.Cu")
		(net "SAS2X28_A_HDD0_TX_+")
	)
	(arc
		(start 67.52336 -459.838806)
		(mid 66.640249 -459.24873)
		(end 65.598548 -459.0415)
		(width 0.09525)
		(layer "F.Cu")
		(net "SAS2X28_A_HDD0_TX_+")
	)
	(arc
		(start 36.30422 -459.0415)
		(mid 35.334537 -459.234382)
		(end 34.512504 -459.783688)
		(width 0.09525)
		(layer "F.Cu")
		(net "SAS2X28_A_HDD0_TX_+")
	)
	(arc
		(start 18.8976 -462.068164)
		(mid 17.385503 -461.764977)
		(end 16.107156 -460.902304)
		(width 0.09525)
		(layer "F.Cu")
		(net "SAS2X28_A_HDD0_TX_+")
	)
	(arc
		(start 10.964926 -416.275774)
		(mid 10.471745 -415.946241)
		(end 9.889998 -415.830512)
		(width 0.09525)
		(layer "F.Cu")
		(net "SAS2X28_A_HDD0_TX_+")
	)
	(arc
		(start 221.40418 -465.502498)
		(mid 221.361995 -465.525438)
		(end 221.315534 -465.53755)
		(width 0.09525)
		(layer "F.Cu")
		(net "SAS2X28_A_HDD0_TX_+")
	)
	(arc
		(start 74.28992 -465.539582)
		(mid 73.305268 -465.343723)
		(end 72.470518 -464.785964)
		(width 0.09525)
		(layer "F.Cu")
		(net "SAS2X28_A_HDD0_TX_+")
	)
	(arc
		(start 67.523868 -459.839314)
		(mid 67.523614 -459.83906)
		(end 67.52336 -459.838806)
		(width 0.09525)
		(layer "F.Cu")
		(net "SAS2X28_A_HDD0_TX_+")
	)
	(arc
		(start 5.461 -415.830512)
		(mid 5.3186 -415.802187)
		(end 5.197856 -415.721546)
		(width 0.09525)
		(layer "F.Cu")
		(net "SAS2X28_A_HDD0_TX_+")
	)
	(segment
		(start 72.236838 -465.019644)
		(end 67.290188 -460.072994)
		(width 0.09525)
		(layer "F.Cu")
		(net "SAS2X28_A_HDD0_TX_-")
	)
	(segment
		(start 15.107666 -420.885112)
		(end 14.858746 -420.6367)
		(width 0.09525)
		(layer "F.Cu")
		(net "SAS2X28_A_HDD0_TX_-")
	)
	(segment
		(start 4.627118 -416.50031)
		(end 4.625594 -416.498786)
		(width 0.09525)
		(layer "F.Cu")
		(net "SAS2X28_A_HDD0_TX_-")
	)
	(segment
		(start 65.598294 -459.3717)
		(end 36.304474 -459.3717)
		(width 0.09525)
		(layer "F.Cu")
		(net "SAS2X28_A_HDD0_TX_-")
	)
	(segment
		(start 14.858746 -420.6367)
		(end 10.731246 -416.509454)
		(width 0.09525)
		(layer "F.Cu")
		(net "SAS2X28_A_HDD0_TX_-")
	)
	(segment
		(start 4.625594 -416.498786)
		(end 3.192526 -416.498786)
		(width 0.09525)
		(layer "F.Cu")
		(net "SAS2X28_A_HDD0_TX_-")
	)
	(segment
		(start 15.481046 -460.054452)
		(end 15.481046 -421.786558)
		(width 0.09525)
		(layer "F.Cu")
		(net "SAS2X28_A_HDD0_TX_-")
	)
	(segment
		(start 74.412094 -465.868258)
		(end 74.285602 -465.868258)
		(width 0.09525)
		(layer "F.Cu")
		(net "SAS2X28_A_HDD0_TX_-")
	)
	(segment
		(start 221.487746 -466.158072)
		(end 221.487746 -465.9757)
		(width 0.09525)
		(layer "F.Cu")
		(net "SAS2X28_A_HDD0_TX_-")
	)
	(segment
		(start 34.746184 -460.017368)
		(end 32.872172 -461.89138)
		(width 0.09525)
		(layer "F.Cu")
		(net "SAS2X28_A_HDD0_TX_-")
	)
	(segment
		(start 221.381828 -465.869782)
		(end 74.512424 -465.869782)
		(width 0.09525)
		(layer "F.Cu")
		(net "SAS2X28_A_HDD0_TX_-")
	)
	(segment
		(start 9.889744 -416.160712)
		(end 5.446776 -416.160712)
		(width 0.09525)
		(layer "F.Cu")
		(net "SAS2X28_A_HDD0_TX_-")
	)
	(segment
		(start 31.648146 -462.398364)
		(end 18.8976 -462.398364)
		(width 0.09525)
		(layer "F.Cu")
		(net "SAS2X28_A_HDD0_TX_-")
	)
	(segment
		(start 223.249998 -466.34019)
		(end 221.669864 -466.34019)
		(width 0.09525)
		(layer "F.Cu")
		(net "SAS2X28_A_HDD0_TX_-")
	)
	(arc
		(start 74.285602 -465.868258)
		(mid 73.176823 -465.647708)
		(end 72.236838 -465.019644)
		(width 0.09525)
		(layer "F.Cu")
		(net "SAS2X28_A_HDD0_TX_-")
	)
	(arc
		(start 221.487746 -465.9757)
		(mid 221.456723 -465.900805)
		(end 221.381828 -465.869782)
		(width 0.09525)
		(layer "F.Cu")
		(net "SAS2X28_A_HDD0_TX_-")
	)
	(arc
		(start 36.304474 -459.3717)
		(mid 35.461084 -459.539496)
		(end 34.746184 -460.017368)
		(width 0.09525)
		(layer "F.Cu")
		(net "SAS2X28_A_HDD0_TX_-")
	)
	(arc
		(start 67.290188 -460.072994)
		(mid 67.289934 -460.07274)
		(end 67.28968 -460.072486)
		(width 0.09525)
		(layer "F.Cu")
		(net "SAS2X28_A_HDD0_TX_-")
	)
	(arc
		(start 5.221224 -416.254184)
		(mid 4.948646 -416.436315)
		(end 4.627118 -416.50031)
		(width 0.09525)
		(layer "F.Cu")
		(net "SAS2X28_A_HDD0_TX_-")
	)
	(arc
		(start 74.512424 -465.869782)
		(mid 74.462253 -465.869387)
		(end 74.412094 -465.868258)
		(width 0.09525)
		(layer "F.Cu")
		(net "SAS2X28_A_HDD0_TX_-")
	)
	(arc
		(start 18.8976 -462.398364)
		(mid 17.25077 -462.066667)
		(end 15.860776 -461.123284)
		(width 0.09525)
		(layer "F.Cu")
		(net "SAS2X28_A_HDD0_TX_-")
	)
	(arc
		(start 67.28968 -460.072486)
		(mid 66.513694 -459.553862)
		(end 65.598294 -459.3717)
		(width 0.09525)
		(layer "F.Cu")
		(net "SAS2X28_A_HDD0_TX_-")
	)
	(arc
		(start 15.481046 -421.786558)
		(mid 15.384006 -421.298703)
		(end 15.107666 -420.885112)
		(width 0.09525)
		(layer "F.Cu")
		(net "SAS2X28_A_HDD0_TX_-")
	)
	(arc
		(start 15.860776 -461.123284)
		(mid 15.578854 -460.62158)
		(end 15.481046 -460.054452)
		(width 0.09525)
		(layer "F.Cu")
		(net "SAS2X28_A_HDD0_TX_-")
	)
	(arc
		(start 5.446776 -416.160712)
		(mid 5.324691 -416.184996)
		(end 5.221224 -416.254184)
		(width 0.09525)
		(layer "F.Cu")
		(net "SAS2X28_A_HDD0_TX_-")
	)
	(arc
		(start 10.731246 -416.509454)
		(mid 10.34519 -416.251373)
		(end 9.889744 -416.160712)
		(width 0.09525)
		(layer "F.Cu")
		(net "SAS2X28_A_HDD0_TX_-")
	)
	(arc
		(start 32.872172 -461.89138)
		(mid 32.310584 -462.266621)
		(end 31.648146 -462.398364)
		(width 0.09525)
		(layer "F.Cu")
		(net "SAS2X28_A_HDD0_TX_-")
	)
	(arc
		(start 221.669864 -466.34019)
		(mid 221.541087 -466.286849)
		(end 221.487746 -466.158072)
		(width 0.09525)
		(layer "F.Cu")
		(net "SAS2X28_A_HDD0_TX_-")
	)
	(segment
		(start 43.814746 -212.563202)
		(end 42.544746 -212.563202)
		(width 0.111252)
		(layer "F.Cu")
		(net "SW_PWR_HDD12")
	)
	(segment
		(start 42.42943 -212.678518)
		(end 42.42943 -213.615016)
		(width 0.111252)
		(layer "F.Cu")
		(net "SW_PWR_HDD12")
	)
	(segment
		(start 42.42943 -213.615016)
		(end 42.290746 -213.7537)
		(width 0.111252)
		(layer "F.Cu")
		(net "SW_PWR_HDD12")
	)
	(segment
		(start 44.830746 -212.563202)
		(end 43.814746 -212.563202)
		(width 0.111252)
		(layer "F.Cu")
		(net "SW_PWR_HDD12")
	)
	(segment
		(start 42.544746 -212.563202)
		(end 42.42943 -212.678518)
		(width 0.111252)
		(layer "F.Cu")
		(net "SW_PWR_HDD12")
	)
	(via
		(at 42.290746 -213.7537)
		(size 0.7112)
		(drill 0.3556)
		(layers "F.Cu" "B.Cu")
		(net "SW_PWR_HDD12")
	)
	(segment
		(start 8.626856 -204.504544)
		(end 9.303258 -203.828142)
		(width 0.111252)
		(layer "F.Cu")
		(net "SAS_EXP_B_PWR7")
	)
	(segment
		(start 11.670538 -203.828142)
		(end 10.346436 -203.828142)
		(width 0.111252)
		(layer "F.Cu")
		(net "SAS_EXP_B_PWR7")
	)
	(segment
		(start 31.68142 -277.998428)
		(end 30.795214 -277.998428)
		(width 0.111252)
		(layer "F.Cu")
		(net "SAS_EXP_B_PWR7")
	)
	(segment
		(start 30.670246 -277.87346)
		(end 29.527246 -277.87346)
		(width 0.111252)
		(layer "F.Cu")
		(net "SAS_EXP_B_PWR7")
	)
	(segment
		(start 11.909298 -204.066902)
		(end 11.670538 -203.828142)
		(width 0.111252)
		(layer "F.Cu")
		(net "SAS_EXP_B_PWR7")
	)
	(segment
		(start 3.19024 -204.504544)
		(end 8.626856 -204.504544)
		(width 0.111252)
		(layer "F.Cu")
		(net "SAS_EXP_B_PWR7")
	)
	(segment
		(start 9.303258 -203.828142)
		(end 10.346436 -203.828142)
		(width 0.111252)
		(layer "F.Cu")
		(net "SAS_EXP_B_PWR7")
	)
	(segment
		(start 30.795214 -277.998428)
		(end 30.670246 -277.87346)
		(width 0.111252)
		(layer "F.Cu")
		(net "SAS_EXP_B_PWR7")
	)
	(via
		(at 10.346436 -203.828142)
		(size 0.7112)
		(drill 0.3556)
		(layers "F.Cu" "B.Cu")
		(net "SAS_EXP_B_PWR7")
	)
	(via
		(at 11.909298 -204.066902)
		(size 0.5588)
		(drill 0.3048)
		(layers "F.Cu" "B.Cu")
		(net "SAS_EXP_B_PWR7")
	)
	(via
		(at 30.670246 -277.87346)
		(size 0.5588)
		(drill 0.3048)
		(layers "F.Cu" "B.Cu")
		(net "SAS_EXP_B_PWR7")
	)
	(segment
		(start 13.255244 -206.041244)
		(end 13.255244 -214.67699)
		(width 0.14605)
		(layer "In5.Cu")
		(net "SAS_EXP_B_PWR7")
	)
	(segment
		(start 13.255244 -214.67699)
		(end 14.9352 -216.356946)
		(width 0.14605)
		(layer "In5.Cu")
		(net "SAS_EXP_B_PWR7")
	)
	(segment
		(start 14.9352 -216.545922)
		(end 14.966696 -216.577418)
		(width 0.14605)
		(layer "In5.Cu")
		(net "SAS_EXP_B_PWR7")
	)
	(segment
		(start 28.325826 -277.87346)
		(end 30.670246 -277.87346)
		(width 0.14605)
		(layer "In5.Cu")
		(net "SAS_EXP_B_PWR7")
	)
	(segment
		(start 14.966696 -264.51433)
		(end 28.325826 -277.87346)
		(width 0.14605)
		(layer "In5.Cu")
		(net "SAS_EXP_B_PWR7")
	)
	(segment
		(start 11.909298 -204.695298)
		(end 13.255244 -206.041244)
		(width 0.14605)
		(layer "In5.Cu")
		(net "SAS_EXP_B_PWR7")
	)
	(segment
		(start 14.9352 -216.356946)
		(end 14.9352 -216.545922)
		(width 0.14605)
		(layer "In5.Cu")
		(net "SAS_EXP_B_PWR7")
	)
	(segment
		(start 14.966696 -216.577418)
		(end 14.966696 -264.51433)
		(width 0.14605)
		(layer "In5.Cu")
		(net "SAS_EXP_B_PWR7")
	)
	(segment
		(start 11.909298 -204.066902)
		(end 11.909298 -204.695298)
		(width 0.14605)
		(layer "In5.Cu")
		(net "SAS_EXP_B_PWR7")
	)
	(segment
		(start 4.694428 -144.500346)
		(end 4.692904 -144.498822)
		(width 0.09525)
		(layer "F.Cu")
		(net "SAS2X28_B_HDD6_TX_+")
	)
	(segment
		(start 39.343584 -369.990116)
		(end 39.340282 -369.986814)
		(width 0.09525)
		(layer "F.Cu")
		(net "SAS2X28_B_HDD6_TX_+")
	)
	(segment
		(start 20.477226 -167.45458)
		(end 21.003514 -166.928292)
		(width 0.09525)
		(layer "F.Cu")
		(net "SAS2X28_B_HDD6_TX_+")
	)
	(segment
		(start 4.692904 -144.498822)
		(end 3.192526 -144.498822)
		(width 0.09525)
		(layer "F.Cu")
		(net "SAS2X28_B_HDD6_TX_+")
	)
	(segment
		(start 36.436808 -370.034058)
		(end 36.321746 -369.918742)
		(width 0.09525)
		(layer "F.Cu")
		(net "SAS2X28_B_HDD6_TX_+")
	)
	(segment
		(start 20.314158 -167.708072)
		(end 20.314158 -167.707818)
		(width 0.09525)
		(layer "F.Cu")
		(net "SAS2X28_B_HDD6_TX_+")
	)
	(segment
		(start 21.003514 -146.619214)
		(end 19.722846 -145.338546)
		(width 0.09525)
		(layer "F.Cu")
		(net "SAS2X28_B_HDD6_TX_+")
	)
	(segment
		(start 21.844 -164.898578)
		(end 21.844 -148.648928)
		(width 0.09525)
		(layer "F.Cu")
		(net "SAS2X28_B_HDD6_TX_+")
	)
	(segment
		(start 18.496026 -144.830546)
		(end 5.491734 -144.830546)
		(width 0.09525)
		(layer "F.Cu")
		(net "SAS2X28_B_HDD6_TX_+")
	)
	(segment
		(start 20.23872 -168.208198)
		(end 20.273264 -167.880538)
		(width 0.09525)
		(layer "F.Cu")
		(net "SAS2X28_B_HDD6_TX_+")
	)
	(segment
		(start 38.866826 -370.2177)
		(end 36.880546 -370.2177)
		(width 0.09525)
		(layer "F.Cu")
		(net "SAS2X28_B_HDD6_TX_+")
	)
	(segment
		(start 40.39997 -369.990116)
		(end 39.343584 -369.990116)
		(width 0.09525)
		(layer "F.Cu")
		(net "SAS2X28_B_HDD6_TX_+")
	)
	(via
		(at 20.446746 -168.7957)
		(size 0.5588)
		(drill 0.3048)
		(layers "F.Cu" "B.Cu")
		(net "SAS2X28_B_HDD6_TX_+")
	)
	(via
		(at 36.321746 -369.918742)
		(size 0.5588)
		(drill 0.3048)
		(layers "F.Cu" "B.Cu")
		(net "SAS2X28_B_HDD6_TX_+")
	)
	(arc
		(start 20.446746 -168.7957)
		(mid 20.329359 -168.641758)
		(end 20.257008 -168.462198)
		(width 0.09525)
		(layer "F.Cu")
		(net "SAS2X28_B_HDD6_TX_+")
	)
	(arc
		(start 20.273264 -167.880538)
		(mid 20.284419 -167.809431)
		(end 20.302728 -167.739822)
		(width 0.09525)
		(layer "F.Cu")
		(net "SAS2X28_B_HDD6_TX_+")
	)
	(arc
		(start 5.302758 -144.752314)
		(mid 5.023654 -144.565823)
		(end 4.694428 -144.500346)
		(width 0.09525)
		(layer "F.Cu")
		(net "SAS2X28_B_HDD6_TX_+")
	)
	(arc
		(start 20.257008 -168.462198)
		(mid 20.236619 -168.336009)
		(end 20.23872 -168.208198)
		(width 0.09525)
		(layer "F.Cu")
		(net "SAS2X28_B_HDD6_TX_+")
	)
	(arc
		(start 21.003514 -166.928292)
		(mid 21.625666 -165.997036)
		(end 21.844 -164.898578)
		(width 0.09525)
		(layer "F.Cu")
		(net "SAS2X28_B_HDD6_TX_+")
	)
	(arc
		(start 20.302728 -167.739822)
		(mid 20.308252 -167.723878)
		(end 20.314158 -167.708072)
		(width 0.09525)
		(layer "F.Cu")
		(net "SAS2X28_B_HDD6_TX_+")
	)
	(arc
		(start 36.880546 -370.2177)
		(mid 36.640404 -370.170027)
		(end 36.436808 -370.034058)
		(width 0.09525)
		(layer "F.Cu")
		(net "SAS2X28_B_HDD6_TX_+")
	)
	(arc
		(start 21.844 -148.648928)
		(mid 21.625602 -147.550496)
		(end 21.003514 -146.619214)
		(width 0.09525)
		(layer "F.Cu")
		(net "SAS2X28_B_HDD6_TX_+")
	)
	(arc
		(start 20.314158 -167.707818)
		(mid 20.382107 -167.572449)
		(end 20.477226 -167.45458)
		(width 0.09525)
		(layer "F.Cu")
		(net "SAS2X28_B_HDD6_TX_+")
	)
	(arc
		(start 5.491734 -144.830546)
		(mid 5.389478 -144.810206)
		(end 5.302758 -144.752314)
		(width 0.09525)
		(layer "F.Cu")
		(net "SAS2X28_B_HDD6_TX_+")
	)
	(arc
		(start 19.722846 -145.338546)
		(mid 19.159948 -144.962556)
		(end 18.496026 -144.830546)
		(width 0.09525)
		(layer "F.Cu")
		(net "SAS2X28_B_HDD6_TX_+")
	)
	(arc
		(start 39.226744 -370.033804)
		(mid 39.167366 -370.069965)
		(end 39.114476 -370.115084)
		(width 0.09525)
		(layer "F.Cu")
		(net "SAS2X28_B_HDD6_TX_+")
	)
	(arc
		(start 39.340282 -369.986814)
		(mid 39.278851 -369.999033)
		(end 39.226744 -370.033804)
		(width 0.09525)
		(layer "F.Cu")
		(net "SAS2X28_B_HDD6_TX_+")
	)
	(arc
		(start 39.114476 -370.115084)
		(mid 39.000853 -370.191004)
		(end 38.866826 -370.2177)
		(width 0.09525)
		(layer "F.Cu")
		(net "SAS2X28_B_HDD6_TX_+")
	)
	(segment
		(start 35.0901 -369.7986)
		(end 35.089846 -369.7986)
		(width 0.09525)
		(layer "B.Cu")
		(net "SAS2X28_B_HDD6_TX_+")
	)
	(segment
		(start 42.874946 -349.706692)
		(end 42.874946 -305.806094)
		(width 0.09525)
		(layer "B.Cu")
		(net "SAS2X28_B_HDD6_TX_+")
	)
	(segment
		(start 48.869346 -298.680124)
		(end 48.869346 -206.416402)
		(width 0.09525)
		(layer "B.Cu")
		(net "SAS2X28_B_HDD6_TX_+")
	)
	(segment
		(start 22.976078 -170.8785)
		(end 21.31441 -170.8785)
		(width 0.09525)
		(layer "B.Cu")
		(net "SAS2X28_B_HDD6_TX_+")
	)
	(segment
		(start 35.9283 -370.1415)
		(end 35.701986 -370.1415)
		(width 0.09525)
		(layer "B.Cu")
		(net "SAS2X28_B_HDD6_TX_+")
	)
	(segment
		(start 36.321746 -369.918742)
		(end 36.219638 -370.02085)
		(width 0.09525)
		(layer "B.Cu")
		(net "SAS2X28_B_HDD6_TX_+")
	)
	(segment
		(start 34.9123 -367.325148)
		(end 34.912046 -367.324894)
		(width 0.09525)
		(layer "B.Cu")
		(net "SAS2X28_B_HDD6_TX_+")
	)
	(segment
		(start 20.372324 -168.7957)
		(end 20.446746 -168.7957)
		(width 0.09525)
		(layer "B.Cu")
		(net "SAS2X28_B_HDD6_TX_+")
	)
	(segment
		(start 34.912046 -369.36934)
		(end 34.912046 -368.792506)
		(width 0.09525)
		(layer "B.Cu")
		(net "SAS2X28_B_HDD6_TX_+")
	)
	(segment
		(start 37.346128 -184.865518)
		(end 23.629874 -171.149264)
		(width 0.09525)
		(layer "B.Cu")
		(net "SAS2X28_B_HDD6_TX_+")
	)
	(segment
		(start 48.392334 -205.264766)
		(end 38.27018 -195.142612)
		(width 0.09525)
		(layer "B.Cu")
		(net "SAS2X28_B_HDD6_TX_+")
	)
	(segment
		(start 20.007072 -169.620946)
		(end 20.007072 -169.064432)
		(width 0.09525)
		(layer "B.Cu")
		(net "SAS2X28_B_HDD6_TX_+")
	)
	(segment
		(start 35.242246 -369.950746)
		(end 35.0901 -369.7986)
		(width 0.09525)
		(layer "B.Cu")
		(net "SAS2X28_B_HDD6_TX_+")
	)
	(segment
		(start 20.934172 -170.72102)
		(end 20.141946 -169.92854)
		(width 0.09525)
		(layer "B.Cu")
		(net "SAS2X28_B_HDD6_TX_+")
	)
	(segment
		(start 34.912046 -368.792506)
		(end 34.9123 -368.792252)
		(width 0.09525)
		(layer "B.Cu")
		(net "SAS2X28_B_HDD6_TX_+")
	)
	(segment
		(start 35.403028 -357.741982)
		(end 42.476674 -350.668336)
		(width 0.09525)
		(layer "B.Cu")
		(net "SAS2X28_B_HDD6_TX_+")
	)
	(segment
		(start 37.808154 -194.098926)
		(end 37.808154 -185.981086)
		(width 0.09525)
		(layer "B.Cu")
		(net "SAS2X28_B_HDD6_TX_+")
	)
	(segment
		(start 34.912046 -367.324894)
		(end 34.912046 -358.9274)
		(width 0.09525)
		(layer "B.Cu")
		(net "SAS2X28_B_HDD6_TX_+")
	)
	(segment
		(start 34.9123 -368.792252)
		(end 34.9123 -367.325148)
		(width 0.09525)
		(layer "B.Cu")
		(net "SAS2X28_B_HDD6_TX_+")
	)
	(segment
		(start 38.27018 -195.142612)
		(end 38.21938 -195.092066)
		(width 0.09525)
		(layer "B.Cu")
		(net "SAS2X28_B_HDD6_TX_+")
	)
	(segment
		(start 43.292268 -304.798476)
		(end 48.486568 -299.604176)
		(width 0.09525)
		(layer "B.Cu")
		(net "SAS2X28_B_HDD6_TX_+")
	)
	(arc
		(start 48.869346 -206.416402)
		(mid 48.745373 -205.793145)
		(end 48.392334 -205.264766)
		(width 0.09525)
		(layer "B.Cu")
		(net "SAS2X28_B_HDD6_TX_+")
	)
	(arc
		(start 42.874946 -305.806094)
		(mid 42.983413 -305.260793)
		(end 43.292268 -304.798476)
		(width 0.09525)
		(layer "B.Cu")
		(net "SAS2X28_B_HDD6_TX_+")
	)
	(arc
		(start 20.141946 -169.92854)
		(mid 20.045444 -169.787492)
		(end 20.007072 -169.620946)
		(width 0.09525)
		(layer "B.Cu")
		(net "SAS2X28_B_HDD6_TX_+")
	)
	(arc
		(start 20.065746 -168.9227)
		(mid 20.206405 -168.828715)
		(end 20.372324 -168.7957)
		(width 0.09525)
		(layer "B.Cu")
		(net "SAS2X28_B_HDD6_TX_+")
	)
	(arc
		(start 35.527996 -370.117624)
		(mid 35.374317 -370.05268)
		(end 35.242246 -369.950746)
		(width 0.09525)
		(layer "B.Cu")
		(net "SAS2X28_B_HDD6_TX_+")
	)
	(arc
		(start 48.486568 -299.604176)
		(mid 48.769848 -299.180217)
		(end 48.869346 -298.680124)
		(width 0.09525)
		(layer "B.Cu")
		(net "SAS2X28_B_HDD6_TX_+")
	)
	(arc
		(start 21.31441 -170.8785)
		(mid 21.108634 -170.837569)
		(end 20.934172 -170.72102)
		(width 0.09525)
		(layer "B.Cu")
		(net "SAS2X28_B_HDD6_TX_+")
	)
	(arc
		(start 35.701986 -370.1415)
		(mid 35.614178 -370.135477)
		(end 35.527996 -370.117624)
		(width 0.09525)
		(layer "B.Cu")
		(net "SAS2X28_B_HDD6_TX_+")
	)
	(arc
		(start 23.629874 -171.149264)
		(mid 23.329896 -170.948859)
		(end 22.976078 -170.8785)
		(width 0.09525)
		(layer "B.Cu")
		(net "SAS2X28_B_HDD6_TX_+")
	)
	(arc
		(start 38.21938 -195.092066)
		(mid 37.915003 -194.636394)
		(end 37.808154 -194.098926)
		(width 0.09525)
		(layer "B.Cu")
		(net "SAS2X28_B_HDD6_TX_+")
	)
	(arc
		(start 20.007072 -169.064432)
		(mid 20.022327 -168.98774)
		(end 20.065746 -168.9227)
		(width 0.09525)
		(layer "B.Cu")
		(net "SAS2X28_B_HDD6_TX_+")
	)
	(arc
		(start 37.808154 -185.981086)
		(mid 37.688014 -185.377392)
		(end 37.346128 -184.865518)
		(width 0.09525)
		(layer "B.Cu")
		(net "SAS2X28_B_HDD6_TX_+")
	)
	(arc
		(start 35.089846 -369.7986)
		(mid 34.958251 -369.601654)
		(end 34.912046 -369.36934)
		(width 0.09525)
		(layer "B.Cu")
		(net "SAS2X28_B_HDD6_TX_+")
	)
	(arc
		(start 42.476674 -350.668336)
		(mid 42.771449 -350.227129)
		(end 42.874946 -349.706692)
		(width 0.09525)
		(layer "B.Cu")
		(net "SAS2X28_B_HDD6_TX_+")
	)
	(arc
		(start 36.219638 -370.02085)
		(mid 36.085971 -370.110163)
		(end 35.9283 -370.1415)
		(width 0.09525)
		(layer "B.Cu")
		(net "SAS2X28_B_HDD6_TX_+")
	)
	(arc
		(start 34.912046 -358.9274)
		(mid 35.039654 -358.285869)
		(end 35.403028 -357.741982)
		(width 0.09525)
		(layer "B.Cu")
		(net "SAS2X28_B_HDD6_TX_+")
	)
	(segment
		(start 29.590746 -311.750202)
		(end 28.447746 -311.750202)
		(width 0.111252)
		(layer "F.Cu")
		(net "SW_PWR_HDD11")
	)
	(segment
		(start 28.447746 -311.750202)
		(end 27.177746 -311.750202)
		(width 0.111252)
		(layer "F.Cu")
		(net "SW_PWR_HDD11")
	)
	(segment
		(start 25.860248 -311.750202)
		(end 25.526746 -311.4167)
		(width 0.111252)
		(layer "F.Cu")
		(net "SW_PWR_HDD11")
	)
	(segment
		(start 27.177746 -311.750202)
		(end 25.860248 -311.750202)
		(width 0.111252)
		(layer "F.Cu")
		(net "SW_PWR_HDD11")
	)
	(via
		(at 25.526746 -311.4167)
		(size 0.7112)
		(drill 0.3556)
		(layers "F.Cu" "B.Cu")
		(net "SW_PWR_HDD11")
	)
	(segment
		(start 26.65349 -366.09274)
		(end 26.65349 -365.921036)
		(width 0.09525)
		(layer "F.Cu")
		(net "SAS2X28_A_HDD6_RX_-")
	)
	(segment
		(start 32.42056 -366.075214)
		(end 32.378396 -366.075214)
		(width 0.09525)
		(layer "F.Cu")
		(net "SAS2X28_A_HDD6_RX_-")
	)
	(segment
		(start 32.306514 -366.104932)
		(end 32.03956 -366.371886)
		(width 0.09525)
		(layer "F.Cu")
		(net "SAS2X28_A_HDD6_RX_-")
	)
	(segment
		(start 26.796492 -366.407446)
		(end 26.774902 -366.385856)
		(width 0.09525)
		(layer "F.Cu")
		(net "SAS2X28_A_HDD6_RX_-")
	)
	(segment
		(start 31.608522 -366.550448)
		(end 27.141678 -366.550448)
		(width 0.09525)
		(layer "F.Cu")
		(net "SAS2X28_A_HDD6_RX_-")
	)
	(via
		(at 26.65349 -365.921036)
		(size 0.5588)
		(drill 0.3048)
		(layers "F.Cu" "B.Cu")
		(net "SAS2X28_A_HDD6_RX_-")
	)
	(arc
		(start 27.141678 -366.550448)
		(mid 26.954857 -366.513287)
		(end 26.796492 -366.407446)
		(width 0.09525)
		(layer "F.Cu")
		(net "SAS2X28_A_HDD6_RX_-")
	)
	(arc
		(start 32.03956 -366.371886)
		(mid 31.883025 -366.48505)
		(end 31.698946 -366.54359)
		(width 0.09525)
		(layer "F.Cu")
		(net "SAS2X28_A_HDD6_RX_-")
	)
	(arc
		(start 26.774902 -366.385856)
		(mid 26.685043 -366.251373)
		(end 26.65349 -366.09274)
		(width 0.09525)
		(layer "F.Cu")
		(net "SAS2X28_A_HDD6_RX_-")
	)
	(arc
		(start 32.378396 -366.075214)
		(mid 32.339501 -366.082933)
		(end 32.306514 -366.104932)
		(width 0.09525)
		(layer "F.Cu")
		(net "SAS2X28_A_HDD6_RX_-")
	)
	(arc
		(start 31.698946 -366.54359)
		(mid 31.653862 -366.548703)
		(end 31.608522 -366.550448)
		(width 0.09525)
		(layer "F.Cu")
		(net "SAS2X28_A_HDD6_RX_-")
	)
	(segment
		(start 12.229084 -385.049776)
		(end 10.291572 -386.987034)
		(width 0.09525)
		(layer "B.Cu")
		(net "SAS2X28_A_HDD6_RX_-")
	)
	(segment
		(start 7.495032 -387.197092)
		(end 7.23265 -386.93471)
		(width 0.09525)
		(layer "B.Cu")
		(net "SAS2X28_A_HDD6_RX_-")
	)
	(segment
		(start 12.230354 -385.047236)
		(end 12.229084 -385.049776)
		(width 0.09525)
		(layer "B.Cu")
		(net "SAS2X28_A_HDD6_RX_-")
	)
	(segment
		(start 13.588746 -377.0757)
		(end 13.545058 -377.119134)
		(width 0.09525)
		(layer "B.Cu")
		(net "SAS2X28_A_HDD6_RX_-")
	)
	(segment
		(start 6.53796 -384.49631)
		(end 6.424168 -384.382264)
		(width 0.09525)
		(layer "B.Cu")
		(net "SAS2X28_A_HDD6_RX_-")
	)
	(segment
		(start 6.424168 -384.382264)
		(end 6.41731 -384.375152)
		(width 0.09525)
		(layer "B.Cu")
		(net "SAS2X28_A_HDD6_RX_-")
	)
	(segment
		(start 27.052778 -366.2807)
		(end 27.052778 -366.4077)
		(width 0.09525)
		(layer "B.Cu")
		(net "SAS2X28_A_HDD6_RX_-")
	)
	(segment
		(start 25.377394 -365.286798)
		(end 25.377394 -365.287052)
		(width 0.09525)
		(layer "B.Cu")
		(net "SAS2X28_A_HDD6_RX_-")
	)
	(segment
		(start 27.1145 -366.55629)
		(end 27.191462 -366.633506)
		(width 0.09525)
		(layer "B.Cu")
		(net "SAS2X28_A_HDD6_RX_-")
	)
	(segment
		(start 4.872482 -384.49885)
		(end 2.811526 -384.49885)
		(width 0.09525)
		(layer "B.Cu")
		(net "SAS2X28_A_HDD6_RX_-")
	)
	(segment
		(start 27.939746 -366.503458)
		(end 27.939746 -365.010446)
		(width 0.09525)
		(layer "B.Cu")
		(net "SAS2X28_A_HDD6_RX_-")
	)
	(segment
		(start 25.5397 -365.124238)
		(end 25.377394 -365.286798)
		(width 0.09525)
		(layer "B.Cu")
		(net "SAS2X28_A_HDD6_RX_-")
	)
	(segment
		(start 5.39877 -384.242818)
		(end 5.33019 -384.311398)
		(width 0.09525)
		(layer "B.Cu")
		(net "SAS2X28_A_HDD6_RX_-")
	)
	(segment
		(start 6.72592 -385.7117)
		(end 6.72592 -384.9497)
		(width 0.09525)
		(layer "B.Cu")
		(net "SAS2X28_A_HDD6_RX_-")
	)
	(segment
		(start 27.686 -364.7567)
		(end 26.427176 -364.7567)
		(width 0.09525)
		(layer "B.Cu")
		(net "SAS2X28_A_HDD6_RX_-")
	)
	(segment
		(start 25.377394 -365.287052)
		(end 13.588746 -377.0757)
		(width 0.09525)
		(layer "B.Cu")
		(net "SAS2X28_A_HDD6_RX_-")
	)
	(segment
		(start 5.841746 -384.1369)
		(end 5.654548 -384.1369)
		(width 0.09525)
		(layer "B.Cu")
		(net "SAS2X28_A_HDD6_RX_-")
	)
	(segment
		(start 10.291572 -386.987034)
		(end 10.166096 -387.112256)
		(width 0.09525)
		(layer "B.Cu")
		(net "SAS2X28_A_HDD6_RX_-")
	)
	(segment
		(start 12.826746 -378.8537)
		(end 12.826746 -383.553462)
		(width 0.09525)
		(layer "B.Cu")
		(net "SAS2X28_A_HDD6_RX_-")
	)
	(segment
		(start 27.415236 -366.684814)
		(end 27.685746 -366.684814)
		(width 0.09525)
		(layer "B.Cu")
		(net "SAS2X28_A_HDD6_RX_-")
	)
	(segment
		(start 8.947912 -387.616954)
		(end 8.508746 -387.616954)
		(width 0.09525)
		(layer "B.Cu")
		(net "SAS2X28_A_HDD6_RX_-")
	)
	(segment
		(start 4.874006 -384.500374)
		(end 4.872482 -384.49885)
		(width 0.09525)
		(layer "B.Cu")
		(net "SAS2X28_A_HDD6_RX_-")
	)
	(segment
		(start 26.65349 -365.921036)
		(end 26.697432 -365.921036)
		(width 0.09525)
		(layer "B.Cu")
		(net "SAS2X28_A_HDD6_RX_-")
	)
	(segment
		(start 12.826746 -383.553462)
		(end 12.827 -383.553462)
		(width 0.09525)
		(layer "B.Cu")
		(net "SAS2X28_A_HDD6_RX_-")
	)
	(arc
		(start 27.685746 -366.684814)
		(mid 27.802582 -366.661574)
		(end 27.901646 -366.595406)
		(width 0.09525)
		(layer "B.Cu")
		(net "SAS2X28_A_HDD6_RX_-")
	)
	(arc
		(start 12.827 -383.553462)
		(mid 12.672211 -384.357669)
		(end 12.230354 -385.047236)
		(width 0.09525)
		(layer "B.Cu")
		(net "SAS2X28_A_HDD6_RX_-")
	)
	(arc
		(start 7.23265 -386.93471)
		(mid 6.857637 -386.373603)
		(end 6.72592 -385.7117)
		(width 0.09525)
		(layer "B.Cu")
		(net "SAS2X28_A_HDD6_RX_-")
	)
	(arc
		(start 27.901646 -366.595406)
		(mid 27.929834 -366.55322)
		(end 27.939746 -366.503458)
		(width 0.09525)
		(layer "B.Cu")
		(net "SAS2X28_A_HDD6_RX_-")
	)
	(arc
		(start 26.697432 -365.921036)
		(mid 26.832153 -365.947834)
		(end 26.946352 -366.02416)
		(width 0.09525)
		(layer "B.Cu")
		(net "SAS2X28_A_HDD6_RX_-")
	)
	(arc
		(start 27.191462 -366.633506)
		(mid 27.30044 -366.671848)
		(end 27.415236 -366.684814)
		(width 0.09525)
		(layer "B.Cu")
		(net "SAS2X28_A_HDD6_RX_-")
	)
	(arc
		(start 26.946352 -366.02416)
		(mid 27.025081 -366.141847)
		(end 27.052778 -366.2807)
		(width 0.09525)
		(layer "B.Cu")
		(net "SAS2X28_A_HDD6_RX_-")
	)
	(arc
		(start 6.72592 -384.9497)
		(mid 6.677017 -384.70432)
		(end 6.53796 -384.49631)
		(width 0.09525)
		(layer "B.Cu")
		(net "SAS2X28_A_HDD6_RX_-")
	)
	(arc
		(start 26.427176 -364.7567)
		(mid 25.946874 -364.852202)
		(end 25.5397 -365.124238)
		(width 0.09525)
		(layer "B.Cu")
		(net "SAS2X28_A_HDD6_RX_-")
	)
	(arc
		(start 27.052778 -366.4077)
		(mid 27.06887 -366.488129)
		(end 27.1145 -366.55629)
		(width 0.09525)
		(layer "B.Cu")
		(net "SAS2X28_A_HDD6_RX_-")
	)
	(arc
		(start 5.33019 -384.311398)
		(mid 5.120891 -384.451247)
		(end 4.874006 -384.500374)
		(width 0.09525)
		(layer "B.Cu")
		(net "SAS2X28_A_HDD6_RX_-")
	)
	(arc
		(start 27.939746 -365.010446)
		(mid 27.865426 -364.83102)
		(end 27.686 -364.7567)
		(width 0.09525)
		(layer "B.Cu")
		(net "SAS2X28_A_HDD6_RX_-")
	)
	(arc
		(start 8.508746 -387.616954)
		(mid 7.96014 -387.50783)
		(end 7.495032 -387.197092)
		(width 0.09525)
		(layer "B.Cu")
		(net "SAS2X28_A_HDD6_RX_-")
	)
	(arc
		(start 10.166096 -387.112256)
		(mid 9.607175 -387.485682)
		(end 8.947912 -387.616954)
		(width 0.09525)
		(layer "B.Cu")
		(net "SAS2X28_A_HDD6_RX_-")
	)
	(arc
		(start 13.545058 -377.119134)
		(mid 13.013387 -377.914975)
		(end 12.826746 -378.8537)
		(width 0.09525)
		(layer "B.Cu")
		(net "SAS2X28_A_HDD6_RX_-")
	)
	(arc
		(start 6.41731 -384.375152)
		(mid 6.153224 -384.198788)
		(end 5.841746 -384.1369)
		(width 0.09525)
		(layer "B.Cu")
		(net "SAS2X28_A_HDD6_RX_-")
	)
	(arc
		(start 5.654548 -384.1369)
		(mid 5.516133 -384.164432)
		(end 5.39877 -384.242818)
		(width 0.09525)
		(layer "B.Cu")
		(net "SAS2X28_A_HDD6_RX_-")
	)
	(segment
		(start 37.528246 -437.5277)
		(end 37.528246 -436.5117)
		(width 0.111252)
		(layer "F.Cu")
		(net "SW_PWR_HDD10")
	)
	(segment
		(start 44.322746 -420.6367)
		(end 43.687746 -421.2717)
		(width 0.111252)
		(layer "F.Cu")
		(net "SW_PWR_HDD10")
	)
	(segment
		(start 37.528246 -436.2577)
		(end 38.353746 -435.4322)
		(width 0.111252)
		(layer "F.Cu")
		(net "SW_PWR_HDD10")
	)
	(segment
		(start 38.353746 -435.4322)
		(end 38.353746 -435.2417)
		(width 0.111252)
		(layer "F.Cu")
		(net "SW_PWR_HDD10")
	)
	(segment
		(start 43.687746 -421.2717)
		(end 43.687746 -422.2115)
		(width 0.111252)
		(layer "F.Cu")
		(net "SW_PWR_HDD10")
	)
	(segment
		(start 44.322746 -419.890702)
		(end 44.322746 -420.6367)
		(width 0.111252)
		(layer "F.Cu")
		(net "SW_PWR_HDD10")
	)
	(segment
		(start 37.528246 -436.5117)
		(end 37.528246 -436.2577)
		(width 0.111252)
		(layer "F.Cu")
		(net "SW_PWR_HDD10")
	)
	(via
		(at 43.687746 -421.2717)
		(size 0.7112)
		(drill 0.3556)
		(layers "F.Cu" "B.Cu")
		(net "SW_PWR_HDD10")
	)
	(via
		(at 43.687746 -422.2115)
		(size 0.5588)
		(drill 0.3048)
		(layers "F.Cu" "B.Cu")
		(net "SW_PWR_HDD10")
	)
	(via
		(at 38.353746 -435.2417)
		(size 0.5588)
		(drill 0.3048)
		(layers "F.Cu" "B.Cu")
		(net "SW_PWR_HDD10")
	)
	(segment
		(start 43.687746 -430.149254)
		(end 43.687746 -422.2115)
		(width 0.14605)
		(layer "In5.Cu")
		(net "SW_PWR_HDD10")
	)
	(segment
		(start 38.5953 -435.2417)
		(end 43.687746 -430.149254)
		(width 0.14605)
		(layer "In5.Cu")
		(net "SW_PWR_HDD10")
	)
	(segment
		(start 38.353746 -435.2417)
		(end 38.5953 -435.2417)
		(width 0.14605)
		(layer "In5.Cu")
		(net "SW_PWR_HDD10")
	)
	(segment
		(start 55.9308 -377.50242)
		(end 56.0578 -377.37542)
		(width 0.111252)
		(layer "F.Cu")
		(net "HDD_PRSNT6")
	)
	(segment
		(start 55.9308 -377.94438)
		(end 55.9308 -377.50242)
		(width 0.111252)
		(layer "F.Cu")
		(net "HDD_PRSNT6")
	)
	(segment
		(start 71.805546 -372.0211)
		(end 74.675746 -374.8913)
		(width 0.111252)
		(layer "F.Cu")
		(net "HDD_PRSNT6")
	)
	(segment
		(start 102.006146 -374.8913)
		(end 87.299546 -374.8913)
		(width 0.111252)
		(layer "F.Cu")
		(net "HDD_PRSNT6")
	)
	(segment
		(start 56.133746 -380.3777)
		(end 56.133746 -378.147326)
		(width 0.111252)
		(layer "F.Cu")
		(net "HDD_PRSNT6")
	)
	(segment
		(start 56.0578 -374.344946)
		(end 58.381646 -372.0211)
		(width 0.111252)
		(layer "F.Cu")
		(net "HDD_PRSNT6")
	)
	(segment
		(start 58.381646 -372.0211)
		(end 71.805546 -372.0211)
		(width 0.111252)
		(layer "F.Cu")
		(net "HDD_PRSNT6")
	)
	(segment
		(start 56.0578 -377.37542)
		(end 56.0578 -374.344946)
		(width 0.111252)
		(layer "F.Cu")
		(net "HDD_PRSNT6")
	)
	(segment
		(start 102.234746 -375.1199)
		(end 102.006146 -374.8913)
		(width 0.111252)
		(layer "F.Cu")
		(net "HDD_PRSNT6")
	)
	(segment
		(start 56.133746 -378.147326)
		(end 55.9308 -377.94438)
		(width 0.111252)
		(layer "F.Cu")
		(net "HDD_PRSNT6")
	)
	(segment
		(start 74.675746 -374.8913)
		(end 87.299546 -374.8913)
		(width 0.111252)
		(layer "F.Cu")
		(net "HDD_PRSNT6")
	)
	(via
		(at 9.875012 -457.091034)
		(size 0.5588)
		(drill 0.3048)
		(layers "F.Cu" "B.Cu")
		(net "HDD_PRSNT6")
	)
	(via
		(at 102.234746 -375.1199)
		(size 0.5588)
		(drill 0.3048)
		(layers "F.Cu" "B.Cu")
		(net "HDD_PRSNT6")
	)
	(via
		(at 11.8618 -208.3054)
		(size 0.5588)
		(drill 0.3048)
		(layers "F.Cu" "B.Cu")
		(net "HDD_PRSNT6")
	)
	(via
		(at 21.742146 -456.5269)
		(size 0.5588)
		(drill 0.3048)
		(layers "F.Cu" "B.Cu")
		(net "HDD_PRSNT6")
	)
	(via
		(at 87.299546 -374.8913)
		(size 0.7112)
		(drill 0.3556)
		(layers "F.Cu" "B.Cu")
		(net "HDD_PRSNT6")
	)
	(segment
		(start 9.464802 -457.501244)
		(end 2.812542 -457.501244)
		(width 0.111252)
		(layer "B.Cu")
		(net "HDD_PRSNT6")
	)
	(segment
		(start 2.812542 -208.501234)
		(end 2.80924 -208.504536)
		(width 0.111252)
		(layer "B.Cu")
		(net "HDD_PRSNT6")
	)
	(segment
		(start 11.043412 -457.091034)
		(end 9.875012 -457.091034)
		(width 0.111252)
		(layer "B.Cu")
		(net "HDD_PRSNT6")
	)
	(segment
		(start 2.812542 -457.501244)
		(end 2.80924 -457.504546)
		(width 0.111252)
		(layer "B.Cu")
		(net "HDD_PRSNT6")
	)
	(segment
		(start 12.6873 -455.8411)
		(end 12.1412 -456.3872)
		(width 0.111252)
		(layer "B.Cu")
		(net "HDD_PRSNT6")
	)
	(segment
		(start 11.493754 -207.937354)
		(end 9.372092 -207.937354)
		(width 0.111252)
		(layer "B.Cu")
		(net "HDD_PRSNT6")
	)
	(segment
		(start 11.747246 -456.3872)
		(end 11.043412 -457.091034)
		(width 0.111252)
		(layer "B.Cu")
		(net "HDD_PRSNT6")
	)
	(segment
		(start 21.742146 -456.5269)
		(end 21.056346 -455.8411)
		(width 0.111252)
		(layer "B.Cu")
		(net "HDD_PRSNT6")
	)
	(segment
		(start 21.056346 -455.8411)
		(end 12.6873 -455.8411)
		(width 0.111252)
		(layer "B.Cu")
		(net "HDD_PRSNT6")
	)
	(segment
		(start 9.372092 -207.937354)
		(end 8.808212 -208.501234)
		(width 0.111252)
		(layer "B.Cu")
		(net "HDD_PRSNT6")
	)
	(segment
		(start 9.875012 -457.091034)
		(end 9.464802 -457.501244)
		(width 0.111252)
		(layer "B.Cu")
		(net "HDD_PRSNT6")
	)
	(segment
		(start 11.8618 -208.3054)
		(end 11.493754 -207.937354)
		(width 0.111252)
		(layer "B.Cu")
		(net "HDD_PRSNT6")
	)
	(segment
		(start 8.808212 -208.501234)
		(end 2.812542 -208.501234)
		(width 0.111252)
		(layer "B.Cu")
		(net "HDD_PRSNT6")
	)
	(segment
		(start 12.1412 -456.3872)
		(end 11.747246 -456.3872)
		(width 0.111252)
		(layer "B.Cu")
		(net "HDD_PRSNT6")
	)
	(segment
		(start 13.36294 -217.581734)
		(end 13.36294 -212.38591)
		(width 0.14605)
		(layer "In2.Cu")
		(net "HDD_PRSNT6")
	)
	(segment
		(start 10.760964 -456.336908)
		(end 10.760964 -455.939652)
		(width 0.14605)
		(layer "In2.Cu")
		(net "HDD_PRSNT6")
	)
	(segment
		(start 13.737336 -266.032488)
		(end 14.50975 -265.260074)
		(width 0.14605)
		(layer "In2.Cu")
		(net "HDD_PRSNT6")
	)
	(segment
		(start 8.287512 -439.520076)
		(end 12.83589 -434.971698)
		(width 0.14605)
		(layer "In2.Cu")
		(net "HDD_PRSNT6")
	)
	(segment
		(start 10.48004 -455.658728)
		(end 10.467594 -455.658728)
		(width 0.14605)
		(layer "In2.Cu")
		(net "HDD_PRSNT6")
	)
	(segment
		(start 11.9634 -208.407)
		(end 11.8618 -208.3054)
		(width 0.14605)
		(layer "In2.Cu")
		(net "HDD_PRSNT6")
	)
	(segment
		(start 13.680948 -393.734544)
		(end 13.680948 -375.872248)
		(width 0.14605)
		(layer "In2.Cu")
		(net "HDD_PRSNT6")
	)
	(segment
		(start 11.9634 -210.98637)
		(end 11.9634 -208.407)
		(width 0.14605)
		(layer "In2.Cu")
		(net "HDD_PRSNT6")
	)
	(segment
		(start 13.737336 -267.527532)
		(end 13.737336 -266.032488)
		(width 0.14605)
		(layer "In2.Cu")
		(net "HDD_PRSNT6")
	)
	(segment
		(start 10.48004 -456.617832)
		(end 10.760964 -456.336908)
		(width 0.14605)
		(layer "In2.Cu")
		(net "HDD_PRSNT6")
	)
	(segment
		(start 13.010388 -396.23746)
		(end 13.113004 -396.134844)
		(width 0.14605)
		(layer "In2.Cu")
		(net "HDD_PRSNT6")
	)
	(segment
		(start 13.010388 -414.448498)
		(end 13.010388 -396.23746)
		(width 0.14605)
		(layer "In2.Cu")
		(net "HDD_PRSNT6")
	)
	(segment
		(start 13.680948 -375.872248)
		(end 14.1986 -375.354596)
		(width 0.14605)
		(layer "In2.Cu")
		(net "HDD_PRSNT6")
	)
	(segment
		(start 12.83589 -414.622996)
		(end 13.010388 -414.448498)
		(width 0.14605)
		(layer "In2.Cu")
		(net "HDD_PRSNT6")
	)
	(segment
		(start 13.113004 -394.302488)
		(end 13.680948 -393.734544)
		(width 0.14605)
		(layer "In2.Cu")
		(net "HDD_PRSNT6")
	)
	(segment
		(start 9.774174 -454.142348)
		(end 9.529318 -454.142348)
		(width 0.14605)
		(layer "In2.Cu")
		(net "HDD_PRSNT6")
	)
	(segment
		(start 13.992352 -258.070096)
		(end 13.992352 -256.86004)
		(width 0.14605)
		(layer "In2.Cu")
		(net "HDD_PRSNT6")
	)
	(segment
		(start 10.055098 -455.246232)
		(end 10.055098 -454.423272)
		(width 0.14605)
		(layer "In2.Cu")
		(net "HDD_PRSNT6")
	)
	(segment
		(start 14.50975 -265.260074)
		(end 14.50975 -258.587748)
		(width 0.14605)
		(layer "In2.Cu")
		(net "HDD_PRSNT6")
	)
	(segment
		(start 14.1986 -366.060228)
		(end 13.73759 -365.599218)
		(width 0.14605)
		(layer "In2.Cu")
		(net "HDD_PRSNT6")
	)
	(segment
		(start 9.875012 -457.091034)
		(end 10.348214 -456.617832)
		(width 0.14605)
		(layer "In2.Cu")
		(net "HDD_PRSNT6")
	)
	(segment
		(start 9.529318 -454.142348)
		(end 8.287512 -452.900542)
		(width 0.14605)
		(layer "In2.Cu")
		(net "HDD_PRSNT6")
	)
	(segment
		(start 10.055098 -454.423272)
		(end 9.774174 -454.142348)
		(width 0.14605)
		(layer "In2.Cu")
		(net "HDD_PRSNT6")
	)
	(segment
		(start 13.73759 -365.599218)
		(end 13.73759 -267.527786)
		(width 0.14605)
		(layer "In2.Cu")
		(net "HDD_PRSNT6")
	)
	(segment
		(start 13.36294 -212.38591)
		(end 11.9634 -210.98637)
		(width 0.14605)
		(layer "In2.Cu")
		(net "HDD_PRSNT6")
	)
	(segment
		(start 13.113004 -396.134844)
		(end 13.113004 -394.302488)
		(width 0.14605)
		(layer "In2.Cu")
		(net "HDD_PRSNT6")
	)
	(segment
		(start 14.1986 -375.354596)
		(end 14.1986 -366.060228)
		(width 0.14605)
		(layer "In2.Cu")
		(net "HDD_PRSNT6")
	)
	(segment
		(start 14.50975 -258.587748)
		(end 13.992352 -258.070096)
		(width 0.14605)
		(layer "In2.Cu")
		(net "HDD_PRSNT6")
	)
	(segment
		(start 10.348214 -456.617832)
		(end 10.48004 -456.617832)
		(width 0.14605)
		(layer "In2.Cu")
		(net "HDD_PRSNT6")
	)
	(segment
		(start 13.992352 -256.86004)
		(end 13.429488 -256.297176)
		(width 0.14605)
		(layer "In2.Cu")
		(net "HDD_PRSNT6")
	)
	(segment
		(start 10.467594 -455.658728)
		(end 10.055098 -455.246232)
		(width 0.14605)
		(layer "In2.Cu")
		(net "HDD_PRSNT6")
	)
	(segment
		(start 13.429488 -256.297176)
		(end 13.429488 -217.648282)
		(width 0.14605)
		(layer "In2.Cu")
		(net "HDD_PRSNT6")
	)
	(segment
		(start 8.287512 -452.900542)
		(end 8.287512 -439.520076)
		(width 0.14605)
		(layer "In2.Cu")
		(net "HDD_PRSNT6")
	)
	(segment
		(start 10.760964 -455.939652)
		(end 10.48004 -455.658728)
		(width 0.14605)
		(layer "In2.Cu")
		(net "HDD_PRSNT6")
	)
	(segment
		(start 13.429488 -217.648282)
		(end 13.36294 -217.581734)
		(width 0.14605)
		(layer "In2.Cu")
		(net "HDD_PRSNT6")
	)
	(segment
		(start 13.73759 -267.527786)
		(end 13.737336 -267.527532)
		(width 0.14605)
		(layer "In2.Cu")
		(net "HDD_PRSNT6")
	)
	(segment
		(start 12.83589 -434.971698)
		(end 12.83589 -414.622996)
		(width 0.14605)
		(layer "In2.Cu")
		(net "HDD_PRSNT6")
	)
	(segment
		(start 102.209346 -439.1279)
		(end 87.629746 -453.7075)
		(width 0.14605)
		(layer "In5.Cu")
		(net "HDD_PRSNT6")
	)
	(segment
		(start 27.355546 -456.5269)
		(end 21.742146 -456.5269)
		(width 0.14605)
		(layer "In5.Cu")
		(net "HDD_PRSNT6")
	)
	(segment
		(start 30.174946 -453.7075)
		(end 27.355546 -456.5269)
		(width 0.14605)
		(layer "In5.Cu")
		(net "HDD_PRSNT6")
	)
	(segment
		(start 102.285546 -399.920714)
		(end 102.285546 -399.94332)
		(width 0.14605)
		(layer "In5.Cu")
		(net "HDD_PRSNT6")
	)
	(segment
		(start 102.333298 -399.991072)
		(end 102.333298 -400.388328)
		(width 0.14605)
		(layer "In5.Cu")
		(net "HDD_PRSNT6")
	)
	(segment
		(start 102.234746 -375.1199)
		(end 102.234746 -399.869914)
		(width 0.14605)
		(layer "In5.Cu")
		(net "HDD_PRSNT6")
	)
	(segment
		(start 102.285546 -399.94332)
		(end 102.333298 -399.991072)
		(width 0.14605)
		(layer "In5.Cu")
		(net "HDD_PRSNT6")
	)
	(segment
		(start 102.333298 -400.388328)
		(end 102.209346 -400.51228)
		(width 0.14605)
		(layer "In5.Cu")
		(net "HDD_PRSNT6")
	)
	(segment
		(start 50.547778 -453.7075)
		(end 30.174946 -453.7075)
		(width 0.14605)
		(layer "In5.Cu")
		(net "HDD_PRSNT6")
	)
	(segment
		(start 87.629746 -453.7075)
		(end 51.813714 -453.7075)
		(width 0.14605)
		(layer "In5.Cu")
		(net "HDD_PRSNT6")
	)
	(segment
		(start 50.60823 -453.767952)
		(end 50.547778 -453.7075)
		(width 0.14605)
		(layer "In5.Cu")
		(net "HDD_PRSNT6")
	)
	(segment
		(start 51.813714 -453.7075)
		(end 51.753262 -453.767952)
		(width 0.14605)
		(layer "In5.Cu")
		(net "HDD_PRSNT6")
	)
	(segment
		(start 51.753262 -453.767952)
		(end 50.60823 -453.767952)
		(width 0.14605)
		(layer "In5.Cu")
		(net "HDD_PRSNT6")
	)
	(segment
		(start 102.209346 -400.51228)
		(end 102.209346 -439.1279)
		(width 0.14605)
		(layer "In5.Cu")
		(net "HDD_PRSNT6")
	)
	(segment
		(start 102.234746 -399.869914)
		(end 102.285546 -399.920714)
		(width 0.14605)
		(layer "In5.Cu")
		(net "HDD_PRSNT6")
	)
	(segment
		(start 6.674866 -150.500334)
		(end 3.19405 -150.500334)
		(width 0.111252)
		(layer "F.Cu")
		(net "HB_EXP_B_INPUT")
	)
	(segment
		(start 7.011416 -150.1775)
		(end 6.818376 -150.37054)
		(width 0.111252)
		(layer "F.Cu")
		(net "HB_EXP_B_INPUT")
	)
	(segment
		(start 13.5636 -157.326838)
		(end 13.558774 -157.322012)
		(width 0.111252)
		(layer "F.Cu")
		(net "HB_EXP_B_INPUT")
	)
	(segment
		(start 11.5697 -150.1775)
		(end 7.011416 -150.1775)
		(width 0.111252)
		(layer "F.Cu")
		(net "HB_EXP_B_INPUT")
	)
	(segment
		(start 13.553948 -157.144466)
		(end 13.553948 -152.161748)
		(width 0.111252)
		(layer "F.Cu")
		(net "HB_EXP_B_INPUT")
	)
	(segment
		(start 12.3063 -161.417)
		(end 13.5636 -160.1597)
		(width 0.111252)
		(layer "F.Cu")
		(net "HB_EXP_B_INPUT")
	)
	(segment
		(start 13.558774 -157.149292)
		(end 13.553948 -157.144466)
		(width 0.111252)
		(layer "F.Cu")
		(net "HB_EXP_B_INPUT")
	)
	(segment
		(start 13.553948 -152.161748)
		(end 11.5697 -150.1775)
		(width 0.111252)
		(layer "F.Cu")
		(net "HB_EXP_B_INPUT")
	)
	(segment
		(start 13.558774 -157.322012)
		(end 13.558774 -157.149292)
		(width 0.111252)
		(layer "F.Cu")
		(net "HB_EXP_B_INPUT")
	)
	(segment
		(start 13.5636 -160.147)
		(end 13.5636 -157.326838)
		(width 0.111252)
		(layer "F.Cu")
		(net "HB_EXP_B_INPUT")
	)
	(segment
		(start 6.80466 -150.37054)
		(end 6.674866 -150.500334)
		(width 0.111252)
		(layer "F.Cu")
		(net "HB_EXP_B_INPUT")
	)
	(segment
		(start 13.5636 -160.1597)
		(end 13.5636 -160.147)
		(width 0.111252)
		(layer "F.Cu")
		(net "HB_EXP_B_INPUT")
	)
	(segment
		(start 3.19405 -150.500334)
		(end 3.192526 -150.49881)
		(width 0.111252)
		(layer "F.Cu")
		(net "HB_EXP_B_INPUT")
	)
	(segment
		(start 6.818376 -150.37054)
		(end 6.80466 -150.37054)
		(width 0.111252)
		(layer "F.Cu")
		(net "HB_EXP_B_INPUT")
	)
	(via
		(at 13.5636 -160.147)
		(size 0.7112)
		(drill 0.3556)
		(layers "F.Cu" "B.Cu")
		(net "HB_EXP_B_INPUT")
	)
	(segment
		(start 77.533246 -86.1187)
		(end 77.533246 -87.2617)
		(width 0.111252)
		(layer "F.Cu")
		(net "SW_PWR_HDD9")
	)
	(segment
		(start 76.823316 -87.364316)
		(end 75.946 -86.487)
		(width 0.111252)
		(layer "F.Cu")
		(net "SW_PWR_HDD9")
	)
	(segment
		(start 77.533246 -84.8487)
		(end 77.533246 -86.1187)
		(width 0.111252)
		(layer "F.Cu")
		(net "SW_PWR_HDD9")
	)
	(segment
		(start 77.43063 -87.364316)
		(end 76.823316 -87.364316)
		(width 0.111252)
		(layer "F.Cu")
		(net "SW_PWR_HDD9")
	)
	(segment
		(start 77.533246 -87.2617)
		(end 77.43063 -87.364316)
		(width 0.111252)
		(layer "F.Cu")
		(net "SW_PWR_HDD9")
	)
	(via
		(at 75.946 -86.487)
		(size 0.7112)
		(drill 0.3556)
		(layers "F.Cu" "B.Cu")
		(net "SW_PWR_HDD9")
	)
	(segment
		(start 4.880864 -386.50037)
		(end 4.87934 -386.498846)
		(width 0.09525)
		(layer "F.Cu")
		(net "SAS2X28_A_HDD6_TX_-")
	)
	(segment
		(start 31.05531 -362.86694)
		(end 30.297882 -362.86694)
		(width 0.09525)
		(layer "F.Cu")
		(net "SAS2X28_A_HDD6_TX_-")
	)
	(segment
		(start 4.87934 -386.498846)
		(end 3.192526 -386.498846)
		(width 0.09525)
		(layer "F.Cu")
		(net "SAS2X28_A_HDD6_TX_-")
	)
	(segment
		(start 37.280088 -363.33684)
		(end 37.269928 -363.33684)
		(width 0.09525)
		(layer "F.Cu")
		(net "SAS2X28_A_HDD6_TX_-")
	)
	(segment
		(start 7.619746 -386.160772)
		(end 5.700776 -386.160772)
		(width 0.09525)
		(layer "F.Cu")
		(net "SAS2X28_A_HDD6_TX_-")
	)
	(segment
		(start 29.95803 -363.007656)
		(end 29.863288 -363.102652)
		(width 0.09525)
		(layer "F.Cu")
		(net "SAS2X28_A_HDD6_TX_-")
	)
	(segment
		(start 36.321746 -362.86694)
		(end 32.2707 -362.86694)
		(width 0.09525)
		(layer "F.Cu")
		(net "SAS2X28_A_HDD6_TX_-")
	)
	(segment
		(start 36.702746 -363.10189)
		(end 36.57092 -362.970318)
		(width 0.09525)
		(layer "F.Cu")
		(net "SAS2X28_A_HDD6_TX_-")
	)
	(segment
		(start 31.80588 -363.09935)
		(end 31.52013 -363.09935)
		(width 0.09525)
		(layer "F.Cu")
		(net "SAS2X28_A_HDD6_TX_-")
	)
	(segment
		(start 38.250114 -363.340142)
		(end 37.28339 -363.340142)
		(width 0.09525)
		(layer "F.Cu")
		(net "SAS2X28_A_HDD6_TX_-")
	)
	(segment
		(start 37.28339 -363.340142)
		(end 37.280088 -363.33684)
		(width 0.09525)
		(layer "F.Cu")
		(net "SAS2X28_A_HDD6_TX_-")
	)
	(segment
		(start 8.127746 -386.461)
		(end 7.974584 -386.307584)
		(width 0.09525)
		(layer "F.Cu")
		(net "SAS2X28_A_HDD6_TX_-")
	)
	(via
		(at 29.81706 -363.213904)
		(size 0.5588)
		(drill 0.3048)
		(layers "F.Cu" "B.Cu")
		(net "SAS2X28_A_HDD6_TX_-")
	)
	(via
		(at 8.127746 -386.461)
		(size 0.5588)
		(drill 0.3048)
		(layers "F.Cu" "B.Cu")
		(net "SAS2X28_A_HDD6_TX_-")
	)
	(arc
		(start 32.03829 -362.983272)
		(mid 31.936173 -363.069503)
		(end 31.80588 -363.09935)
		(width 0.09525)
		(layer "F.Cu")
		(net "SAS2X28_A_HDD6_TX_-")
	)
	(arc
		(start 5.700776 -386.160772)
		(mid 5.492667 -386.202167)
		(end 5.31622 -386.32003)
		(width 0.09525)
		(layer "F.Cu")
		(net "SAS2X28_A_HDD6_TX_-")
	)
	(arc
		(start 36.57092 -362.970318)
		(mid 36.456613 -362.893848)
		(end 36.321746 -362.86694)
		(width 0.09525)
		(layer "F.Cu")
		(net "SAS2X28_A_HDD6_TX_-")
	)
	(arc
		(start 37.269928 -363.33684)
		(mid 36.962965 -363.275781)
		(end 36.702746 -363.10189)
		(width 0.09525)
		(layer "F.Cu")
		(net "SAS2X28_A_HDD6_TX_-")
	)
	(arc
		(start 30.297882 -362.86694)
		(mid 30.113962 -362.903506)
		(end 29.95803 -363.007656)
		(width 0.09525)
		(layer "F.Cu")
		(net "SAS2X28_A_HDD6_TX_-")
	)
	(arc
		(start 7.974584 -386.307584)
		(mid 7.811768 -386.198887)
		(end 7.619746 -386.160772)
		(width 0.09525)
		(layer "F.Cu")
		(net "SAS2X28_A_HDD6_TX_-")
	)
	(arc
		(start 31.28772 -362.983272)
		(mid 31.185646 -362.896873)
		(end 31.05531 -362.86694)
		(width 0.09525)
		(layer "F.Cu")
		(net "SAS2X28_A_HDD6_TX_-")
	)
	(arc
		(start 32.2707 -362.86694)
		(mid 32.140365 -362.896876)
		(end 32.03829 -362.983272)
		(width 0.09525)
		(layer "F.Cu")
		(net "SAS2X28_A_HDD6_TX_-")
	)
	(arc
		(start 5.31622 -386.32003)
		(mid 5.116477 -386.453494)
		(end 4.880864 -386.50037)
		(width 0.09525)
		(layer "F.Cu")
		(net "SAS2X28_A_HDD6_TX_-")
	)
	(arc
		(start 31.52013 -363.09935)
		(mid 31.389812 -363.069553)
		(end 31.28772 -362.983272)
		(width 0.09525)
		(layer "F.Cu")
		(net "SAS2X28_A_HDD6_TX_-")
	)
	(arc
		(start 29.863288 -363.102652)
		(mid 29.829099 -363.15368)
		(end 29.81706 -363.213904)
		(width 0.09525)
		(layer "F.Cu")
		(net "SAS2X28_A_HDD6_TX_-")
	)
	(segment
		(start 10.162032 -385.587494)
		(end 9.990836 -385.75869)
		(width 0.09525)
		(layer "B.Cu")
		(net "SAS2X28_A_HDD6_TX_-")
	)
	(segment
		(start 11.759946 -378.472954)
		(end 11.759946 -383.076704)
		(width 0.09525)
		(layer "B.Cu")
		(net "SAS2X28_A_HDD6_TX_-")
	)
	(segment
		(start 8.189214 -386.399786)
		(end 8.127746 -386.461)
		(width 0.09525)
		(layer "B.Cu")
		(net "SAS2X28_A_HDD6_TX_-")
	)
	(segment
		(start 13.118592 -376.0978)
		(end 13.118846 -376.098054)
		(width 0.09525)
		(layer "B.Cu")
		(net "SAS2X28_A_HDD6_TX_-")
	)
	(segment
		(start 25.749504 -363.466888)
		(end 13.118592 -376.0978)
		(width 0.09525)
		(layer "B.Cu")
		(net "SAS2X28_A_HDD6_TX_-")
	)
	(segment
		(start 9.016746 -386.162042)
		(end 8.762746 -386.162042)
		(width 0.09525)
		(layer "B.Cu")
		(net "SAS2X28_A_HDD6_TX_-")
	)
	(segment
		(start 12.5476 -376.6693)
		(end 12.47902 -376.738134)
		(width 0.09525)
		(layer "B.Cu")
		(net "SAS2X28_A_HDD6_TX_-")
	)
	(segment
		(start 13.118846 -376.098054)
		(end 12.5476 -376.6693)
		(width 0.09525)
		(layer "B.Cu")
		(net "SAS2X28_A_HDD6_TX_-")
	)
	(segment
		(start 27.050746 -362.9279)
		(end 27.050492 -362.927646)
		(width 0.09525)
		(layer "B.Cu")
		(net "SAS2X28_A_HDD6_TX_-")
	)
	(segment
		(start 11.114786 -384.634994)
		(end 10.162032 -385.587494)
		(width 0.09525)
		(layer "B.Cu")
		(net "SAS2X28_A_HDD6_TX_-")
	)
	(segment
		(start 12.47902 -376.738134)
		(end 12.478004 -376.73915)
		(width 0.09525)
		(layer "B.Cu")
		(net "SAS2X28_A_HDD6_TX_-")
	)
	(segment
		(start 11.760708 -378.415042)
		(end 11.760454 -378.421138)
		(width 0.09525)
		(layer "B.Cu")
		(net "SAS2X28_A_HDD6_TX_-")
	)
	(segment
		(start 11.981942 -377.453652)
		(end 11.981688 -377.454414)
		(width 0.09525)
		(layer "B.Cu")
		(net "SAS2X28_A_HDD6_TX_-")
	)
	(segment
		(start 29.126688 -362.9279)
		(end 27.050746 -362.9279)
		(width 0.09525)
		(layer "B.Cu")
		(net "SAS2X28_A_HDD6_TX_-")
	)
	(arc
		(start 27.050492 -362.927646)
		(mid 26.346374 -363.067891)
		(end 25.749504 -363.466888)
		(width 0.09525)
		(layer "B.Cu")
		(net "SAS2X28_A_HDD6_TX_-")
	)
	(arc
		(start 29.81706 -363.213904)
		(mid 29.500315 -363.002262)
		(end 29.126688 -362.9279)
		(width 0.09525)
		(layer "B.Cu")
		(net "SAS2X28_A_HDD6_TX_-")
	)
	(arc
		(start 8.762746 -386.162042)
		(mid 8.452338 -386.22388)
		(end 8.189214 -386.399786)
		(width 0.09525)
		(layer "B.Cu")
		(net "SAS2X28_A_HDD6_TX_-")
	)
	(arc
		(start 11.760454 -378.421138)
		(mid 11.760046 -378.447044)
		(end 11.759946 -378.472954)
		(width 0.09525)
		(layer "B.Cu")
		(net "SAS2X28_A_HDD6_TX_-")
	)
	(arc
		(start 11.759946 -383.076704)
		(mid 11.592384 -383.920035)
		(end 11.114786 -384.634994)
		(width 0.09525)
		(layer "B.Cu")
		(net "SAS2X28_A_HDD6_TX_-")
	)
	(arc
		(start 12.478004 -376.73915)
		(mid 12.198028 -377.074225)
		(end 11.981942 -377.453652)
		(width 0.09525)
		(layer "B.Cu")
		(net "SAS2X28_A_HDD6_TX_-")
	)
	(arc
		(start 9.990836 -385.75869)
		(mid 9.543919 -386.057281)
		(end 9.016746 -386.162042)
		(width 0.09525)
		(layer "B.Cu")
		(net "SAS2X28_A_HDD6_TX_-")
	)
	(arc
		(start 11.981688 -377.454414)
		(mid 11.822431 -377.923511)
		(end 11.760708 -378.415042)
		(width 0.09525)
		(layer "B.Cu")
		(net "SAS2X28_A_HDD6_TX_-")
	)
	(segment
		(start 76.656946 -190.5127)
		(end 76.479146 -190.6905)
		(width 0.111252)
		(layer "F.Cu")
		(net "SW_PWR_HDD8")
	)
	(segment
		(start 77.914246 -190.5127)
		(end 76.656946 -190.5127)
		(width 0.111252)
		(layer "F.Cu")
		(net "SW_PWR_HDD8")
	)
	(segment
		(start 77.914246 -188.4807)
		(end 77.914246 -189.4967)
		(width 0.111252)
		(layer "F.Cu")
		(net "SW_PWR_HDD8")
	)
	(segment
		(start 77.914246 -189.4967)
		(end 77.914246 -190.5127)
		(width 0.111252)
		(layer "F.Cu")
		(net "SW_PWR_HDD8")
	)
	(via
		(at 76.479146 -190.6905)
		(size 0.7112)
		(drill 0.3556)
		(layers "F.Cu" "B.Cu")
		(net "SW_PWR_HDD8")
	)
	(segment
		(start 37.5666 -362.06684)
		(end 36.937696 -362.06684)
		(width 0.09525)
		(layer "F.Cu")
		(net "SAS2X28_A_HDD6_TX_+")
	)
	(segment
		(start 7.619746 -385.830572)
		(end 5.683504 -385.830572)
		(width 0.09525)
		(layer "F.Cu")
		(net "SAS2X28_A_HDD6_TX_+")
	)
	(segment
		(start 38.250114 -362.070142)
		(end 37.569902 -362.070142)
		(width 0.09525)
		(layer "F.Cu")
		(net "SAS2X28_A_HDD6_TX_+")
	)
	(segment
		(start 29.95803 -362.396024)
		(end 29.81706 -362.255054)
		(width 0.09525)
		(layer "F.Cu")
		(net "SAS2X28_A_HDD6_TX_+")
	)
	(segment
		(start 37.569902 -362.070142)
		(end 37.5666 -362.06684)
		(width 0.09525)
		(layer "F.Cu")
		(net "SAS2X28_A_HDD6_TX_+")
	)
	(segment
		(start 4.886198 -385.500372)
		(end 4.884674 -385.498848)
		(width 0.09525)
		(layer "F.Cu")
		(net "SAS2X28_A_HDD6_TX_+")
	)
	(segment
		(start 4.884674 -385.498848)
		(end 3.192526 -385.498848)
		(width 0.09525)
		(layer "F.Cu")
		(net "SAS2X28_A_HDD6_TX_+")
	)
	(segment
		(start 8.127746 -385.532884)
		(end 7.979664 -385.680966)
		(width 0.09525)
		(layer "F.Cu")
		(net "SAS2X28_A_HDD6_TX_+")
	)
	(segment
		(start 36.467796 -362.53674)
		(end 30.297882 -362.53674)
		(width 0.09525)
		(layer "F.Cu")
		(net "SAS2X28_A_HDD6_TX_+")
	)
	(via
		(at 8.127746 -385.532884)
		(size 0.5588)
		(drill 0.3048)
		(layers "F.Cu" "B.Cu")
		(net "SAS2X28_A_HDD6_TX_+")
	)
	(via
		(at 29.81706 -362.255054)
		(size 0.5588)
		(drill 0.3048)
		(layers "F.Cu" "B.Cu")
		(net "SAS2X28_A_HDD6_TX_+")
	)
	(arc
		(start 30.297882 -362.53674)
		(mid 30.113962 -362.500174)
		(end 29.95803 -362.396024)
		(width 0.09525)
		(layer "F.Cu")
		(net "SAS2X28_A_HDD6_TX_+")
	)
	(arc
		(start 36.937696 -362.06684)
		(mid 36.771561 -362.135655)
		(end 36.702746 -362.30179)
		(width 0.09525)
		(layer "F.Cu")
		(net "SAS2X28_A_HDD6_TX_+")
	)
	(arc
		(start 5.574538 -385.81965)
		(mid 5.42089 -385.764682)
		(end 5.289804 -385.667504)
		(width 0.09525)
		(layer "F.Cu")
		(net "SAS2X28_A_HDD6_TX_+")
	)
	(arc
		(start 36.702746 -362.30179)
		(mid 36.633931 -362.467925)
		(end 36.467796 -362.53674)
		(width 0.09525)
		(layer "F.Cu")
		(net "SAS2X28_A_HDD6_TX_+")
	)
	(arc
		(start 5.289804 -385.667504)
		(mid 5.104628 -385.543773)
		(end 4.886198 -385.500372)
		(width 0.09525)
		(layer "F.Cu")
		(net "SAS2X28_A_HDD6_TX_+")
	)
	(arc
		(start 5.683504 -385.830572)
		(mid 5.628752 -385.827798)
		(end 5.574538 -385.81965)
		(width 0.09525)
		(layer "F.Cu")
		(net "SAS2X28_A_HDD6_TX_+")
	)
	(arc
		(start 7.695692 -385.82473)
		(mid 7.657828 -385.82907)
		(end 7.619746 -385.830572)
		(width 0.09525)
		(layer "F.Cu")
		(net "SAS2X28_A_HDD6_TX_+")
	)
	(arc
		(start 7.979664 -385.680966)
		(mid 7.849174 -385.775563)
		(end 7.695692 -385.82473)
		(width 0.09525)
		(layer "F.Cu")
		(net "SAS2X28_A_HDD6_TX_+")
	)
	(segment
		(start 9.016746 -385.831842)
		(end 8.762746 -385.831842)
		(width 0.09525)
		(layer "B.Cu")
		(net "SAS2X28_A_HDD6_TX_+")
	)
	(segment
		(start 10.881106 -384.401314)
		(end 9.928606 -385.353814)
		(width 0.09525)
		(layer "B.Cu")
		(net "SAS2X28_A_HDD6_TX_+")
	)
	(segment
		(start 25.515824 -363.233208)
		(end 22.607016 -366.142016)
		(width 0.09525)
		(layer "B.Cu")
		(net "SAS2X28_A_HDD6_TX_+")
	)
	(segment
		(start 8.189214 -385.594098)
		(end 8.127746 -385.532884)
		(width 0.09525)
		(layer "B.Cu")
		(net "SAS2X28_A_HDD6_TX_+")
	)
	(segment
		(start 12.65174 -376.098054)
		(end 12.313666 -376.435874)
		(width 0.09525)
		(layer "B.Cu")
		(net "SAS2X28_A_HDD6_TX_+")
	)
	(segment
		(start 22.607016 -366.142016)
		(end 12.651486 -376.0978)
		(width 0.09525)
		(layer "B.Cu")
		(net "SAS2X28_A_HDD6_TX_+")
	)
	(segment
		(start 12.313666 -376.435874)
		(end 12.245086 -376.504708)
		(width 0.09525)
		(layer "B.Cu")
		(net "SAS2X28_A_HDD6_TX_+")
	)
	(segment
		(start 12.651486 -376.0978)
		(end 12.65174 -376.098054)
		(width 0.09525)
		(layer "B.Cu")
		(net "SAS2X28_A_HDD6_TX_+")
	)
	(segment
		(start 9.928606 -385.353814)
		(end 9.757156 -385.52501)
		(width 0.09525)
		(layer "B.Cu")
		(net "SAS2X28_A_HDD6_TX_+")
	)
	(segment
		(start 29.209746 -362.5977)
		(end 27.017726 -362.5977)
		(width 0.09525)
		(layer "B.Cu")
		(net "SAS2X28_A_HDD6_TX_+")
	)
	(segment
		(start 11.429746 -378.4727)
		(end 11.429746 -383.076704)
		(width 0.09525)
		(layer "B.Cu")
		(net "SAS2X28_A_HDD6_TX_+")
	)
	(segment
		(start 29.81706 -362.255054)
		(end 29.661612 -362.410502)
		(width 0.09525)
		(layer "B.Cu")
		(net "SAS2X28_A_HDD6_TX_+")
	)
	(arc
		(start 11.429746 -383.076704)
		(mid 11.287153 -383.793566)
		(end 10.881106 -384.401314)
		(width 0.09525)
		(layer "B.Cu")
		(net "SAS2X28_A_HDD6_TX_+")
	)
	(arc
		(start 8.762746 -385.831842)
		(mid 8.452338 -385.770004)
		(end 8.189214 -385.594098)
		(width 0.09525)
		(layer "B.Cu")
		(net "SAS2X28_A_HDD6_TX_+")
	)
	(arc
		(start 11.680952 -377.317254)
		(mid 11.500451 -377.849506)
		(end 11.430508 -378.407168)
		(width 0.09525)
		(layer "B.Cu")
		(net "SAS2X28_A_HDD6_TX_+")
	)
	(arc
		(start 29.661612 -362.410502)
		(mid 29.454294 -362.549027)
		(end 29.209746 -362.5977)
		(width 0.09525)
		(layer "B.Cu")
		(net "SAS2X28_A_HDD6_TX_+")
	)
	(arc
		(start 9.757156 -385.52501)
		(mid 9.417481 -385.7521)
		(end 9.016746 -385.831842)
		(width 0.09525)
		(layer "B.Cu")
		(net "SAS2X28_A_HDD6_TX_+")
	)
	(arc
		(start 11.430508 -378.407168)
		(mid 11.429935 -378.439932)
		(end 11.429746 -378.4727)
		(width 0.09525)
		(layer "B.Cu")
		(net "SAS2X28_A_HDD6_TX_+")
	)
	(arc
		(start 27.017726 -362.5977)
		(mid 26.204833 -362.769058)
		(end 25.515824 -363.233208)
		(width 0.09525)
		(layer "B.Cu")
		(net "SAS2X28_A_HDD6_TX_+")
	)
	(arc
		(start 12.245086 -376.504708)
		(mid 11.926633 -376.885719)
		(end 11.680952 -377.317254)
		(width 0.09525)
		(layer "B.Cu")
		(net "SAS2X28_A_HDD6_TX_+")
	)
	(segment
		(start 25.907746 -276.0472)
		(end 26.507694 -276.647148)
		(width 0.111252)
		(layer "F.Cu")
		(net "SW_PWR_HDD7")
	)
	(segment
		(start 26.507694 -276.647148)
		(end 31.175198 -276.647148)
		(width 0.111252)
		(layer "F.Cu")
		(net "SW_PWR_HDD7")
	)
	(segment
		(start 34.289746 -279.3492)
		(end 34.289746 -277.6347)
		(width 0.111252)
		(layer "F.Cu")
		(net "SW_PWR_HDD7")
	)
	(segment
		(start 32.638746 -281.0002)
		(end 34.289746 -279.3492)
		(width 0.111252)
		(layer "F.Cu")
		(net "SW_PWR_HDD7")
	)
	(segment
		(start 30.352746 -281.0002)
		(end 32.638746 -281.0002)
		(width 0.111252)
		(layer "F.Cu")
		(net "SW_PWR_HDD7")
	)
	(segment
		(start 34.289746 -277.6347)
		(end 32.892746 -276.2377)
		(width 0.111252)
		(layer "F.Cu")
		(net "SW_PWR_HDD7")
	)
	(segment
		(start 31.584646 -276.2377)
		(end 32.003746 -276.2377)
		(width 0.111252)
		(layer "F.Cu")
		(net "SW_PWR_HDD7")
	)
	(segment
		(start 32.892746 -276.2377)
		(end 32.003746 -276.2377)
		(width 0.111252)
		(layer "F.Cu")
		(net "SW_PWR_HDD7")
	)
	(segment
		(start 24.764746 -276.0472)
		(end 25.907746 -276.0472)
		(width 0.111252)
		(layer "F.Cu")
		(net "SW_PWR_HDD7")
	)
	(segment
		(start 31.175198 -276.647148)
		(end 31.584646 -276.2377)
		(width 0.111252)
		(layer "F.Cu")
		(net "SW_PWR_HDD7")
	)
	(via
		(at 32.003746 -276.2377)
		(size 0.7112)
		(drill 0.3556)
		(layers "F.Cu" "B.Cu")
		(net "SW_PWR_HDD7")
	)
	(segment
		(start 32.003746 -372.5799)
		(end 31.951676 -372.5799)
		(width 0.09525)
		(layer "F.Cu")
		(net "SAS2X28_B_HDD6_RX_-")
	)
	(segment
		(start 32.42056 -372.298214)
		(end 32.234378 -372.484396)
		(width 0.09525)
		(layer "F.Cu")
		(net "SAS2X28_B_HDD6_RX_-")
	)
	(via
		(at 31.447232 -372.1227)
		(size 0.5588)
		(drill 0.3048)
		(layers "F.Cu" "B.Cu")
		(net "SAS2X28_B_HDD6_RX_-")
	)
	(arc
		(start 31.951676 -372.5799)
		(mid 31.7459 -372.538969)
		(end 31.571438 -372.42242)
		(width 0.09525)
		(layer "F.Cu")
		(net "SAS2X28_B_HDD6_RX_-")
	)
	(arc
		(start 32.234378 -372.484396)
		(mid 32.128563 -372.555099)
		(end 32.003746 -372.5799)
		(width 0.09525)
		(layer "F.Cu")
		(net "SAS2X28_B_HDD6_RX_-")
	)
	(arc
		(start 31.571438 -372.42242)
		(mid 31.479501 -372.284922)
		(end 31.447232 -372.1227)
		(width 0.09525)
		(layer "F.Cu")
		(net "SAS2X28_B_HDD6_RX_-")
	)
	(segment
		(start 2.811526 -148.498814)
		(end 4.688586 -148.498814)
		(width 0.09525)
		(layer "B.Cu")
		(net "SAS2X28_B_HDD6_RX_-")
	)
	(segment
		(start 21.386546 -162.445954)
		(end 21.386546 -162.944556)
		(width 0.09525)
		(layer "B.Cu")
		(net "SAS2X28_B_HDD6_RX_-")
	)
	(segment
		(start 38.417754 -182.508906)
		(end 38.417754 -193.900806)
		(width 0.09525)
		(layer "B.Cu")
		(net "SAS2X28_B_HDD6_RX_-")
	)
	(segment
		(start 38.4175 -182.50916)
		(end 38.417754 -182.508906)
		(width 0.09525)
		(layer "B.Cu")
		(net "SAS2X28_B_HDD6_RX_-")
	)
	(segment
		(start 7.937246 -148.4122)
		(end 9.397492 -149.872446)
		(width 0.09525)
		(layer "B.Cu")
		(net "SAS2X28_B_HDD6_RX_-")
	)
	(segment
		(start 9.397492 -149.872446)
		(end 9.397492 -149.8727)
		(width 0.09525)
		(layer "B.Cu")
		(net "SAS2X28_B_HDD6_RX_-")
	)
	(segment
		(start 49.478946 -206.182722)
		(end 49.478946 -299.093636)
		(width 0.09525)
		(layer "B.Cu")
		(net "SAS2X28_B_HDD6_RX_-")
	)
	(segment
		(start 44.163488 -362.20146)
		(end 44.163488 -364.0455)
		(width 0.09525)
		(layer "B.Cu")
		(net "SAS2X28_B_HDD6_RX_-")
	)
	(segment
		(start 44.163488 -353.179126)
		(end 44.163488 -360.98607)
		(width 0.09525)
		(layer "B.Cu")
		(net "SAS2X28_B_HDD6_RX_-")
	)
	(segment
		(start 31.447232 -372.345204)
		(end 31.447232 -372.1227)
		(width 0.09525)
		(layer "B.Cu")
		(net "SAS2X28_B_HDD6_RX_-")
	)
	(segment
		(start 22.11832 -164.71138)
		(end 22.118066 -164.71138)
		(width 0.09525)
		(layer "B.Cu")
		(net "SAS2X28_B_HDD6_RX_-")
	)
	(segment
		(start 43.806364 -352.496628)
		(end 43.933364 -352.623628)
		(width 0.09525)
		(layer "B.Cu")
		(net "SAS2X28_B_HDD6_RX_-")
	)
	(segment
		(start 49.209706 -299.743368)
		(end 44.015406 -304.937668)
		(width 0.09525)
		(layer "B.Cu")
		(net "SAS2X28_B_HDD6_RX_-")
	)
	(segment
		(start 22.118066 -164.71138)
		(end 37.358066 -179.95138)
		(width 0.09525)
		(layer "B.Cu")
		(net "SAS2X28_B_HDD6_RX_-")
	)
	(segment
		(start 38.790372 -194.800474)
		(end 48.988472 -204.998574)
		(width 0.09525)
		(layer "B.Cu")
		(net "SAS2X28_B_HDD6_RX_-")
	)
	(segment
		(start 43.484546 -306.219352)
		(end 43.484546 -351.719642)
		(width 0.09525)
		(layer "B.Cu")
		(net "SAS2X28_B_HDD6_RX_-")
	)
	(segment
		(start 43.931078 -361.45089)
		(end 43.931078 -361.73664)
		(width 0.09525)
		(layer "B.Cu")
		(net "SAS2X28_B_HDD6_RX_-")
	)
	(segment
		(start 9.397492 -149.8727)
		(end 20.973288 -161.448496)
		(width 0.09525)
		(layer "B.Cu")
		(net "SAS2X28_B_HDD6_RX_-")
	)
	(segment
		(start 43.877992 -364.734094)
		(end 36.340796 -372.27129)
		(width 0.09525)
		(layer "B.Cu")
		(net "SAS2X28_B_HDD6_RX_-")
	)
	(segment
		(start 35.432492 -372.647718)
		(end 31.749746 -372.647718)
		(width 0.09525)
		(layer "B.Cu")
		(net "SAS2X28_B_HDD6_RX_-")
	)
	(segment
		(start 4.688586 -148.498814)
		(end 4.69011 -148.500338)
		(width 0.09525)
		(layer "B.Cu")
		(net "SAS2X28_B_HDD6_RX_-")
	)
	(segment
		(start 5.510022 -148.16074)
		(end 7.33044 -148.16074)
		(width 0.09525)
		(layer "B.Cu")
		(net "SAS2X28_B_HDD6_RX_-")
	)
	(arc
		(start 21.386546 -162.944556)
		(mid 21.576673 -163.900768)
		(end 22.11832 -164.71138)
		(width 0.09525)
		(layer "B.Cu")
		(net "SAS2X28_B_HDD6_RX_-")
	)
	(arc
		(start 44.047156 -361.96905)
		(mid 44.133555 -362.071124)
		(end 44.163488 -362.20146)
		(width 0.09525)
		(layer "B.Cu")
		(net "SAS2X28_B_HDD6_RX_-")
	)
	(arc
		(start 49.478946 -299.093636)
		(mid 49.408963 -299.445283)
		(end 49.209706 -299.743368)
		(width 0.09525)
		(layer "B.Cu")
		(net "SAS2X28_B_HDD6_RX_-")
	)
	(arc
		(start 43.931078 -361.73664)
		(mid 43.960875 -361.866958)
		(end 44.047156 -361.96905)
		(width 0.09525)
		(layer "B.Cu")
		(net "SAS2X28_B_HDD6_RX_-")
	)
	(arc
		(start 4.69011 -148.500338)
		(mid 4.96626 -148.445408)
		(end 5.200396 -148.28901)
		(width 0.09525)
		(layer "B.Cu")
		(net "SAS2X28_B_HDD6_RX_-")
	)
	(arc
		(start 44.047156 -361.21848)
		(mid 43.960925 -361.320597)
		(end 43.931078 -361.45089)
		(width 0.09525)
		(layer "B.Cu")
		(net "SAS2X28_B_HDD6_RX_-")
	)
	(arc
		(start 43.484546 -351.719642)
		(mid 43.56824 -352.140111)
		(end 43.806364 -352.496628)
		(width 0.09525)
		(layer "B.Cu")
		(net "SAS2X28_B_HDD6_RX_-")
	)
	(arc
		(start 37.358066 -179.95138)
		(mid 38.142187 -181.124899)
		(end 38.4175 -182.50916)
		(width 0.09525)
		(layer "B.Cu")
		(net "SAS2X28_B_HDD6_RX_-")
	)
	(arc
		(start 31.749746 -372.647718)
		(mid 31.535836 -372.559114)
		(end 31.447232 -372.345204)
		(width 0.09525)
		(layer "B.Cu")
		(net "SAS2X28_B_HDD6_RX_-")
	)
	(arc
		(start 43.933364 -352.623628)
		(mid 44.103659 -352.878493)
		(end 44.163488 -353.179126)
		(width 0.09525)
		(layer "B.Cu")
		(net "SAS2X28_B_HDD6_RX_-")
	)
	(arc
		(start 44.163488 -364.0455)
		(mid 44.089242 -364.4182)
		(end 43.877992 -364.734094)
		(width 0.09525)
		(layer "B.Cu")
		(net "SAS2X28_B_HDD6_RX_-")
	)
	(arc
		(start 44.163488 -360.98607)
		(mid 44.133552 -361.116405)
		(end 44.047156 -361.21848)
		(width 0.09525)
		(layer "B.Cu")
		(net "SAS2X28_B_HDD6_RX_-")
	)
	(arc
		(start 7.33044 -148.16074)
		(mid 7.658856 -148.226102)
		(end 7.937246 -148.4122)
		(width 0.09525)
		(layer "B.Cu")
		(net "SAS2X28_B_HDD6_RX_-")
	)
	(arc
		(start 38.417754 -193.900806)
		(mid 38.514533 -194.387728)
		(end 38.790372 -194.800474)
		(width 0.09525)
		(layer "B.Cu")
		(net "SAS2X28_B_HDD6_RX_-")
	)
	(arc
		(start 48.988472 -204.998574)
		(mid 49.351488 -205.541866)
		(end 49.478946 -206.182722)
		(width 0.09525)
		(layer "B.Cu")
		(net "SAS2X28_B_HDD6_RX_-")
	)
	(arc
		(start 36.340796 -372.27129)
		(mid 35.924091 -372.54985)
		(end 35.432492 -372.647718)
		(width 0.09525)
		(layer "B.Cu")
		(net "SAS2X28_B_HDD6_RX_-")
	)
	(arc
		(start 5.200396 -148.28901)
		(mid 5.342454 -148.19409)
		(end 5.510022 -148.16074)
		(width 0.09525)
		(layer "B.Cu")
		(net "SAS2X28_B_HDD6_RX_-")
	)
	(arc
		(start 44.015406 -304.937668)
		(mid 43.622514 -305.525723)
		(end 43.484546 -306.219352)
		(width 0.09525)
		(layer "B.Cu")
		(net "SAS2X28_B_HDD6_RX_-")
	)
	(arc
		(start 20.973288 -161.448496)
		(mid 21.279125 -161.906119)
		(end 21.386546 -162.445954)
		(width 0.09525)
		(layer "B.Cu")
		(net "SAS2X28_B_HDD6_RX_-")
	)
	(segment
		(start 77.025246 -394.8557)
		(end 77.025246 -393.9032)
		(width 0.111252)
		(layer "F.Cu")
		(net "SW_PWR_HDD6")
	)
	(segment
		(start 77.025246 -393.9032)
		(end 77.342746 -393.5857)
		(width 0.111252)
		(layer "F.Cu")
		(net "SW_PWR_HDD6")
	)
	(segment
		(start 77.025246 -395.8717)
		(end 77.025246 -394.8557)
		(width 0.111252)
		(layer "F.Cu")
		(net "SW_PWR_HDD6")
	)
	(segment
		(start 77.025246 -396.8877)
		(end 77.025246 -395.8717)
		(width 0.111252)
		(layer "F.Cu")
		(net "SW_PWR_HDD6")
	)
	(via
		(at 77.342746 -393.5857)
		(size 0.7112)
		(drill 0.3556)
		(layers "F.Cu" "B.Cu")
		(net "SW_PWR_HDD6")
	)
	(segment
		(start 31.56966 -373.187214)
		(end 32.42056 -373.187214)
		(width 0.09525)
		(layer "F.Cu")
		(net "SAS2X28_B_HDD6_RX_+")
	)
	(via
		(at 31.56966 -373.187214)
		(size 0.5588)
		(drill 0.3048)
		(layers "F.Cu" "B.Cu")
		(net "SAS2X28_B_HDD6_RX_+")
	)
	(segment
		(start 44.167044 -352.390202)
		(end 44.040044 -352.263202)
		(width 0.09525)
		(layer "B.Cu")
		(net "SAS2X28_B_HDD6_RX_+")
	)
	(segment
		(start 21.206968 -161.214816)
		(end 8.170672 -148.17852)
		(width 0.09525)
		(layer "B.Cu")
		(net "SAS2X28_B_HDD6_RX_+")
	)
	(segment
		(start 36.574476 -372.50497)
		(end 44.119546 -364.9599)
		(width 0.09525)
		(layer "B.Cu")
		(net "SAS2X28_B_HDD6_RX_+")
	)
	(segment
		(start 4.660646 -147.498816)
		(end 2.811526 -147.498816)
		(width 0.09525)
		(layer "B.Cu")
		(net "SAS2X28_B_HDD6_RX_+")
	)
	(segment
		(start 44.493688 -364.056676)
		(end 44.493688 -353.178872)
		(width 0.09525)
		(layer "B.Cu")
		(net "SAS2X28_B_HDD6_RX_+")
	)
	(segment
		(start 21.716746 -162.944556)
		(end 21.716746 -162.4457)
		(width 0.09525)
		(layer "B.Cu")
		(net "SAS2X28_B_HDD6_RX_+")
	)
	(segment
		(start 7.330694 -147.83054)
		(end 5.459222 -147.83054)
		(width 0.09525)
		(layer "B.Cu")
		(net "SAS2X28_B_HDD6_RX_+")
	)
	(segment
		(start 44.249086 -305.171094)
		(end 49.443386 -299.976794)
		(width 0.09525)
		(layer "B.Cu")
		(net "SAS2X28_B_HDD6_RX_+")
	)
	(segment
		(start 4.66217 -147.50034)
		(end 4.660646 -147.498816)
		(width 0.09525)
		(layer "B.Cu")
		(net "SAS2X28_B_HDD6_RX_+")
	)
	(segment
		(start 43.814746 -351.719388)
		(end 43.814746 -306.219606)
		(width 0.09525)
		(layer "B.Cu")
		(net "SAS2X28_B_HDD6_RX_+")
	)
	(segment
		(start 32.074866 -372.977918)
		(end 35.432746 -372.977918)
		(width 0.09525)
		(layer "B.Cu")
		(net "SAS2X28_B_HDD6_RX_+")
	)
	(segment
		(start 49.809146 -299.09389)
		(end 49.809146 -206.182722)
		(width 0.09525)
		(layer "B.Cu")
		(net "SAS2X28_B_HDD6_RX_+")
	)
	(segment
		(start 37.591746 -179.7177)
		(end 22.351746 -164.4777)
		(width 0.09525)
		(layer "B.Cu")
		(net "SAS2X28_B_HDD6_RX_+")
	)
	(segment
		(start 49.221898 -204.764894)
		(end 39.023798 -194.566794)
		(width 0.09525)
		(layer "B.Cu")
		(net "SAS2X28_B_HDD6_RX_+")
	)
	(segment
		(start 38.747954 -193.90106)
		(end 38.747954 -182.50916)
		(width 0.09525)
		(layer "B.Cu")
		(net "SAS2X28_B_HDD6_RX_+")
	)
	(arc
		(start 21.716746 -162.4457)
		(mid 21.584261 -161.779563)
		(end 21.206968 -161.214816)
		(width 0.09525)
		(layer "B.Cu")
		(net "SAS2X28_B_HDD6_RX_+")
	)
	(arc
		(start 38.747954 -182.50916)
		(mid 38.447456 -180.998453)
		(end 37.591746 -179.7177)
		(width 0.09525)
		(layer "B.Cu")
		(net "SAS2X28_B_HDD6_RX_+")
	)
	(arc
		(start 5.459222 -147.83054)
		(mid 5.318863 -147.802621)
		(end 5.199888 -147.723098)
		(width 0.09525)
		(layer "B.Cu")
		(net "SAS2X28_B_HDD6_RX_+")
	)
	(arc
		(start 5.199888 -147.723098)
		(mid 4.953181 -147.558254)
		(end 4.66217 -147.50034)
		(width 0.09525)
		(layer "B.Cu")
		(net "SAS2X28_B_HDD6_RX_+")
	)
	(arc
		(start 35.432746 -372.977918)
		(mid 36.050657 -372.855008)
		(end 36.574476 -372.50497)
		(width 0.09525)
		(layer "B.Cu")
		(net "SAS2X28_B_HDD6_RX_+")
	)
	(arc
		(start 8.170672 -148.17852)
		(mid 7.785287 -147.921014)
		(end 7.330694 -147.83054)
		(width 0.09525)
		(layer "B.Cu")
		(net "SAS2X28_B_HDD6_RX_+")
	)
	(arc
		(start 44.119546 -364.9599)
		(mid 44.396441 -364.545497)
		(end 44.493688 -364.056676)
		(width 0.09525)
		(layer "B.Cu")
		(net "SAS2X28_B_HDD6_RX_+")
	)
	(arc
		(start 44.040044 -352.263202)
		(mid 43.873331 -352.013698)
		(end 43.814746 -351.719388)
		(width 0.09525)
		(layer "B.Cu")
		(net "SAS2X28_B_HDD6_RX_+")
	)
	(arc
		(start 44.493688 -353.178872)
		(mid 44.408737 -352.752085)
		(end 44.167044 -352.390202)
		(width 0.09525)
		(layer "B.Cu")
		(net "SAS2X28_B_HDD6_RX_+")
	)
	(arc
		(start 49.443386 -299.976794)
		(mid 49.714052 -299.571714)
		(end 49.809146 -299.09389)
		(width 0.09525)
		(layer "B.Cu")
		(net "SAS2X28_B_HDD6_RX_+")
	)
	(arc
		(start 43.814746 -306.219606)
		(mid 43.927621 -305.652143)
		(end 44.249086 -305.171094)
		(width 0.09525)
		(layer "B.Cu")
		(net "SAS2X28_B_HDD6_RX_+")
	)
	(arc
		(start 22.351746 -164.4777)
		(mid 21.881741 -163.774288)
		(end 21.716746 -162.944556)
		(width 0.09525)
		(layer "B.Cu")
		(net "SAS2X28_B_HDD6_RX_+")
	)
	(arc
		(start 49.809146 -206.182722)
		(mid 49.656587 -205.415373)
		(end 49.221898 -204.764894)
		(width 0.09525)
		(layer "B.Cu")
		(net "SAS2X28_B_HDD6_RX_+")
	)
	(arc
		(start 39.023798 -194.566794)
		(mid 38.819679 -194.261353)
		(end 38.747954 -193.90106)
		(width 0.09525)
		(layer "B.Cu")
		(net "SAS2X28_B_HDD6_RX_+")
	)
	(arc
		(start 31.56966 -373.187214)
		(mid 31.80145 -373.032337)
		(end 32.074866 -372.977918)
		(width 0.09525)
		(layer "B.Cu")
		(net "SAS2X28_B_HDD6_RX_+")
	)
	(segment
		(start 77.774546 -492.00054)
		(end 77.774546 -492.3155)
		(width 0.111252)
		(layer "F.Cu")
		(net "SW_PWR_HDD5")
	)
	(segment
		(start 78.231746 -492.7727)
		(end 78.231746 -493.0267)
		(width 0.111252)
		(layer "F.Cu")
		(net "SW_PWR_HDD5")
	)
	(segment
		(start 78.767432 -495.115088)
		(end 78.767432 -496.145312)
		(width 0.111252)
		(layer "F.Cu")
		(net "SW_PWR_HDD5")
	)
	(segment
		(start 78.231746 -493.0267)
		(end 78.859634 -493.654588)
		(width 0.111252)
		(layer "F.Cu")
		(net "SW_PWR_HDD5")
	)
	(segment
		(start 78.859634 -495.022886)
		(end 78.767432 -495.115088)
		(width 0.111252)
		(layer "F.Cu")
		(net "SW_PWR_HDD5")
	)
	(segment
		(start 78.859634 -494.006886)
		(end 78.859634 -495.022886)
		(width 0.111252)
		(layer "F.Cu")
		(net "SW_PWR_HDD5")
	)
	(segment
		(start 77.774546 -492.3155)
		(end 78.231746 -492.7727)
		(width 0.111252)
		(layer "F.Cu")
		(net "SW_PWR_HDD5")
	)
	(segment
		(start 78.859634 -493.654588)
		(end 78.859634 -494.006886)
		(width 0.111252)
		(layer "F.Cu")
		(net "SW_PWR_HDD5")
	)
	(via
		(at 77.774546 -492.00054)
		(size 0.7112)
		(drill 0.3556)
		(layers "F.Cu" "B.Cu")
		(net "SW_PWR_HDD5")
	)
	(segment
		(start 7.526274 -389.398002)
		(end 6.628638 -388.500366)
		(width 0.111252)
		(layer "F.Cu")
		(net "SAS2X28_A_HDD6_FLT")
	)
	(segment
		(start 6.628638 -388.500366)
		(end 3.19405 -388.500366)
		(width 0.111252)
		(layer "F.Cu")
		(net "SAS2X28_A_HDD6_FLT")
	)
	(segment
		(start 71.500746 -394.8557)
		(end 71.500746 -394.0302)
		(width 0.111252)
		(layer "F.Cu")
		(net "SAS2X28_A_HDD6_FLT")
	)
	(segment
		(start 70.738746 -396.0622)
		(end 70.738746 -395.6177)
		(width 0.111252)
		(layer "F.Cu")
		(net "SAS2X28_A_HDD6_FLT")
	)
	(segment
		(start 70.738746 -395.6177)
		(end 71.119746 -395.2367)
		(width 0.111252)
		(layer "F.Cu")
		(net "SAS2X28_A_HDD6_FLT")
	)
	(segment
		(start 3.19405 -388.500366)
		(end 3.192526 -388.498842)
		(width 0.111252)
		(layer "F.Cu")
		(net "SAS2X28_A_HDD6_FLT")
	)
	(segment
		(start 71.119746 -395.2367)
		(end 71.500746 -394.8557)
		(width 0.111252)
		(layer "F.Cu")
		(net "SAS2X28_A_HDD6_FLT")
	)
	(via
		(at 7.526274 -389.398002)
		(size 0.5588)
		(drill 0.3048)
		(layers "F.Cu" "B.Cu")
		(net "SAS2X28_A_HDD6_FLT")
	)
	(via
		(at 21.59 -390.2583)
		(size 0.7112)
		(drill 0.3556)
		(layers "F.Cu" "B.Cu")
		(net "SAS2X28_A_HDD6_FLT")
	)
	(via
		(at 71.119746 -395.2367)
		(size 0.5588)
		(drill 0.3048)
		(layers "F.Cu" "B.Cu")
		(net "SAS2X28_A_HDD6_FLT")
	)
	(via
		(at 25.6032 -390.2583)
		(size 0.5588)
		(drill 0.3048)
		(layers "F.Cu" "B.Cu")
		(net "SAS2X28_A_HDD6_FLT")
	)
	(segment
		(start 9.420352 -390.555226)
		(end 19.474942 -390.555226)
		(width 0.111252)
		(layer "B.Cu")
		(net "SAS2X28_A_HDD6_FLT")
	)
	(segment
		(start 7.526274 -389.398002)
		(end 8.263128 -389.398002)
		(width 0.111252)
		(layer "B.Cu")
		(net "SAS2X28_A_HDD6_FLT")
	)
	(segment
		(start 21.59 -390.2583)
		(end 25.6032 -390.2583)
		(width 0.111252)
		(layer "B.Cu")
		(net "SAS2X28_A_HDD6_FLT")
	)
	(segment
		(start 19.771868 -390.2583)
		(end 21.59 -390.2583)
		(width 0.111252)
		(layer "B.Cu")
		(net "SAS2X28_A_HDD6_FLT")
	)
	(segment
		(start 19.474942 -390.555226)
		(end 19.771868 -390.2583)
		(width 0.111252)
		(layer "B.Cu")
		(net "SAS2X28_A_HDD6_FLT")
	)
	(segment
		(start 8.263128 -389.398002)
		(end 9.420352 -390.555226)
		(width 0.111252)
		(layer "B.Cu")
		(net "SAS2X28_A_HDD6_FLT")
	)
	(segment
		(start 38.7223 -390.2583)
		(end 25.6032 -390.2583)
		(width 0.14605)
		(layer "In2.Cu")
		(net "SAS2X28_A_HDD6_FLT")
	)
	(segment
		(start 43.7007 -395.2367)
		(end 38.7223 -390.2583)
		(width 0.14605)
		(layer "In2.Cu")
		(net "SAS2X28_A_HDD6_FLT")
	)
	(segment
		(start 71.119746 -395.2367)
		(end 43.7007 -395.2367)
		(width 0.14605)
		(layer "In2.Cu")
		(net "SAS2X28_A_HDD6_FLT")
	)
	(segment
		(start 21.844 -202.1078)
		(end 21.427948 -202.523852)
		(width 0.111252)
		(layer "F.Cu")
		(net "SAS_EXP_B_PWR9")
	)
	(segment
		(start 8.31723 -200.039224)
		(end 7.851902 -200.504552)
		(width 0.111252)
		(layer "F.Cu")
		(net "SAS_EXP_B_PWR9")
	)
	(segment
		(start 21.427948 -202.523852)
		(end 13.185394 -202.523852)
		(width 0.111252)
		(layer "F.Cu")
		(net "SAS_EXP_B_PWR9")
	)
	(segment
		(start 10.700766 -200.039224)
		(end 8.31723 -200.039224)
		(width 0.111252)
		(layer "F.Cu")
		(net "SAS_EXP_B_PWR9")
	)
	(segment
		(start 83.755992 -84.610956)
		(end 83.517232 -84.849716)
		(width 0.111252)
		(layer "F.Cu")
		(net "SAS_EXP_B_PWR9")
	)
	(segment
		(start 28.1178 -202.1078)
		(end 21.844 -202.1078)
		(width 0.111252)
		(layer "F.Cu")
		(net "SAS_EXP_B_PWR9")
	)
	(segment
		(start 82.930746 -84.849716)
		(end 81.723992 -84.849716)
		(width 0.111252)
		(layer "F.Cu")
		(net "SAS_EXP_B_PWR9")
	)
	(segment
		(start 13.185394 -202.523852)
		(end 10.700766 -200.039224)
		(width 0.111252)
		(layer "F.Cu")
		(net "SAS_EXP_B_PWR9")
	)
	(segment
		(start 7.851902 -200.504552)
		(end 3.19024 -200.504552)
		(width 0.111252)
		(layer "F.Cu")
		(net "SAS_EXP_B_PWR9")
	)
	(segment
		(start 83.517232 -84.849716)
		(end 82.930746 -84.849716)
		(width 0.111252)
		(layer "F.Cu")
		(net "SAS_EXP_B_PWR9")
	)
	(via
		(at 28.1178 -202.1078)
		(size 0.5588)
		(drill 0.3048)
		(layers "F.Cu" "B.Cu")
		(net "SAS_EXP_B_PWR9")
	)
	(via
		(at 81.406746 -202.7047)
		(size 0.5588)
		(drill 0.3048)
		(layers "F.Cu" "B.Cu")
		(net "SAS_EXP_B_PWR9")
	)
	(via
		(at 82.930746 -84.849716)
		(size 0.5588)
		(drill 0.3048)
		(layers "F.Cu" "B.Cu")
		(net "SAS_EXP_B_PWR9")
	)
	(via
		(at 82.168746 -84.2137)
		(size 0.7112)
		(drill 0.3556)
		(layers "F.Cu" "B.Cu")
		(net "SAS_EXP_B_PWR9")
	)
	(via
		(at 100.240846 -160.1724)
		(size 0.5588)
		(drill 0.3048)
		(layers "F.Cu" "B.Cu")
		(net "SAS_EXP_B_PWR9")
	)
	(segment
		(start 82.930746 -84.849716)
		(end 82.804762 -84.849716)
		(width 0.111252)
		(layer "B.Cu")
		(net "SAS_EXP_B_PWR9")
	)
	(segment
		(start 82.804762 -84.849716)
		(end 82.168746 -84.2137)
		(width 0.111252)
		(layer "B.Cu")
		(net "SAS_EXP_B_PWR9")
	)
	(segment
		(start 100.240846 -160.1724)
		(end 85.248496 -175.16475)
		(width 0.14605)
		(layer "In2.Cu")
		(net "SAS_EXP_B_PWR9")
	)
	(segment
		(start 85.248496 -198.86295)
		(end 81.406746 -202.7047)
		(width 0.14605)
		(layer "In2.Cu")
		(net "SAS_EXP_B_PWR9")
	)
	(segment
		(start 85.248496 -175.16475)
		(end 85.248496 -198.86295)
		(width 0.14605)
		(layer "In2.Cu")
		(net "SAS_EXP_B_PWR9")
	)
	(segment
		(start 28.1178 -202.1332)
		(end 28.1178 -202.1078)
		(width 0.14605)
		(layer "In5.Cu")
		(net "SAS_EXP_B_PWR9")
	)
	(segment
		(start 27.765248 -202.485752)
		(end 28.1178 -202.1332)
		(width 0.14605)
		(layer "In5.Cu")
		(net "SAS_EXP_B_PWR9")
	)
	(segment
		(start 100.215446 -103.866188)
		(end 100.215446 -160.147)
		(width 0.14605)
		(layer "In5.Cu")
		(net "SAS_EXP_B_PWR9")
	)
	(segment
		(start 28.046172 -203.539852)
		(end 27.765248 -203.258928)
		(width 0.14605)
		(layer "In5.Cu")
		(net "SAS_EXP_B_PWR9")
	)
	(segment
		(start 27.765248 -203.258928)
		(end 27.765248 -202.485752)
		(width 0.14605)
		(layer "In5.Cu")
		(net "SAS_EXP_B_PWR9")
	)
	(segment
		(start 82.930746 -84.849716)
		(end 100.120196 -102.039166)
		(width 0.14605)
		(layer "In5.Cu")
		(net "SAS_EXP_B_PWR9")
	)
	(segment
		(start 100.215446 -160.147)
		(end 100.240846 -160.1724)
		(width 0.14605)
		(layer "In5.Cu")
		(net "SAS_EXP_B_PWR9")
	)
	(segment
		(start 78.741016 -202.7047)
		(end 77.905864 -203.539852)
		(width 0.14605)
		(layer "In5.Cu")
		(net "SAS_EXP_B_PWR9")
	)
	(segment
		(start 100.120196 -103.770938)
		(end 100.215446 -103.866188)
		(width 0.14605)
		(layer "In5.Cu")
		(net "SAS_EXP_B_PWR9")
	)
	(segment
		(start 81.406746 -202.7047)
		(end 78.741016 -202.7047)
		(width 0.14605)
		(layer "In5.Cu")
		(net "SAS_EXP_B_PWR9")
	)
	(segment
		(start 77.905864 -203.539852)
		(end 28.046172 -203.539852)
		(width 0.14605)
		(layer "In5.Cu")
		(net "SAS_EXP_B_PWR9")
	)
	(segment
		(start 100.120196 -102.039166)
		(end 100.120196 -103.770938)
		(width 0.14605)
		(layer "In5.Cu")
		(net "SAS_EXP_B_PWR9")
	)
	(segment
		(start 190.811912 -82.276696)
		(end 190.811912 -83.546696)
		(width 0.111252)
		(layer "F.Cu")
		(net "SW_PWR_HDD4")
	)
	(segment
		(start 190.15075 -82.276696)
		(end 190.811912 -82.276696)
		(width 0.111252)
		(layer "F.Cu")
		(net "SW_PWR_HDD4")
	)
	(segment
		(start 189.357 -84.074)
		(end 189.357 -84.963)
		(width 0.111252)
		(layer "F.Cu")
		(net "SW_PWR_HDD4")
	)
	(segment
		(start 189.357 -84.963)
		(end 189.738 -85.344)
		(width 0.111252)
		(layer "F.Cu")
		(net "SW_PWR_HDD4")
	)
	(segment
		(start 189.738 -85.344)
		(end 191.173608 -85.344)
		(width 0.111252)
		(layer "F.Cu")
		(net "SW_PWR_HDD4")
	)
	(segment
		(start 191.173608 -85.344)
		(end 191.256412 -85.261196)
		(width 0.111252)
		(layer "F.Cu")
		(net "SW_PWR_HDD4")
	)
	(segment
		(start 189.884304 -83.546696)
		(end 189.357 -84.074)
		(width 0.111252)
		(layer "F.Cu")
		(net "SW_PWR_HDD4")
	)
	(segment
		(start 190.811912 -83.546696)
		(end 189.884304 -83.546696)
		(width 0.111252)
		(layer "F.Cu")
		(net "SW_PWR_HDD4")
	)
	(segment
		(start 189.737746 -82.6897)
		(end 190.15075 -82.276696)
		(width 0.111252)
		(layer "F.Cu")
		(net "SW_PWR_HDD4")
	)
	(via
		(at 189.737746 -82.6897)
		(size 0.7112)
		(drill 0.3556)
		(layers "F.Cu" "B.Cu")
		(net "SW_PWR_HDD4")
	)
	(segment
		(start 72.008746 -395.2367)
		(end 72.150986 -395.09446)
		(width 0.111252)
		(layer "F.Cu")
		(net "SAS2X28_B_HDD6_FLT")
	)
	(segment
		(start 10.150602 -139.500356)
		(end 3.19405 -139.500356)
		(width 0.111252)
		(layer "F.Cu")
		(net "SAS2X28_B_HDD6_FLT")
	)
	(segment
		(start 72.150986 -395.09446)
		(end 72.150986 -394.0302)
		(width 0.111252)
		(layer "F.Cu")
		(net "SAS2X28_B_HDD6_FLT")
	)
	(segment
		(start 71.754746 -396.0622)
		(end 71.754746 -395.4907)
		(width 0.111252)
		(layer "F.Cu")
		(net "SAS2X28_B_HDD6_FLT")
	)
	(segment
		(start 11.759946 -140.4493)
		(end 11.099546 -140.4493)
		(width 0.111252)
		(layer "F.Cu")
		(net "SAS2X28_B_HDD6_FLT")
	)
	(segment
		(start 3.19405 -139.500356)
		(end 3.192526 -139.498832)
		(width 0.111252)
		(layer "F.Cu")
		(net "SAS2X28_B_HDD6_FLT")
	)
	(segment
		(start 71.754746 -395.4907)
		(end 72.008746 -395.2367)
		(width 0.111252)
		(layer "F.Cu")
		(net "SAS2X28_B_HDD6_FLT")
	)
	(segment
		(start 11.099546 -140.4493)
		(end 10.150602 -139.500356)
		(width 0.111252)
		(layer "F.Cu")
		(net "SAS2X28_B_HDD6_FLT")
	)
	(via
		(at 72.008746 -395.2367)
		(size 0.5588)
		(drill 0.3048)
		(layers "F.Cu" "B.Cu")
		(net "SAS2X28_B_HDD6_FLT")
	)
	(via
		(at 93.001846 -394.7287)
		(size 0.5588)
		(drill 0.3048)
		(layers "F.Cu" "B.Cu")
		(net "SAS2X28_B_HDD6_FLT")
	)
	(via
		(at 11.759946 -140.4493)
		(size 0.5588)
		(drill 0.3048)
		(layers "F.Cu" "B.Cu")
		(net "SAS2X28_B_HDD6_FLT")
	)
	(via
		(at 72.864472 -395.625828)
		(size 0.7112)
		(drill 0.3556)
		(layers "F.Cu" "B.Cu")
		(net "SAS2X28_B_HDD6_FLT")
	)
	(segment
		(start 72.008746 -395.2367)
		(end 72.465946 -395.2367)
		(width 0.111252)
		(layer "B.Cu")
		(net "SAS2X28_B_HDD6_FLT")
	)
	(segment
		(start 72.855074 -395.625828)
		(end 72.864472 -395.625828)
		(width 0.111252)
		(layer "B.Cu")
		(net "SAS2X28_B_HDD6_FLT")
	)
	(segment
		(start 72.465946 -395.2367)
		(end 72.855074 -395.625828)
		(width 0.111252)
		(layer "B.Cu")
		(net "SAS2X28_B_HDD6_FLT")
	)
	(segment
		(start 92.373196 -395.4018)
		(end 93.001846 -394.77315)
		(width 0.14605)
		(layer "In2.Cu")
		(net "SAS2X28_B_HDD6_FLT")
	)
	(segment
		(start 72.173846 -395.4018)
		(end 92.373196 -395.4018)
		(width 0.14605)
		(layer "In2.Cu")
		(net "SAS2X28_B_HDD6_FLT")
	)
	(segment
		(start 93.001846 -394.77315)
		(end 93.001846 -394.7287)
		(width 0.14605)
		(layer "In2.Cu")
		(net "SAS2X28_B_HDD6_FLT")
	)
	(segment
		(start 72.008746 -395.2367)
		(end 72.173846 -395.4018)
		(width 0.14605)
		(layer "In2.Cu")
		(net "SAS2X28_B_HDD6_FLT")
	)
	(segment
		(start 11.759946 -140.4493)
		(end 11.759946 -140.18133)
		(width 0.14605)
		(layer "In5.Cu")
		(net "SAS2X28_B_HDD6_FLT")
	)
	(segment
		(start 93.062298 -106.808016)
		(end 93.062298 -394.668248)
		(width 0.14605)
		(layer "In5.Cu")
		(net "SAS2X28_B_HDD6_FLT")
	)
	(segment
		(start 21.096986 -101.826314)
		(end 88.080596 -101.826314)
		(width 0.14605)
		(layer "In5.Cu")
		(net "SAS2X28_B_HDD6_FLT")
	)
	(segment
		(start 12.039854 -139.901422)
		(end 12.039854 -135.368284)
		(width 0.14605)
		(layer "In5.Cu")
		(net "SAS2X28_B_HDD6_FLT")
	)
	(segment
		(start 13.389102 -129.277364)
		(end 12.950698 -128.83896)
		(width 0.14605)
		(layer "In5.Cu")
		(net "SAS2X28_B_HDD6_FLT")
	)
	(segment
		(start 88.080596 -101.826314)
		(end 93.062298 -106.808016)
		(width 0.14605)
		(layer "In5.Cu")
		(net "SAS2X28_B_HDD6_FLT")
	)
	(segment
		(start 12.950698 -109.972602)
		(end 21.096986 -101.826314)
		(width 0.14605)
		(layer "In5.Cu")
		(net "SAS2X28_B_HDD6_FLT")
	)
	(segment
		(start 13.389102 -134.019036)
		(end 13.389102 -129.277364)
		(width 0.14605)
		(layer "In5.Cu")
		(net "SAS2X28_B_HDD6_FLT")
	)
	(segment
		(start 93.062298 -394.668248)
		(end 93.001846 -394.7287)
		(width 0.14605)
		(layer "In5.Cu")
		(net "SAS2X28_B_HDD6_FLT")
	)
	(segment
		(start 11.759946 -140.18133)
		(end 12.039854 -139.901422)
		(width 0.14605)
		(layer "In5.Cu")
		(net "SAS2X28_B_HDD6_FLT")
	)
	(segment
		(start 12.950698 -128.83896)
		(end 12.950698 -109.972602)
		(width 0.14605)
		(layer "In5.Cu")
		(net "SAS2X28_B_HDD6_FLT")
	)
	(segment
		(start 12.039854 -135.368284)
		(end 13.389102 -134.019036)
		(width 0.14605)
		(layer "In5.Cu")
		(net "SAS2X28_B_HDD6_FLT")
	)
	(segment
		(start 190.618364 -186.908948)
		(end 190.803784 -186.723528)
		(width 0.111252)
		(layer "F.Cu")
		(net "SW_PWR_HDD3")
	)
	(segment
		(start 190.092838 -186.908948)
		(end 190.618364 -186.908948)
		(width 0.111252)
		(layer "F.Cu")
		(net "SW_PWR_HDD3")
	)
	(segment
		(start 189.504574 -186.913774)
		(end 190.088012 -186.913774)
		(width 0.111252)
		(layer "F.Cu")
		(net "SW_PWR_HDD3")
	)
	(segment
		(start 190.486284 -185.390028)
		(end 189.640972 -185.390028)
		(width 0.111252)
		(layer "F.Cu")
		(net "SW_PWR_HDD3")
	)
	(segment
		(start 190.486284 -184.120028)
		(end 189.449456 -184.120028)
		(width 0.111252)
		(layer "F.Cu")
		(net "SW_PWR_HDD3")
	)
	(segment
		(start 190.088012 -186.913774)
		(end 190.092838 -186.908948)
		(width 0.111252)
		(layer "F.Cu")
		(net "SW_PWR_HDD3")
	)
	(segment
		(start 189.23 -185.801)
		(end 189.23 -186.6392)
		(width 0.111252)
		(layer "F.Cu")
		(net "SW_PWR_HDD3")
	)
	(segment
		(start 189.449456 -184.120028)
		(end 189.406784 -184.1627)
		(width 0.111252)
		(layer "F.Cu")
		(net "SW_PWR_HDD3")
	)
	(segment
		(start 189.640972 -185.390028)
		(end 189.23 -185.801)
		(width 0.111252)
		(layer "F.Cu")
		(net "SW_PWR_HDD3")
	)
	(segment
		(start 190.486284 -185.390028)
		(end 189.406784 -184.310528)
		(width 0.111252)
		(layer "F.Cu")
		(net "SW_PWR_HDD3")
	)
	(segment
		(start 189.23 -186.6392)
		(end 189.504574 -186.913774)
		(width 0.111252)
		(layer "F.Cu")
		(net "SW_PWR_HDD3")
	)
	(segment
		(start 189.406784 -184.310528)
		(end 189.406784 -184.1627)
		(width 0.111252)
		(layer "F.Cu")
		(net "SW_PWR_HDD3")
	)
	(via
		(at 189.406784 -184.1627)
		(size 0.7112)
		(drill 0.3556)
		(layers "F.Cu" "B.Cu")
		(net "SW_PWR_HDD3")
	)
	(segment
		(start 54.800246 -349.7072)
		(end 50.939446 -349.7072)
		(width 0.111252)
		(layer "F.Cu")
		(net "DRIVE_ACT_6")
	)
	(segment
		(start 49.466246 -349.7707)
		(end 50.875946 -349.7707)
		(width 0.111252)
		(layer "F.Cu")
		(net "DRIVE_ACT_6")
	)
	(segment
		(start 49.466246 -350.7867)
		(end 49.466246 -349.7707)
		(width 0.111252)
		(layer "F.Cu")
		(net "DRIVE_ACT_6")
	)
	(segment
		(start 50.875946 -349.7707)
		(end 50.939446 -349.7072)
		(width 0.111252)
		(layer "F.Cu")
		(net "DRIVE_ACT_6")
	)
	(segment
		(start 54.990746 -349.8977)
		(end 54.800246 -349.7072)
		(width 0.111252)
		(layer "F.Cu")
		(net "DRIVE_ACT_6")
	)
	(via
		(at 54.990746 -349.8977)
		(size 0.7112)
		(drill 0.3556)
		(layers "F.Cu" "B.Cu")
		(net "DRIVE_ACT_6")
	)
	(segment
		(start 6.072886 -397.500348)
		(end 3.19405 -397.500348)
		(width 0.111252)
		(layer "F.Cu")
		(net "SAS2X28_A_HDD5_FLT")
	)
	(segment
		(start 71.126858 -495.700812)
		(end 70.865746 -495.4397)
		(width 0.111252)
		(layer "F.Cu")
		(net "SAS2X28_A_HDD5_FLT")
	)
	(segment
		(start 72.681846 -494.421414)
		(end 72.681846 -493.4458)
		(width 0.111252)
		(layer "F.Cu")
		(net "SAS2X28_A_HDD5_FLT")
	)
	(segment
		(start 72.389746 -494.713514)
		(end 72.681846 -494.421414)
		(width 0.111252)
		(layer "F.Cu")
		(net "SAS2X28_A_HDD5_FLT")
	)
	(segment
		(start 6.482334 -397.0909)
		(end 6.072886 -397.500348)
		(width 0.111252)
		(layer "F.Cu")
		(net "SAS2X28_A_HDD5_FLT")
	)
	(segment
		(start 70.865746 -495.4397)
		(end 71.591932 -494.713514)
		(width 0.111252)
		(layer "F.Cu")
		(net "SAS2X28_A_HDD5_FLT")
	)
	(segment
		(start 71.591932 -494.713514)
		(end 72.389746 -494.713514)
		(width 0.111252)
		(layer "F.Cu")
		(net "SAS2X28_A_HDD5_FLT")
	)
	(segment
		(start 72.226932 -495.700812)
		(end 71.126858 -495.700812)
		(width 0.111252)
		(layer "F.Cu")
		(net "SAS2X28_A_HDD5_FLT")
	)
	(segment
		(start 3.19405 -397.500348)
		(end 3.192526 -397.498824)
		(width 0.111252)
		(layer "F.Cu")
		(net "SAS2X28_A_HDD5_FLT")
	)
	(via
		(at 72.389746 -494.713514)
		(size 0.5588)
		(drill 0.3048)
		(layers "F.Cu" "B.Cu")
		(net "SAS2X28_A_HDD5_FLT")
	)
	(via
		(at 6.482334 -397.0909)
		(size 0.5588)
		(drill 0.3048)
		(layers "F.Cu" "B.Cu")
		(net "SAS2X28_A_HDD5_FLT")
	)
	(via
		(at 70.865746 -495.4397)
		(size 0.7112)
		(drill 0.3556)
		(layers "F.Cu" "B.Cu")
		(net "SAS2X28_A_HDD5_FLT")
	)
	(segment
		(start 6.825488 -460.934054)
		(end 6.83514 -460.885286)
		(width 0.14605)
		(layer "In5.Cu")
		(net "SAS2X28_A_HDD5_FLT")
	)
	(segment
		(start 5.698744 -465.514436)
		(end 5.698744 -462.060798)
		(width 0.14605)
		(layer "In5.Cu")
		(net "SAS2X28_A_HDD5_FLT")
	)
	(segment
		(start 9.337294 -405.938482)
		(end 9.892792 -405.382984)
		(width 0.14605)
		(layer "In5.Cu")
		(net "SAS2X28_A_HDD5_FLT")
	)
	(segment
		(start 8.344662 -468.837772)
		(end 8.344662 -468.160354)
		(width 0.14605)
		(layer "In5.Cu")
		(net "SAS2X28_A_HDD5_FLT")
	)
	(segment
		(start 31.835344 -473.579698)
		(end 13.086842 -473.579698)
		(width 0.14605)
		(layer "In5.Cu")
		(net "SAS2X28_A_HDD5_FLT")
	)
	(segment
		(start 8.344662 -468.160354)
		(end 5.698744 -465.514436)
		(width 0.14605)
		(layer "In5.Cu")
		(net "SAS2X28_A_HDD5_FLT")
	)
	(segment
		(start 6.83514 -458.594968)
		(end 5.17525 -456.935078)
		(width 0.14605)
		(layer "In5.Cu")
		(net "SAS2X28_A_HDD5_FLT")
	)
	(segment
		(start 9.340088 -410.197808)
		(end 9.337294 -410.195014)
		(width 0.14605)
		(layer "In5.Cu")
		(net "SAS2X28_A_HDD5_FLT")
	)
	(segment
		(start 5.17525 -456.935078)
		(end 5.17525 -444.110872)
		(width 0.14605)
		(layer "In5.Cu")
		(net "SAS2X28_A_HDD5_FLT")
	)
	(segment
		(start 9.892792 -400.360388)
		(end 10.385552 -399.867628)
		(width 0.14605)
		(layer "In5.Cu")
		(net "SAS2X28_A_HDD5_FLT")
	)
	(segment
		(start 13.086842 -473.579698)
		(end 12.906248 -473.399104)
		(width 0.14605)
		(layer "In5.Cu")
		(net "SAS2X28_A_HDD5_FLT")
	)
	(segment
		(start 72.389746 -494.713514)
		(end 70.623684 -494.713514)
		(width 0.14605)
		(layer "In5.Cu")
		(net "SAS2X28_A_HDD5_FLT")
	)
	(segment
		(start 8.961374 -398.260062)
		(end 7.792212 -397.0909)
		(width 0.14605)
		(layer "In5.Cu")
		(net "SAS2X28_A_HDD5_FLT")
	)
	(segment
		(start 5.698744 -462.060798)
		(end 6.825488 -460.934054)
		(width 0.14605)
		(layer "In5.Cu")
		(net "SAS2X28_A_HDD5_FLT")
	)
	(segment
		(start 9.340088 -429.77435)
		(end 9.340088 -410.197808)
		(width 0.14605)
		(layer "In5.Cu")
		(net "SAS2X28_A_HDD5_FLT")
	)
	(segment
		(start 9.892792 -405.382984)
		(end 9.892792 -400.360388)
		(width 0.14605)
		(layer "In5.Cu")
		(net "SAS2X28_A_HDD5_FLT")
	)
	(segment
		(start 12.906248 -473.399104)
		(end 12.905994 -473.399104)
		(width 0.14605)
		(layer "In5.Cu")
		(net "SAS2X28_A_HDD5_FLT")
	)
	(segment
		(start 9.337294 -410.195014)
		(end 9.337294 -405.938482)
		(width 0.14605)
		(layer "In5.Cu")
		(net "SAS2X28_A_HDD5_FLT")
	)
	(segment
		(start 66.0654 -490.15523)
		(end 66.0654 -485.389174)
		(width 0.14605)
		(layer "In5.Cu")
		(net "SAS2X28_A_HDD5_FLT")
	)
	(segment
		(start 56.70423 -476.028004)
		(end 34.28365 -476.028004)
		(width 0.14605)
		(layer "In5.Cu")
		(net "SAS2X28_A_HDD5_FLT")
	)
	(segment
		(start 70.623684 -494.713514)
		(end 66.0654 -490.15523)
		(width 0.14605)
		(layer "In5.Cu")
		(net "SAS2X28_A_HDD5_FLT")
	)
	(segment
		(start 3.228594 -435.885844)
		(end 9.340088 -429.77435)
		(width 0.14605)
		(layer "In5.Cu")
		(net "SAS2X28_A_HDD5_FLT")
	)
	(segment
		(start 66.0654 -485.389174)
		(end 56.70423 -476.028004)
		(width 0.14605)
		(layer "In5.Cu")
		(net "SAS2X28_A_HDD5_FLT")
	)
	(segment
		(start 5.17525 -444.110872)
		(end 3.228594 -442.164216)
		(width 0.14605)
		(layer "In5.Cu")
		(net "SAS2X28_A_HDD5_FLT")
	)
	(segment
		(start 3.228594 -442.164216)
		(end 3.228594 -435.885844)
		(width 0.14605)
		(layer "In5.Cu")
		(net "SAS2X28_A_HDD5_FLT")
	)
	(segment
		(start 10.385552 -398.742154)
		(end 9.90346 -398.260062)
		(width 0.14605)
		(layer "In5.Cu")
		(net "SAS2X28_A_HDD5_FLT")
	)
	(segment
		(start 34.28365 -476.028004)
		(end 31.835344 -473.579698)
		(width 0.14605)
		(layer "In5.Cu")
		(net "SAS2X28_A_HDD5_FLT")
	)
	(segment
		(start 9.90346 -398.260062)
		(end 8.961374 -398.260062)
		(width 0.14605)
		(layer "In5.Cu")
		(net "SAS2X28_A_HDD5_FLT")
	)
	(segment
		(start 7.792212 -397.0909)
		(end 6.482334 -397.0909)
		(width 0.14605)
		(layer "In5.Cu")
		(net "SAS2X28_A_HDD5_FLT")
	)
	(segment
		(start 12.905994 -473.399104)
		(end 8.344662 -468.837772)
		(width 0.14605)
		(layer "In5.Cu")
		(net "SAS2X28_A_HDD5_FLT")
	)
	(segment
		(start 6.83514 -460.885286)
		(end 6.83514 -458.594968)
		(width 0.14605)
		(layer "In5.Cu")
		(net "SAS2X28_A_HDD5_FLT")
	)
	(segment
		(start 10.385552 -399.867628)
		(end 10.385552 -398.742154)
		(width 0.14605)
		(layer "In5.Cu")
		(net "SAS2X28_A_HDD5_FLT")
	)
	(segment
		(start 189.977014 -287.373568)
		(end 189.382146 -286.7787)
		(width 0.111252)
		(layer "F.Cu")
		(net "SW_PWR_HDD2")
	)
	(segment
		(start 190.057278 -286.103568)
		(end 189.382146 -286.7787)
		(width 0.111252)
		(layer "F.Cu")
		(net "SW_PWR_HDD2")
	)
	(segment
		(start 190.880746 -289.6362)
		(end 190.648082 -289.403536)
		(width 0.111252)
		(layer "F.Cu")
		(net "SW_PWR_HDD2")
	)
	(segment
		(start 190.648082 -287.373568)
		(end 189.977014 -287.373568)
		(width 0.111252)
		(layer "F.Cu")
		(net "SW_PWR_HDD2")
	)
	(segment
		(start 190.648082 -286.103568)
		(end 190.057278 -286.103568)
		(width 0.111252)
		(layer "F.Cu")
		(net "SW_PWR_HDD2")
	)
	(segment
		(start 190.648082 -289.403536)
		(end 190.648082 -287.373568)
		(width 0.111252)
		(layer "F.Cu")
		(net "SW_PWR_HDD2")
	)
	(via
		(at 189.382146 -286.7787)
		(size 0.7112)
		(drill 0.3556)
		(layers "F.Cu" "B.Cu")
		(net "SW_PWR_HDD2")
	)
	(segment
		(start 190.932816 -390.219184)
		(end 190.3222 -390.8298)
		(width 0.111252)
		(layer "F.Cu")
		(net "SW_PWR_HDD1")
	)
	(segment
		(start 191.408558 -390.219184)
		(end 190.932816 -390.219184)
		(width 0.111252)
		(layer "F.Cu")
		(net "SW_PWR_HDD1")
	)
	(segment
		(start 191.408558 -388.949184)
		(end 191.408558 -390.219184)
		(width 0.111252)
		(layer "F.Cu")
		(net "SW_PWR_HDD1")
	)
	(segment
		(start 189.3824 -388.949184)
		(end 191.408558 -388.949184)
		(width 0.111252)
		(layer "F.Cu")
		(net "SW_PWR_HDD1")
	)
	(segment
		(start 190.3222 -391.3886)
		(end 190.994284 -392.060684)
		(width 0.111252)
		(layer "F.Cu")
		(net "SW_PWR_HDD1")
	)
	(segment
		(start 190.994284 -392.060684)
		(end 191.472058 -392.060684)
		(width 0.111252)
		(layer "F.Cu")
		(net "SW_PWR_HDD1")
	)
	(segment
		(start 190.3222 -390.8298)
		(end 190.3222 -391.3886)
		(width 0.111252)
		(layer "F.Cu")
		(net "SW_PWR_HDD1")
	)
	(via
		(at 189.3824 -388.949184)
		(size 0.7112)
		(drill 0.3556)
		(layers "F.Cu" "B.Cu")
		(net "SW_PWR_HDD1")
	)
	(segment
		(start 190.754 -494.6015)
		(end 189.0141 -494.6015)
		(width 0.111252)
		(layer "F.Cu")
		(net "SW_PWR_HDD0")
	)
	(segment
		(start 190.516256 -492.179102)
		(end 190.516256 -491.13821)
		(width 0.111252)
		(layer "F.Cu")
		(net "SW_PWR_HDD0")
	)
	(segment
		(start 189.0395 -493.4585)
		(end 190.379858 -493.4585)
		(width 0.111252)
		(layer "F.Cu")
		(net "SW_PWR_HDD0")
	)
	(segment
		(start 188.8744 -494.4618)
		(end 188.8744 -493.6236)
		(width 0.111252)
		(layer "F.Cu")
		(net "SW_PWR_HDD0")
	)
	(segment
		(start 188.8744 -493.6236)
		(end 189.0395 -493.4585)
		(width 0.111252)
		(layer "F.Cu")
		(net "SW_PWR_HDD0")
	)
	(segment
		(start 190.516256 -491.13821)
		(end 190.372746 -490.9947)
		(width 0.111252)
		(layer "F.Cu")
		(net "SW_PWR_HDD0")
	)
	(segment
		(start 190.516256 -493.322102)
		(end 190.516256 -492.179102)
		(width 0.111252)
		(layer "F.Cu")
		(net "SW_PWR_HDD0")
	)
	(segment
		(start 189.0141 -494.6015)
		(end 188.8744 -494.4618)
		(width 0.111252)
		(layer "F.Cu")
		(net "SW_PWR_HDD0")
	)
	(segment
		(start 190.379858 -493.4585)
		(end 190.516256 -493.322102)
		(width 0.111252)
		(layer "F.Cu")
		(net "SW_PWR_HDD0")
	)
	(via
		(at 190.372746 -490.9947)
		(size 0.7112)
		(drill 0.3556)
		(layers "F.Cu" "B.Cu")
		(net "SW_PWR_HDD0")
	)
	(via
		(at 219.202 -289.306)
		(size 0.7112)
		(drill 0.3556)
		(layers "F.Cu" "B.Cu")
		(net "P12V_HDD2")
	)
	(via
		(at 204.012546 -292.5699)
		(size 0.5588)
		(drill 0.3048)
		(layers "F.Cu" "B.Cu")
		(net "P12V_HDD2")
	)
	(via
		(at 204.952346 -292.5699)
		(size 0.7112)
		(drill 0.3556)
		(layers "F.Cu" "B.Cu")
		(net "P12V_HDD2")
	)
	(segment
		(start 204.952346 -292.5699)
		(end 204.012546 -292.5699)
		(width 0.508)
		(layer "B.Cu")
		(net "P12V_HDD2")
	)
	(segment
		(start 57.864756 -480.342702)
		(end 57.864756 -479.428302)
		(width 0.111252)
		(layer "F.Cu")
		(net "HDD_PRSNT5")
	)
	(via
		(at 7.518146 -468.4649)
		(size 0.5588)
		(drill 0.3048)
		(layers "F.Cu" "B.Cu")
		(net "HDD_PRSNT5")
	)
	(via
		(at 57.864756 -479.428302)
		(size 0.5588)
		(drill 0.3048)
		(layers "F.Cu" "B.Cu")
		(net "HDD_PRSNT5")
	)
	(via
		(at 7.2517 -464.350862)
		(size 0.5588)
		(drill 0.3048)
		(layers "F.Cu" "B.Cu")
		(net "HDD_PRSNT5")
	)
	(via
		(at 12.5222 -212.471)
		(size 0.5588)
		(drill 0.3048)
		(layers "F.Cu" "B.Cu")
		(net "HDD_PRSNT5")
	)
	(via
		(at 11.404346 -212.4075)
		(size 0.7112)
		(drill 0.3556)
		(layers "F.Cu" "B.Cu")
		(net "HDD_PRSNT5")
	)
	(segment
		(start 11.409172 -465.606384)
		(end 10.965688 -465.1629)
		(width 0.111252)
		(layer "B.Cu")
		(net "HDD_PRSNT5")
	)
	(segment
		(start 12.5222 -212.471)
		(end 12.4587 -212.4075)
		(width 0.111252)
		(layer "B.Cu")
		(net "HDD_PRSNT5")
	)
	(segment
		(start 7.101078 -464.501484)
		(end 2.812542 -464.501484)
		(width 0.111252)
		(layer "B.Cu")
		(net "HDD_PRSNT5")
	)
	(segment
		(start 11.409172 -465.989416)
		(end 11.409172 -465.606384)
		(width 0.111252)
		(layer "B.Cu")
		(net "HDD_PRSNT5")
	)
	(segment
		(start 8.432546 -465.1629)
		(end 7.620508 -464.350862)
		(width 0.111252)
		(layer "B.Cu")
		(net "HDD_PRSNT5")
	)
	(segment
		(start 2.812542 -464.501484)
		(end 2.80924 -464.504786)
		(width 0.111252)
		(layer "B.Cu")
		(net "HDD_PRSNT5")
	)
	(segment
		(start 7.620508 -464.350862)
		(end 7.2517 -464.350862)
		(width 0.111252)
		(layer "B.Cu")
		(net "HDD_PRSNT5")
	)
	(segment
		(start 7.679944 -213.2203)
		(end 6.9977 -213.2203)
		(width 0.111252)
		(layer "B.Cu")
		(net "HDD_PRSNT5")
	)
	(segment
		(start 2.812542 -211.501482)
		(end 2.80924 -211.504784)
		(width 0.111252)
		(layer "B.Cu")
		(net "HDD_PRSNT5")
	)
	(segment
		(start 6.9977 -213.2203)
		(end 5.278882 -211.501482)
		(width 0.111252)
		(layer "B.Cu")
		(net "HDD_PRSNT5")
	)
	(segment
		(start 8.933688 -468.4649)
		(end 11.409172 -465.989416)
		(width 0.111252)
		(layer "B.Cu")
		(net "HDD_PRSNT5")
	)
	(segment
		(start 7.518146 -468.4649)
		(end 8.933688 -468.4649)
		(width 0.111252)
		(layer "B.Cu")
		(net "HDD_PRSNT5")
	)
	(segment
		(start 10.965688 -465.1629)
		(end 8.432546 -465.1629)
		(width 0.111252)
		(layer "B.Cu")
		(net "HDD_PRSNT5")
	)
	(segment
		(start 12.4587 -212.4075)
		(end 11.404346 -212.4075)
		(width 0.111252)
		(layer "B.Cu")
		(net "HDD_PRSNT5")
	)
	(segment
		(start 11.404346 -212.4075)
		(end 8.492744 -212.4075)
		(width 0.111252)
		(layer "B.Cu")
		(net "HDD_PRSNT5")
	)
	(segment
		(start 5.278882 -211.501482)
		(end 2.812542 -211.501482)
		(width 0.111252)
		(layer "B.Cu")
		(net "HDD_PRSNT5")
	)
	(segment
		(start 7.2517 -464.350862)
		(end 7.101078 -464.501484)
		(width 0.111252)
		(layer "B.Cu")
		(net "HDD_PRSNT5")
	)
	(segment
		(start 8.492744 -212.4075)
		(end 7.679944 -213.2203)
		(width 0.111252)
		(layer "B.Cu")
		(net "HDD_PRSNT5")
	)
	(segment
		(start 13.230098 -375.685304)
		(end 13.230098 -393.5476)
		(width 0.14605)
		(layer "In2.Cu")
		(net "HDD_PRSNT5")
	)
	(segment
		(start 14.058646 -259.332222)
		(end 14.0589 -259.332476)
		(width 0.14605)
		(layer "In2.Cu")
		(net "HDD_PRSNT5")
	)
	(segment
		(start 7.836662 -439.333132)
		(end 7.836662 -453.094852)
		(width 0.14605)
		(layer "In2.Cu")
		(net "HDD_PRSNT5")
	)
	(segment
		(start 14.058646 -258.774184)
		(end 14.058646 -259.332222)
		(width 0.14605)
		(layer "In2.Cu")
		(net "HDD_PRSNT5")
	)
	(segment
		(start 13.28674 -365.786162)
		(end 13.74775 -366.247172)
		(width 0.14605)
		(layer "In2.Cu")
		(net "HDD_PRSNT5")
	)
	(segment
		(start 13.74775 -366.247172)
		(end 13.74775 -375.167652)
		(width 0.14605)
		(layer "In2.Cu")
		(net "HDD_PRSNT5")
	)
	(segment
		(start 12.978638 -256.48412)
		(end 13.541502 -257.046984)
		(width 0.14605)
		(layer "In2.Cu")
		(net "HDD_PRSNT5")
	)
	(segment
		(start 12.559538 -414.261554)
		(end 12.38504 -414.436052)
		(width 0.14605)
		(layer "In2.Cu")
		(net "HDD_PRSNT5")
	)
	(segment
		(start 13.286486 -265.845544)
		(end 13.286486 -267.714476)
		(width 0.14605)
		(layer "In2.Cu")
		(net "HDD_PRSNT5")
	)
	(segment
		(start 8.661146 -457.054712)
		(end 9.699752 -458.093318)
		(width 0.14605)
		(layer "In2.Cu")
		(net "HDD_PRSNT5")
	)
	(segment
		(start 13.541502 -257.046984)
		(end 13.541502 -258.256786)
		(width 0.14605)
		(layer "In2.Cu")
		(net "HDD_PRSNT5")
	)
	(segment
		(start 13.74775 -375.167652)
		(end 13.230098 -375.685304)
		(width 0.14605)
		(layer "In2.Cu")
		(net "HDD_PRSNT5")
	)
	(segment
		(start 12.38504 -414.436052)
		(end 12.38504 -434.784754)
		(width 0.14605)
		(layer "In2.Cu")
		(net "HDD_PRSNT5")
	)
	(segment
		(start 8.128 -463.474562)
		(end 7.2517 -464.350862)
		(width 0.14605)
		(layer "In2.Cu")
		(net "HDD_PRSNT5")
	)
	(segment
		(start 13.286486 -267.714476)
		(end 13.28674 -267.71473)
		(width 0.14605)
		(layer "In2.Cu")
		(net "HDD_PRSNT5")
	)
	(segment
		(start 14.0589 -265.07313)
		(end 13.286486 -265.845544)
		(width 0.14605)
		(layer "In2.Cu")
		(net "HDD_PRSNT5")
	)
	(segment
		(start 13.28674 -267.71473)
		(end 13.28674 -365.786162)
		(width 0.14605)
		(layer "In2.Cu")
		(net "HDD_PRSNT5")
	)
	(segment
		(start 8.661146 -453.919336)
		(end 8.661146 -457.054712)
		(width 0.14605)
		(layer "In2.Cu")
		(net "HDD_PRSNT5")
	)
	(segment
		(start 13.541502 -258.256786)
		(end 14.058646 -258.774184)
		(width 0.14605)
		(layer "In2.Cu")
		(net "HDD_PRSNT5")
	)
	(segment
		(start 12.38504 -434.784754)
		(end 7.836662 -439.333132)
		(width 0.14605)
		(layer "In2.Cu")
		(net "HDD_PRSNT5")
	)
	(segment
		(start 9.699752 -461.207104)
		(end 8.128 -462.778856)
		(width 0.14605)
		(layer "In2.Cu")
		(net "HDD_PRSNT5")
	)
	(segment
		(start 12.91209 -217.768678)
		(end 12.978638 -217.835226)
		(width 0.14605)
		(layer "In2.Cu")
		(net "HDD_PRSNT5")
	)
	(segment
		(start 8.128 -462.778856)
		(end 8.128 -463.474562)
		(width 0.14605)
		(layer "In2.Cu")
		(net "HDD_PRSNT5")
	)
	(segment
		(start 14.0589 -259.332476)
		(end 14.0589 -265.07313)
		(width 0.14605)
		(layer "In2.Cu")
		(net "HDD_PRSNT5")
	)
	(segment
		(start 12.662154 -395.9479)
		(end 12.559538 -396.050262)
		(width 0.14605)
		(layer "In2.Cu")
		(net "HDD_PRSNT5")
	)
	(segment
		(start 12.662154 -394.115544)
		(end 12.662154 -395.9479)
		(width 0.14605)
		(layer "In2.Cu")
		(net "HDD_PRSNT5")
	)
	(segment
		(start 7.836662 -453.094852)
		(end 8.661146 -453.919336)
		(width 0.14605)
		(layer "In2.Cu")
		(net "HDD_PRSNT5")
	)
	(segment
		(start 12.5222 -212.471)
		(end 12.91209 -212.86089)
		(width 0.14605)
		(layer "In2.Cu")
		(net "HDD_PRSNT5")
	)
	(segment
		(start 12.559538 -396.050262)
		(end 12.559538 -414.261554)
		(width 0.14605)
		(layer "In2.Cu")
		(net "HDD_PRSNT5")
	)
	(segment
		(start 12.91209 -212.86089)
		(end 12.91209 -217.768678)
		(width 0.14605)
		(layer "In2.Cu")
		(net "HDD_PRSNT5")
	)
	(segment
		(start 12.978638 -217.835226)
		(end 12.978638 -256.48412)
		(width 0.14605)
		(layer "In2.Cu")
		(net "HDD_PRSNT5")
	)
	(segment
		(start 9.699752 -458.093318)
		(end 9.699752 -461.207104)
		(width 0.14605)
		(layer "In2.Cu")
		(net "HDD_PRSNT5")
	)
	(segment
		(start 13.230098 -393.5476)
		(end 12.662154 -394.115544)
		(width 0.14605)
		(layer "In2.Cu")
		(net "HDD_PRSNT5")
	)
	(segment
		(start 34.147252 -476.5294)
		(end 31.6484 -474.030548)
		(width 0.14605)
		(layer "In5.Cu")
		(net "HDD_PRSNT5")
	)
	(segment
		(start 12.71905 -473.849954)
		(end 7.518146 -468.64905)
		(width 0.14605)
		(layer "In5.Cu")
		(net "HDD_PRSNT5")
	)
	(segment
		(start 57.864756 -479.428302)
		(end 54.965854 -476.5294)
		(width 0.14605)
		(layer "In5.Cu")
		(net "HDD_PRSNT5")
	)
	(segment
		(start 7.518146 -468.64905)
		(end 7.518146 -468.4649)
		(width 0.14605)
		(layer "In5.Cu")
		(net "HDD_PRSNT5")
	)
	(segment
		(start 54.965854 -476.5294)
		(end 34.147252 -476.5294)
		(width 0.14605)
		(layer "In5.Cu")
		(net "HDD_PRSNT5")
	)
	(segment
		(start 12.719304 -473.849954)
		(end 12.71905 -473.849954)
		(width 0.14605)
		(layer "In5.Cu")
		(net "HDD_PRSNT5")
	)
	(segment
		(start 12.899898 -474.030548)
		(end 12.719304 -473.849954)
		(width 0.14605)
		(layer "In5.Cu")
		(net "HDD_PRSNT5")
	)
	(segment
		(start 31.6484 -474.030548)
		(end 12.899898 -474.030548)
		(width 0.14605)
		(layer "In5.Cu")
		(net "HDD_PRSNT5")
	)
	(via
		(at 217.297 -281.051)
		(size 0.7112)
		(drill 0.3556)
		(layers "F.Cu" "B.Cu")
		(net "P5V_HDD2")
	)
	(via
		(at 210.058 -279.908)
		(size 0.7112)
		(drill 0.3556)
		(layers "F.Cu" "B.Cu")
		(net "P5V_HDD2")
	)
	(segment
		(start 32.003746 -475.781116)
		(end 31.825946 -475.781116)
		(width 0.09525)
		(layer "F.Cu")
		(net "SAS2X28_B_HDD5_RX_+")
	)
	(segment
		(start 32.598868 -476.060516)
		(end 32.542734 -476.004382)
		(width 0.09525)
		(layer "F.Cu")
		(net "SAS2X28_B_HDD5_RX_+")
	)
	(segment
		(start 31.562802 -475.890082)
		(end 31.392368 -476.060516)
		(width 0.09525)
		(layer "F.Cu")
		(net "SAS2X28_B_HDD5_RX_+")
	)
	(via
		(at 31.392368 -476.060516)
		(size 0.5588)
		(drill 0.3048)
		(layers "F.Cu" "B.Cu")
		(net "SAS2X28_B_HDD5_RX_+")
	)
	(arc
		(start 32.542734 -476.004382)
		(mid 32.295444 -475.839148)
		(end 32.003746 -475.781116)
		(width 0.09525)
		(layer "F.Cu")
		(net "SAS2X28_B_HDD5_RX_+")
	)
	(arc
		(start 31.825946 -475.781116)
		(mid 31.683546 -475.809441)
		(end 31.562802 -475.890082)
		(width 0.09525)
		(layer "F.Cu")
		(net "SAS2X28_B_HDD5_RX_+")
	)
	(segment
		(start 37.8206 -473.3798)
		(end 37.8206 -460.016606)
		(width 0.09525)
		(layer "B.Cu")
		(net "SAS2X28_B_HDD5_RX_+")
	)
	(segment
		(start 12.753848 -155.830524)
		(end 5.44576 -155.830524)
		(width 0.09525)
		(layer "B.Cu")
		(net "SAS2X28_B_HDD5_RX_+")
	)
	(segment
		(start 37.1475 -474.951552)
		(end 37.185092 -474.913706)
		(width 0.09525)
		(layer "B.Cu")
		(net "SAS2X28_B_HDD5_RX_+")
	)
	(segment
		(start 17.219168 -158.582868)
		(end 15.677642 -157.041596)
		(width 0.09525)
		(layer "B.Cu")
		(net "SAS2X28_B_HDD5_RX_+")
	)
	(segment
		(start 4.64693 -155.4988)
		(end 2.811526 -155.4988)
		(width 0.09525)
		(layer "B.Cu")
		(net "SAS2X28_B_HDD5_RX_+")
	)
	(segment
		(start 47.333662 -205.53553)
		(end 37.148262 -195.35013)
		(width 0.09525)
		(layer "B.Cu")
		(net "SAS2X28_B_HDD5_RX_+")
	)
	(segment
		(start 36.774628 -475.324424)
		(end 37.1475 -474.951552)
		(width 0.09525)
		(layer "B.Cu")
		(net "SAS2X28_B_HDD5_RX_+")
	)
	(segment
		(start 38.735762 -458.73289)
		(end 38.82644 -458.642466)
		(width 0.09525)
		(layer "B.Cu")
		(net "SAS2X28_B_HDD5_RX_+")
	)
	(segment
		(start 18.287746 -169.412158)
		(end 18.287746 -161.163)
		(width 0.09525)
		(layer "B.Cu")
		(net "SAS2X28_B_HDD5_RX_+")
	)
	(segment
		(start 31.854648 -475.869)
		(end 35.459924 -475.869)
		(width 0.09525)
		(layer "B.Cu")
		(net "SAS2X28_B_HDD5_RX_+")
	)
	(segment
		(start 38.281864 -427.744382)
		(end 30.306264 -419.768782)
		(width 0.09525)
		(layer "B.Cu")
		(net "SAS2X28_B_HDD5_RX_+")
	)
	(segment
		(start 39.255446 -457.6064)
		(end 39.255446 -430.094898)
		(width 0.09525)
		(layer "B.Cu")
		(net "SAS2X28_B_HDD5_RX_+")
	)
	(segment
		(start 36.220146 -187.6679)
		(end 18.516346 -169.9641)
		(width 0.09525)
		(layer "B.Cu")
		(net "SAS2X28_B_HDD5_RX_+")
	)
	(segment
		(start 4.648454 -155.500324)
		(end 4.64693 -155.4988)
		(width 0.09525)
		(layer "B.Cu")
		(net "SAS2X28_B_HDD5_RX_+")
	)
	(segment
		(start 29.768546 -418.470588)
		(end 29.768546 -373.678958)
		(width 0.09525)
		(layer "B.Cu")
		(net "SAS2X28_B_HDD5_RX_+")
	)
	(segment
		(start 30.268926 -372.470934)
		(end 33.278826 -369.461034)
		(width 0.09525)
		(layer "B.Cu")
		(net "SAS2X28_B_HDD5_RX_+")
	)
	(segment
		(start 33.972246 -367.78692)
		(end 33.972246 -358.639364)
		(width 0.09525)
		(layer "B.Cu")
		(net "SAS2X28_B_HDD5_RX_+")
	)
	(segment
		(start 38.081204 -459.387448)
		(end 38.735762 -458.73289)
		(width 0.09525)
		(layer "B.Cu")
		(net "SAS2X28_B_HDD5_RX_+")
	)
	(segment
		(start 34.53511 -357.280464)
		(end 41.64711 -350.168464)
		(width 0.09525)
		(layer "B.Cu")
		(net "SAS2X28_B_HDD5_RX_+")
	)
	(segment
		(start 36.825936 -194.571874)
		(end 36.825936 -189.130432)
		(width 0.09525)
		(layer "B.Cu")
		(net "SAS2X28_B_HDD5_RX_+")
	)
	(segment
		(start 42.22115 -304.540158)
		(end 47.55515 -299.206158)
		(width 0.09525)
		(layer "B.Cu")
		(net "SAS2X28_B_HDD5_RX_+")
	)
	(segment
		(start 47.929546 -298.302172)
		(end 47.929546 -206.974186)
		(width 0.09525)
		(layer "B.Cu")
		(net "SAS2X28_B_HDD5_RX_+")
	)
	(segment
		(start 41.935146 -349.473012)
		(end 41.935146 -305.23053)
		(width 0.09525)
		(layer "B.Cu")
		(net "SAS2X28_B_HDD5_RX_+")
	)
	(arc
		(start 18.516346 -169.9641)
		(mid 18.347141 -169.710867)
		(end 18.287746 -169.412158)
		(width 0.09525)
		(layer "B.Cu")
		(net "SAS2X28_B_HDD5_RX_+")
	)
	(arc
		(start 37.185092 -474.913706)
		(mid 37.655414 -474.209959)
		(end 37.8206 -473.3798)
		(width 0.09525)
		(layer "B.Cu")
		(net "SAS2X28_B_HDD5_RX_+")
	)
	(arc
		(start 31.392368 -476.060516)
		(mid 31.604464 -475.918798)
		(end 31.854648 -475.869)
		(width 0.09525)
		(layer "B.Cu")
		(net "SAS2X28_B_HDD5_RX_+")
	)
	(arc
		(start 33.972246 -358.639364)
		(mid 34.118532 -357.903937)
		(end 34.53511 -357.280464)
		(width 0.09525)
		(layer "B.Cu")
		(net "SAS2X28_B_HDD5_RX_+")
	)
	(arc
		(start 15.677642 -157.041596)
		(mid 14.336194 -156.145269)
		(end 12.753848 -155.830524)
		(width 0.09525)
		(layer "B.Cu")
		(net "SAS2X28_B_HDD5_RX_+")
	)
	(arc
		(start 41.935146 -305.23053)
		(mid 42.009468 -304.856887)
		(end 42.22115 -304.540158)
		(width 0.09525)
		(layer "B.Cu")
		(net "SAS2X28_B_HDD5_RX_+")
	)
	(arc
		(start 35.459924 -475.869)
		(mid 36.17144 -475.727471)
		(end 36.774628 -475.324424)
		(width 0.09525)
		(layer "B.Cu")
		(net "SAS2X28_B_HDD5_RX_+")
	)
	(arc
		(start 33.278826 -369.461034)
		(mid 33.792101 -368.692958)
		(end 33.972246 -367.78692)
		(width 0.09525)
		(layer "B.Cu")
		(net "SAS2X28_B_HDD5_RX_+")
	)
	(arc
		(start 37.8206 -460.016606)
		(mid 37.888329 -459.676109)
		(end 38.081204 -459.387448)
		(width 0.09525)
		(layer "B.Cu")
		(net "SAS2X28_B_HDD5_RX_+")
	)
	(arc
		(start 41.64711 -350.168464)
		(mid 41.86031 -349.849388)
		(end 41.935146 -349.473012)
		(width 0.09525)
		(layer "B.Cu")
		(net "SAS2X28_B_HDD5_RX_+")
	)
	(arc
		(start 29.768546 -373.678958)
		(mid 29.898591 -373.02518)
		(end 30.268926 -372.470934)
		(width 0.09525)
		(layer "B.Cu")
		(net "SAS2X28_B_HDD5_RX_+")
	)
	(arc
		(start 38.82644 -458.642466)
		(mid 39.143976 -458.1671)
		(end 39.255446 -457.6064)
		(width 0.09525)
		(layer "B.Cu")
		(net "SAS2X28_B_HDD5_RX_+")
	)
	(arc
		(start 5.44576 -155.830524)
		(mid 5.321634 -155.805834)
		(end 5.216398 -155.735528)
		(width 0.09525)
		(layer "B.Cu")
		(net "SAS2X28_B_HDD5_RX_+")
	)
	(arc
		(start 36.825936 -189.130432)
		(mid 36.668441 -188.338945)
		(end 36.220146 -187.6679)
		(width 0.09525)
		(layer "B.Cu")
		(net "SAS2X28_B_HDD5_RX_+")
	)
	(arc
		(start 47.929546 -206.974186)
		(mid 47.774744 -206.195562)
		(end 47.333662 -205.53553)
		(width 0.09525)
		(layer "B.Cu")
		(net "SAS2X28_B_HDD5_RX_+")
	)
	(arc
		(start 5.216398 -155.735528)
		(mid 4.955823 -155.561417)
		(end 4.648454 -155.500324)
		(width 0.09525)
		(layer "B.Cu")
		(net "SAS2X28_B_HDD5_RX_+")
	)
	(arc
		(start 39.255446 -430.094898)
		(mid 39.002361 -428.822846)
		(end 38.281864 -427.744382)
		(width 0.09525)
		(layer "B.Cu")
		(net "SAS2X28_B_HDD5_RX_+")
	)
	(arc
		(start 37.148262 -195.35013)
		(mid 36.909678 -194.993063)
		(end 36.825936 -194.571874)
		(width 0.09525)
		(layer "B.Cu")
		(net "SAS2X28_B_HDD5_RX_+")
	)
	(arc
		(start 47.55515 -299.206158)
		(mid 47.832279 -298.791406)
		(end 47.929546 -298.302172)
		(width 0.09525)
		(layer "B.Cu")
		(net "SAS2X28_B_HDD5_RX_+")
	)
	(arc
		(start 30.306264 -419.768782)
		(mid 29.908286 -419.173166)
		(end 29.768546 -418.470588)
		(width 0.09525)
		(layer "B.Cu")
		(net "SAS2X28_B_HDD5_RX_+")
	)
	(arc
		(start 18.287746 -161.163)
		(mid 18.010087 -159.766645)
		(end 17.219168 -158.582868)
		(width 0.09525)
		(layer "B.Cu")
		(net "SAS2X28_B_HDD5_RX_+")
	)
	(segment
		(start 83.311746 -188.0997)
		(end 83.199986 -188.21146)
		(width 0.111252)
		(layer "F.Cu")
		(net "SAS_EXP_B_PWR8")
	)
	(segment
		(start 83.199986 -188.21146)
		(end 82.105246 -188.21146)
		(width 0.111252)
		(layer "F.Cu")
		(net "SAS_EXP_B_PWR8")
	)
	(segment
		(start 83.438746 -188.2267)
		(end 83.311746 -188.0997)
		(width 0.111252)
		(layer "F.Cu")
		(net "SAS_EXP_B_PWR8")
	)
	(segment
		(start 84.137246 -188.2267)
		(end 83.438746 -188.2267)
		(width 0.111252)
		(layer "F.Cu")
		(net "SAS_EXP_B_PWR8")
	)
	(segment
		(start 7.861046 -203.504546)
		(end 3.19024 -203.504546)
		(width 0.111252)
		(layer "F.Cu")
		(net "SAS_EXP_B_PWR8")
	)
	(segment
		(start 8.3312 -203.9747)
		(end 7.861046 -203.504546)
		(width 0.111252)
		(layer "F.Cu")
		(net "SAS_EXP_B_PWR8")
	)
	(via
		(at 84.140802 -188.542676)
		(size 0.7112)
		(drill 0.3556)
		(layers "F.Cu" "B.Cu")
		(net "SAS_EXP_B_PWR8")
	)
	(via
		(at 8.3312 -203.9747)
		(size 0.5588)
		(drill 0.3048)
		(layers "F.Cu" "B.Cu")
		(net "SAS_EXP_B_PWR8")
	)
	(via
		(at 83.311746 -188.0997)
		(size 0.5588)
		(drill 0.3048)
		(layers "F.Cu" "B.Cu")
		(net "SAS_EXP_B_PWR8")
	)
	(segment
		(start 83.311746 -188.0997)
		(end 83.697826 -188.0997)
		(width 0.111252)
		(layer "B.Cu")
		(net "SAS_EXP_B_PWR8")
	)
	(segment
		(start 83.697826 -188.0997)
		(end 84.140802 -188.542676)
		(width 0.111252)
		(layer "B.Cu")
		(net "SAS_EXP_B_PWR8")
	)
	(segment
		(start 13.992352 -401.36318)
		(end 13.992352 -397.109442)
		(width 0.14605)
		(layer "In5.Cu")
		(net "SAS_EXP_B_PWR8")
	)
	(segment
		(start 13.73759 -401.617942)
		(end 13.992352 -401.36318)
		(width 0.14605)
		(layer "In5.Cu")
		(net "SAS_EXP_B_PWR8")
	)
	(segment
		(start 13.73759 -431.142648)
		(end 13.73759 -401.617942)
		(width 0.14605)
		(layer "In5.Cu")
		(net "SAS_EXP_B_PWR8")
	)
	(segment
		(start 90.203782 -435.835552)
		(end 76.462382 -449.576952)
		(width 0.14605)
		(layer "In5.Cu")
		(net "SAS_EXP_B_PWR8")
	)
	(segment
		(start 8.429498 -441.624974)
		(end 8.429498 -436.45074)
		(width 0.14605)
		(layer "In5.Cu")
		(net "SAS_EXP_B_PWR8")
	)
	(segment
		(start 11.290046 -218.101418)
		(end 8.880348 -215.69172)
		(width 0.14605)
		(layer "In5.Cu")
		(net "SAS_EXP_B_PWR8")
	)
	(segment
		(start 8.880348 -206.995522)
		(end 8.3312 -206.446374)
		(width 0.14605)
		(layer "In5.Cu")
		(net "SAS_EXP_B_PWR8")
	)
	(segment
		(start 10.375646 -391.066528)
		(end 9.188196 -389.879078)
		(width 0.14605)
		(layer "In5.Cu")
		(net "SAS_EXP_B_PWR8")
	)
	(segment
		(start 8.3312 -206.446374)
		(end 8.3312 -203.9747)
		(width 0.14605)
		(layer "In5.Cu")
		(net "SAS_EXP_B_PWR8")
	)
	(segment
		(start 9.985248 -443.949328)
		(end 9.985248 -443.180724)
		(width 0.14605)
		(layer "In5.Cu")
		(net "SAS_EXP_B_PWR8")
	)
	(segment
		(start 12.392406 -444.610998)
		(end 11.435842 -444.610998)
		(width 0.14605)
		(layer "In5.Cu")
		(net "SAS_EXP_B_PWR8")
	)
	(segment
		(start 9.985248 -443.180724)
		(end 8.429498 -441.624974)
		(width 0.14605)
		(layer "In5.Cu")
		(net "SAS_EXP_B_PWR8")
	)
	(segment
		(start 91.486228 -196.274182)
		(end 91.486228 -434.710586)
		(width 0.14605)
		(layer "In5.Cu")
		(net "SAS_EXP_B_PWR8")
	)
	(segment
		(start 9.188196 -389.879078)
		(end 9.188196 -389.06323)
		(width 0.14605)
		(layer "In5.Cu")
		(net "SAS_EXP_B_PWR8")
	)
	(segment
		(start 9.172194 -389.047228)
		(end 9.172194 -388.411974)
		(width 0.14605)
		(layer "In5.Cu")
		(net "SAS_EXP_B_PWR8")
	)
	(segment
		(start 17.51965 -449.49745)
		(end 17.383252 -449.49745)
		(width 0.14605)
		(layer "In5.Cu")
		(net "SAS_EXP_B_PWR8")
	)
	(segment
		(start 90.361262 -435.835552)
		(end 90.203782 -435.835552)
		(width 0.14605)
		(layer "In5.Cu")
		(net "SAS_EXP_B_PWR8")
	)
	(segment
		(start 17.383252 -449.49745)
		(end 12.500102 -444.6143)
		(width 0.14605)
		(layer "In5.Cu")
		(net "SAS_EXP_B_PWR8")
	)
	(segment
		(start 91.486228 -434.710586)
		(end 90.361262 -435.835552)
		(width 0.14605)
		(layer "In5.Cu")
		(net "SAS_EXP_B_PWR8")
	)
	(segment
		(start 12.395708 -444.6143)
		(end 12.392406 -444.610998)
		(width 0.14605)
		(layer "In5.Cu")
		(net "SAS_EXP_B_PWR8")
	)
	(segment
		(start 11.536172 -394.653262)
		(end 11.285728 -394.653262)
		(width 0.14605)
		(layer "In5.Cu")
		(net "SAS_EXP_B_PWR8")
	)
	(segment
		(start 9.188196 -389.06323)
		(end 9.172194 -389.047228)
		(width 0.14605)
		(layer "In5.Cu")
		(net "SAS_EXP_B_PWR8")
	)
	(segment
		(start 17.599152 -449.576952)
		(end 17.51965 -449.49745)
		(width 0.14605)
		(layer "In5.Cu")
		(net "SAS_EXP_B_PWR8")
	)
	(segment
		(start 76.462382 -449.576952)
		(end 17.599152 -449.576952)
		(width 0.14605)
		(layer "In5.Cu")
		(net "SAS_EXP_B_PWR8")
	)
	(segment
		(start 12.500102 -444.6143)
		(end 12.395708 -444.6143)
		(width 0.14605)
		(layer "In5.Cu")
		(net "SAS_EXP_B_PWR8")
	)
	(segment
		(start 10.375646 -393.74318)
		(end 10.375646 -391.066528)
		(width 0.14605)
		(layer "In5.Cu")
		(net "SAS_EXP_B_PWR8")
	)
	(segment
		(start 8.429498 -436.45074)
		(end 13.73759 -431.142648)
		(width 0.14605)
		(layer "In5.Cu")
		(net "SAS_EXP_B_PWR8")
	)
	(segment
		(start 11.178794 -444.35395)
		(end 10.38987 -444.35395)
		(width 0.14605)
		(layer "In5.Cu")
		(net "SAS_EXP_B_PWR8")
	)
	(segment
		(start 83.311746 -188.0997)
		(end 91.486228 -196.274182)
		(width 0.14605)
		(layer "In5.Cu")
		(net "SAS_EXP_B_PWR8")
	)
	(segment
		(start 8.880348 -215.69172)
		(end 8.880348 -206.995522)
		(width 0.14605)
		(layer "In5.Cu")
		(net "SAS_EXP_B_PWR8")
	)
	(segment
		(start 10.38987 -444.35395)
		(end 9.985248 -443.949328)
		(width 0.14605)
		(layer "In5.Cu")
		(net "SAS_EXP_B_PWR8")
	)
	(segment
		(start 9.172194 -388.411974)
		(end 11.290046 -386.294122)
		(width 0.14605)
		(layer "In5.Cu")
		(net "SAS_EXP_B_PWR8")
	)
	(segment
		(start 13.992352 -397.109442)
		(end 11.536172 -394.653262)
		(width 0.14605)
		(layer "In5.Cu")
		(net "SAS_EXP_B_PWR8")
	)
	(segment
		(start 11.435842 -444.610998)
		(end 11.178794 -444.35395)
		(width 0.14605)
		(layer "In5.Cu")
		(net "SAS_EXP_B_PWR8")
	)
	(segment
		(start 11.285728 -394.653262)
		(end 10.375646 -393.74318)
		(width 0.14605)
		(layer "In5.Cu")
		(net "SAS_EXP_B_PWR8")
	)
	(segment
		(start 11.290046 -386.294122)
		(end 11.290046 -218.101418)
		(width 0.14605)
		(layer "In5.Cu")
		(net "SAS_EXP_B_PWR8")
	)
	(via
		(at 19.049746 -286.1437)
		(size 0.7112)
		(drill 0.3556)
		(layers "F.Cu" "B.Cu")
		(net "P12V_HDD7")
	)
	(via
		(at 32.4612 -295.5036)
		(size 0.7112)
		(drill 0.3556)
		(layers "F.Cu" "B.Cu")
		(net "P12V_HDD7")
	)
	(segment
		(start 6.984746 -158.459678)
		(end 6.894322 -158.369254)
		(width 0.09525)
		(layer "F.Cu")
		(net "SAS2X28_B_HDD5_TX_-")
	)
	(segment
		(start 38.924738 -473.551758)
		(end 35.889184 -473.551758)
		(width 0.09525)
		(layer "F.Cu")
		(net "SAS2X28_B_HDD5_TX_-")
	)
	(segment
		(start 40.39997 -473.79001)
		(end 39.423594 -473.79001)
		(width 0.09525)
		(layer "F.Cu")
		(net "SAS2X28_B_HDD5_TX_-")
	)
	(segment
		(start 39.213536 -473.70111)
		(end 39.162736 -473.65031)
		(width 0.09525)
		(layer "F.Cu")
		(net "SAS2X28_B_HDD5_TX_-")
	)
	(segment
		(start 39.423594 -473.79001)
		(end 39.420292 -473.786708)
		(width 0.09525)
		(layer "F.Cu")
		(net "SAS2X28_B_HDD5_TX_-")
	)
	(segment
		(start 35.281362 -473.518738)
		(end 35.051746 -473.748354)
		(width 0.09525)
		(layer "F.Cu")
		(net "SAS2X28_B_HDD5_TX_-")
	)
	(segment
		(start 4.64439 -158.498794)
		(end 3.192526 -158.498794)
		(width 0.09525)
		(layer "F.Cu")
		(net "SAS2X28_B_HDD5_TX_-")
	)
	(segment
		(start 6.390894 -158.16072)
		(end 5.465826 -158.16072)
		(width 0.09525)
		(layer "F.Cu")
		(net "SAS2X28_B_HDD5_TX_-")
	)
	(segment
		(start 4.645914 -158.500318)
		(end 4.64439 -158.498794)
		(width 0.09525)
		(layer "F.Cu")
		(net "SAS2X28_B_HDD5_TX_-")
	)
	(via
		(at 35.051746 -473.748354)
		(size 0.5588)
		(drill 0.3048)
		(layers "F.Cu" "B.Cu")
		(net "SAS2X28_B_HDD5_TX_-")
	)
	(via
		(at 6.984746 -158.459678)
		(size 0.5588)
		(drill 0.3048)
		(layers "F.Cu" "B.Cu")
		(net "SAS2X28_B_HDD5_TX_-")
	)
	(arc
		(start 39.162736 -473.65031)
		(mid 39.053542 -473.577349)
		(end 38.924738 -473.551758)
		(width 0.09525)
		(layer "F.Cu")
		(net "SAS2X28_B_HDD5_TX_-")
	)
	(arc
		(start 35.889184 -473.551758)
		(mid 35.876483 -473.551688)
		(end 35.863784 -473.551504)
		(width 0.09525)
		(layer "F.Cu")
		(net "SAS2X28_B_HDD5_TX_-")
	)
	(arc
		(start 6.894322 -158.369254)
		(mid 6.663348 -158.214892)
		(end 6.390894 -158.16072)
		(width 0.09525)
		(layer "F.Cu")
		(net "SAS2X28_B_HDD5_TX_-")
	)
	(arc
		(start 5.465826 -158.16072)
		(mid 5.321773 -158.189374)
		(end 5.199634 -158.270956)
		(width 0.09525)
		(layer "F.Cu")
		(net "SAS2X28_B_HDD5_TX_-")
	)
	(arc
		(start 39.420292 -473.786708)
		(mid 39.308413 -473.764454)
		(end 39.213536 -473.70111)
		(width 0.09525)
		(layer "F.Cu")
		(net "SAS2X28_B_HDD5_TX_-")
	)
	(arc
		(start 35.44824 -473.479622)
		(mid 35.359243 -473.475461)
		(end 35.281362 -473.518738)
		(width 0.09525)
		(layer "F.Cu")
		(net "SAS2X28_B_HDD5_TX_-")
	)
	(arc
		(start 35.863784 -473.551504)
		(mid 35.653264 -473.531457)
		(end 35.44824 -473.479622)
		(width 0.09525)
		(layer "F.Cu")
		(net "SAS2X28_B_HDD5_TX_-")
	)
	(arc
		(start 5.199634 -158.270956)
		(mid 4.945585 -158.440706)
		(end 4.645914 -158.500318)
		(width 0.09525)
		(layer "F.Cu")
		(net "SAS2X28_B_HDD5_TX_-")
	)
	(segment
		(start 29.382466 -420.641526)
		(end 36.646866 -427.905926)
		(width 0.09525)
		(layer "B.Cu")
		(net "SAS2X28_B_HDD5_TX_-")
	)
	(segment
		(start 16.814292 -161.184844)
		(end 16.814546 -161.18459)
		(width 0.09525)
		(layer "B.Cu")
		(net "SAS2X28_B_HDD5_TX_-")
	)
	(segment
		(start 33.4264 -462.604612)
		(end 33.4264 -472.54668)
		(width 0.09525)
		(layer "B.Cu")
		(net "SAS2X28_B_HDD5_TX_-")
	)
	(segment
		(start 33.655508 -473.099892)
		(end 33.655254 -473.100146)
		(width 0.09525)
		(layer "B.Cu")
		(net "SAS2X28_B_HDD5_TX_-")
	)
	(segment
		(start 32.317182 -368.626136)
		(end 29.154882 -371.788436)
		(width 0.09525)
		(layer "B.Cu")
		(net "SAS2X28_B_HDD5_TX_-")
	)
	(segment
		(start 40.532812 -349.48622)
		(end 33.217612 -356.80142)
		(width 0.09525)
		(layer "B.Cu")
		(net "SAS2X28_B_HDD5_TX_-")
	)
	(segment
		(start 16.814546 -161.18459)
		(end 16.814546 -169.457878)
		(width 0.09525)
		(layer "B.Cu")
		(net "SAS2X28_B_HDD5_TX_-")
	)
	(segment
		(start 7.706614 -158.16072)
		(end 12.113006 -158.16072)
		(width 0.09525)
		(layer "B.Cu")
		(net "SAS2X28_B_HDD5_TX_-")
	)
	(segment
		(start 35.940746 -195.939156)
		(end 46.257718 -206.256128)
		(width 0.09525)
		(layer "B.Cu")
		(net "SAS2X28_B_HDD5_TX_-")
	)
	(segment
		(start 37.464746 -429.880268)
		(end 37.464746 -457.1492)
		(width 0.09525)
		(layer "B.Cu")
		(net "SAS2X28_B_HDD5_TX_-")
	)
	(segment
		(start 40.665146 -304.996596)
		(end 40.665146 -349.166942)
		(width 0.09525)
		(layer "B.Cu")
		(net "SAS2X28_B_HDD5_TX_-")
	)
	(segment
		(start 34.860738 -473.5576)
		(end 35.051746 -473.748354)
		(width 0.09525)
		(layer "B.Cu")
		(net "SAS2X28_B_HDD5_TX_-")
	)
	(segment
		(start 35.450018 -189.212982)
		(end 35.450018 -194.7545)
		(width 0.09525)
		(layer "B.Cu")
		(net "SAS2X28_B_HDD5_TX_-")
	)
	(segment
		(start 34.340546 -473.4052)
		(end 34.4932 -473.4052)
		(width 0.09525)
		(layer "B.Cu")
		(net "SAS2X28_B_HDD5_TX_-")
	)
	(segment
		(start 32.702246 -358.045766)
		(end 32.702246 -367.69675)
		(width 0.09525)
		(layer "B.Cu")
		(net "SAS2X28_B_HDD5_TX_-")
	)
	(segment
		(start 46.659546 -207.226154)
		(end 46.659546 -298.121832)
		(width 0.09525)
		(layer "B.Cu")
		(net "SAS2X28_B_HDD5_TX_-")
	)
	(segment
		(start 33.655254 -473.100146)
		(end 33.691576 -473.136468)
		(width 0.09525)
		(layer "B.Cu")
		(net "SAS2X28_B_HDD5_TX_-")
	)
	(segment
		(start 32.702246 -367.69675)
		(end 32.701992 -367.696496)
		(width 0.09525)
		(layer "B.Cu")
		(net "SAS2X28_B_HDD5_TX_-")
	)
	(segment
		(start 46.529752 -298.435014)
		(end 41.157906 -303.80686)
		(width 0.09525)
		(layer "B.Cu")
		(net "SAS2X28_B_HDD5_TX_-")
	)
	(segment
		(start 28.498546 -373.373142)
		(end 28.498546 -418.507418)
		(width 0.09525)
		(layer "B.Cu")
		(net "SAS2X28_B_HDD5_TX_-")
	)
	(segment
		(start 17.423892 -170.929046)
		(end 35.267646 -188.7728)
		(width 0.09525)
		(layer "B.Cu")
		(net "SAS2X28_B_HDD5_TX_-")
	)
	(arc
		(start 46.659546 -298.121832)
		(mid 46.625796 -298.291323)
		(end 46.529752 -298.435014)
		(width 0.09525)
		(layer "B.Cu")
		(net "SAS2X28_B_HDD5_TX_-")
	)
	(arc
		(start 35.450018 -194.7545)
		(mid 35.577549 -195.395642)
		(end 35.940746 -195.939156)
		(width 0.09525)
		(layer "B.Cu")
		(net "SAS2X28_B_HDD5_TX_-")
	)
	(arc
		(start 33.217612 -356.80142)
		(mid 32.836166 -357.372344)
		(end 32.702246 -358.045766)
		(width 0.09525)
		(layer "B.Cu")
		(net "SAS2X28_B_HDD5_TX_-")
	)
	(arc
		(start 33.691576 -473.136468)
		(mid 33.98934 -473.335364)
		(end 34.340546 -473.4052)
		(width 0.09525)
		(layer "B.Cu")
		(net "SAS2X28_B_HDD5_TX_-")
	)
	(arc
		(start 28.498546 -418.507418)
		(mid 28.728333 -419.662342)
		(end 29.382466 -420.641526)
		(width 0.09525)
		(layer "B.Cu")
		(net "SAS2X28_B_HDD5_TX_-")
	)
	(arc
		(start 6.984746 -158.459678)
		(mid 7.315942 -158.23838)
		(end 7.706614 -158.16072)
		(width 0.09525)
		(layer "B.Cu")
		(net "SAS2X28_B_HDD5_TX_-")
	)
	(arc
		(start 37.464746 -457.1492)
		(mid 37.329337 -457.827685)
		(end 36.9316 -458.3938)
		(width 0.09525)
		(layer "B.Cu")
		(net "SAS2X28_B_HDD5_TX_-")
	)
	(arc
		(start 29.154882 -371.788436)
		(mid 28.669099 -372.515506)
		(end 28.498546 -373.373142)
		(width 0.09525)
		(layer "B.Cu")
		(net "SAS2X28_B_HDD5_TX_-")
	)
	(arc
		(start 12.113006 -158.16072)
		(mid 14.366071 -158.608994)
		(end 16.276066 -159.88538)
		(width 0.09525)
		(layer "B.Cu")
		(net "SAS2X28_B_HDD5_TX_-")
	)
	(arc
		(start 16.814546 -169.457878)
		(mid 16.972969 -170.254031)
		(end 17.423892 -170.929046)
		(width 0.09525)
		(layer "B.Cu")
		(net "SAS2X28_B_HDD5_TX_-")
	)
	(arc
		(start 41.157906 -303.80686)
		(mid 40.793206 -304.352716)
		(end 40.665146 -304.996596)
		(width 0.09525)
		(layer "B.Cu")
		(net "SAS2X28_B_HDD5_TX_-")
	)
	(arc
		(start 36.9316 -458.3938)
		(mid 35.451797 -459.797595)
		(end 33.996884 -461.22717)
		(width 0.09525)
		(layer "B.Cu")
		(net "SAS2X28_B_HDD5_TX_-")
	)
	(arc
		(start 33.4264 -472.54668)
		(mid 33.485883 -472.8461)
		(end 33.655508 -473.099892)
		(width 0.09525)
		(layer "B.Cu")
		(net "SAS2X28_B_HDD5_TX_-")
	)
	(arc
		(start 40.665146 -349.166942)
		(mid 40.630739 -349.339738)
		(end 40.532812 -349.48622)
		(width 0.09525)
		(layer "B.Cu")
		(net "SAS2X28_B_HDD5_TX_-")
	)
	(arc
		(start 36.646866 -427.905926)
		(mid 37.252155 -428.811761)
		(end 37.464746 -429.880268)
		(width 0.09525)
		(layer "B.Cu")
		(net "SAS2X28_B_HDD5_TX_-")
	)
	(arc
		(start 16.276066 -159.88538)
		(mid 16.674434 -160.481579)
		(end 16.814292 -161.184844)
		(width 0.09525)
		(layer "B.Cu")
		(net "SAS2X28_B_HDD5_TX_-")
	)
	(arc
		(start 34.4932 -473.4052)
		(mid 34.692118 -473.444861)
		(end 34.860738 -473.5576)
		(width 0.09525)
		(layer "B.Cu")
		(net "SAS2X28_B_HDD5_TX_-")
	)
	(arc
		(start 46.257718 -206.256128)
		(mid 46.555092 -206.70118)
		(end 46.659546 -207.226154)
		(width 0.09525)
		(layer "B.Cu")
		(net "SAS2X28_B_HDD5_TX_-")
	)
	(arc
		(start 33.996884 -461.22717)
		(mid 33.574641 -461.859147)
		(end 33.4264 -462.604612)
		(width 0.09525)
		(layer "B.Cu")
		(net "SAS2X28_B_HDD5_TX_-")
	)
	(arc
		(start 32.701992 -367.696496)
		(mid 32.602048 -368.199596)
		(end 32.317182 -368.626136)
		(width 0.09525)
		(layer "B.Cu")
		(net "SAS2X28_B_HDD5_TX_-")
	)
	(arc
		(start 35.267646 -188.7728)
		(mid 35.402589 -188.974757)
		(end 35.450018 -189.212982)
		(width 0.09525)
		(layer "B.Cu")
		(net "SAS2X28_B_HDD5_TX_-")
	)
	(via
		(at 204.444346 -395.4653)
		(size 0.5588)
		(drill 0.3048)
		(layers "F.Cu" "B.Cu")
		(net "P12V_HDD1")
	)
	(via
		(at 204.444346 -394.5255)
		(size 0.7112)
		(drill 0.3556)
		(layers "F.Cu" "B.Cu")
		(net "P12V_HDD1")
	)
	(via
		(at 219.414852 -391.789412)
		(size 0.7112)
		(drill 0.3556)
		(layers "F.Cu" "B.Cu")
		(net "P12V_HDD1")
	)
	(via
		(at 220.350842 -391.876534)
		(size 0.5588)
		(drill 0.3048)
		(layers "F.Cu" "B.Cu")
		(net "P12V_HDD1")
	)
	(segment
		(start 204.444346 -394.5255)
		(end 204.444346 -395.4653)
		(width 0.508)
		(layer "B.Cu")
		(net "P12V_HDD1")
	)
	(segment
		(start 220.350842 -391.876534)
		(end 220.26372 -391.789412)
		(width 0.508)
		(layer "B.Cu")
		(net "P12V_HDD1")
	)
	(segment
		(start 220.26372 -391.789412)
		(end 219.414852 -391.789412)
		(width 0.508)
		(layer "B.Cu")
		(net "P12V_HDD1")
	)
	(via
		(at 62.0776 -281.9908)
		(size 0.7112)
		(drill 0.3556)
		(layers "F.Cu" "B.Cu")
		(net "P5V_HDD7")
	)
	(via
		(at 59.309 -282.7274)
		(size 0.7112)
		(drill 0.3556)
		(layers "F.Cu" "B.Cu")
		(net "P5V_HDD7")
	)
	(via
		(at 63.5 -286.512)
		(size 0.7112)
		(drill 0.3556)
		(layers "F.Cu" "B.Cu")
		(net "P5V_HDD7")
	)
	(segment
		(start 4.657344 -157.498796)
		(end 3.192526 -157.498796)
		(width 0.09525)
		(layer "F.Cu")
		(net "SAS2X28_B_HDD5_TX_+")
	)
	(segment
		(start 40.39997 -472.990164)
		(end 39.503096 -472.990164)
		(width 0.09525)
		(layer "F.Cu")
		(net "SAS2X28_B_HDD5_TX_+")
	)
	(segment
		(start 39.503096 -472.990164)
		(end 39.499794 -472.986862)
		(width 0.09525)
		(layer "F.Cu")
		(net "SAS2X28_B_HDD5_TX_+")
	)
	(segment
		(start 6.262878 -157.83052)
		(end 5.456174 -157.83052)
		(width 0.09525)
		(layer "F.Cu")
		(net "SAS2X28_B_HDD5_TX_+")
	)
	(segment
		(start 4.658868 -157.50032)
		(end 4.657344 -157.498796)
		(width 0.09525)
		(layer "F.Cu")
		(net "SAS2X28_B_HDD5_TX_+")
	)
	(segment
		(start 38.93312 -473.221558)
		(end 35.889946 -473.221558)
		(width 0.09525)
		(layer "F.Cu")
		(net "SAS2X28_B_HDD5_TX_+")
	)
	(segment
		(start 35.144202 -472.912694)
		(end 35.051746 -472.820238)
		(width 0.09525)
		(layer "F.Cu")
		(net "SAS2X28_B_HDD5_TX_+")
	)
	(via
		(at 6.984746 -157.531562)
		(size 0.5588)
		(drill 0.3048)
		(layers "F.Cu" "B.Cu")
		(net "SAS2X28_B_HDD5_TX_+")
	)
	(via
		(at 35.051746 -472.820238)
		(size 0.5588)
		(drill 0.3048)
		(layers "F.Cu" "B.Cu")
		(net "SAS2X28_B_HDD5_TX_+")
	)
	(arc
		(start 35.889946 -473.221558)
		(mid 35.880166 -473.221477)
		(end 35.870388 -473.221304)
		(width 0.09525)
		(layer "F.Cu")
		(net "SAS2X28_B_HDD5_TX_+")
	)
	(arc
		(start 35.870388 -473.221304)
		(mid 35.477361 -473.137445)
		(end 35.144202 -472.912694)
		(width 0.09525)
		(layer "F.Cu")
		(net "SAS2X28_B_HDD5_TX_+")
	)
	(arc
		(start 39.156894 -473.128848)
		(mid 39.054226 -473.197449)
		(end 38.93312 -473.221558)
		(width 0.09525)
		(layer "F.Cu")
		(net "SAS2X28_B_HDD5_TX_+")
	)
	(arc
		(start 5.456174 -157.83052)
		(mid 5.319411 -157.803316)
		(end 5.203444 -157.725872)
		(width 0.09525)
		(layer "F.Cu")
		(net "SAS2X28_B_HDD5_TX_+")
	)
	(arc
		(start 5.203444 -157.725872)
		(mid 4.95359 -157.558925)
		(end 4.658868 -157.50032)
		(width 0.09525)
		(layer "F.Cu")
		(net "SAS2X28_B_HDD5_TX_+")
	)
	(arc
		(start 39.499794 -472.986862)
		(mid 39.314236 -473.023772)
		(end 39.156894 -473.128848)
		(width 0.09525)
		(layer "F.Cu")
		(net "SAS2X28_B_HDD5_TX_+")
	)
	(arc
		(start 6.984746 -157.531562)
		(mid 6.65355 -157.75286)
		(end 6.262878 -157.83052)
		(width 0.09525)
		(layer "F.Cu")
		(net "SAS2X28_B_HDD5_TX_+")
	)
	(segment
		(start 46.763432 -298.66844)
		(end 41.391332 -304.04054)
		(width 0.09525)
		(layer "B.Cu")
		(net "SAS2X28_B_HDD5_TX_+")
	)
	(segment
		(start 7.706614 -157.83052)
		(end 12.113006 -157.83052)
		(width 0.09525)
		(layer "B.Cu")
		(net "SAS2X28_B_HDD5_TX_+")
	)
	(segment
		(start 46.989746 -207.2259)
		(end 46.989746 -298.122086)
		(width 0.09525)
		(layer "B.Cu")
		(net "SAS2X28_B_HDD5_TX_+")
	)
	(segment
		(start 34.3408 -473.075)
		(end 34.6202 -473.075)
		(width 0.09525)
		(layer "B.Cu")
		(net "SAS2X28_B_HDD5_TX_+")
	)
	(segment
		(start 40.995346 -304.996596)
		(end 40.995346 -349.167196)
		(width 0.09525)
		(layer "B.Cu")
		(net "SAS2X28_B_HDD5_TX_+")
	)
	(segment
		(start 32.550608 -368.859816)
		(end 29.388308 -372.022116)
		(width 0.09525)
		(layer "B.Cu")
		(net "SAS2X28_B_HDD5_TX_+")
	)
	(segment
		(start 40.766492 -349.719646)
		(end 33.451292 -357.034846)
		(width 0.09525)
		(layer "B.Cu")
		(net "SAS2X28_B_HDD5_TX_+")
	)
	(segment
		(start 17.144746 -161.184844)
		(end 17.144746 -169.457624)
		(width 0.09525)
		(layer "B.Cu")
		(net "SAS2X28_B_HDD5_TX_+")
	)
	(segment
		(start 36.153344 -195.684648)
		(end 46.491398 -206.022702)
		(width 0.09525)
		(layer "B.Cu")
		(net "SAS2X28_B_HDD5_TX_+")
	)
	(segment
		(start 37.794946 -429.880522)
		(end 37.794946 -457.149454)
		(width 0.09525)
		(layer "B.Cu")
		(net "SAS2X28_B_HDD5_TX_+")
	)
	(segment
		(start 35.501072 -188.53912)
		(end 35.501072 -188.539374)
		(width 0.09525)
		(layer "B.Cu")
		(net "SAS2X28_B_HDD5_TX_+")
	)
	(segment
		(start 29.616146 -420.4081)
		(end 36.880292 -427.672246)
		(width 0.09525)
		(layer "B.Cu")
		(net "SAS2X28_B_HDD5_TX_+")
	)
	(segment
		(start 17.657572 -170.69562)
		(end 35.501072 -188.53912)
		(width 0.09525)
		(layer "B.Cu")
		(net "SAS2X28_B_HDD5_TX_+")
	)
	(segment
		(start 33.032446 -358.04602)
		(end 33.032446 -367.696496)
		(width 0.09525)
		(layer "B.Cu")
		(net "SAS2X28_B_HDD5_TX_+")
	)
	(segment
		(start 34.921952 -472.950032)
		(end 35.051746 -472.820238)
		(width 0.09525)
		(layer "B.Cu")
		(net "SAS2X28_B_HDD5_TX_+")
	)
	(segment
		(start 33.888934 -472.866466)
		(end 33.925256 -472.902788)
		(width 0.09525)
		(layer "B.Cu")
		(net "SAS2X28_B_HDD5_TX_+")
	)
	(segment
		(start 33.7566 -462.604358)
		(end 33.7566 -472.546934)
		(width 0.09525)
		(layer "B.Cu")
		(net "SAS2X28_B_HDD5_TX_+")
	)
	(segment
		(start 28.828746 -373.373142)
		(end 28.828746 -418.507164)
		(width 0.09525)
		(layer "B.Cu")
		(net "SAS2X28_B_HDD5_TX_+")
	)
	(segment
		(start 35.780218 -189.212728)
		(end 35.780218 -194.783964)
		(width 0.09525)
		(layer "B.Cu")
		(net "SAS2X28_B_HDD5_TX_+")
	)
	(segment
		(start 34.230564 -461.46085)
		(end 34.23031 -461.460596)
		(width 0.09525)
		(layer "B.Cu")
		(net "SAS2X28_B_HDD5_TX_+")
	)
	(arc
		(start 6.984746 -157.531562)
		(mid 7.315942 -157.75286)
		(end 7.706614 -157.83052)
		(width 0.09525)
		(layer "B.Cu")
		(net "SAS2X28_B_HDD5_TX_+")
	)
	(arc
		(start 34.23031 -461.460596)
		(mid 33.879675 -461.985358)
		(end 33.7566 -462.604358)
		(width 0.09525)
		(layer "B.Cu")
		(net "SAS2X28_B_HDD5_TX_+")
	)
	(arc
		(start 37.156898 -458.635354)
		(mid 35.68132 -460.035248)
		(end 34.230564 -461.46085)
		(width 0.09525)
		(layer "B.Cu")
		(net "SAS2X28_B_HDD5_TX_+")
	)
	(arc
		(start 34.6202 -473.075)
		(mid 34.783499 -473.042518)
		(end 34.921952 -472.950032)
		(width 0.09525)
		(layer "B.Cu")
		(net "SAS2X28_B_HDD5_TX_+")
	)
	(arc
		(start 33.925256 -472.902788)
		(mid 34.115895 -473.030232)
		(end 34.3408 -473.075)
		(width 0.09525)
		(layer "B.Cu")
		(net "SAS2X28_B_HDD5_TX_+")
	)
	(arc
		(start 35.501072 -188.539374)
		(mid 35.70761 -188.848296)
		(end 35.780218 -189.212728)
		(width 0.09525)
		(layer "B.Cu")
		(net "SAS2X28_B_HDD5_TX_+")
	)
	(arc
		(start 29.388308 -372.022116)
		(mid 28.974133 -372.641972)
		(end 28.828746 -373.373142)
		(width 0.09525)
		(layer "B.Cu")
		(net "SAS2X28_B_HDD5_TX_+")
	)
	(arc
		(start 36.880292 -427.672246)
		(mid 37.557238 -428.685412)
		(end 37.794946 -429.880522)
		(width 0.09525)
		(layer "B.Cu")
		(net "SAS2X28_B_HDD5_TX_+")
	)
	(arc
		(start 17.144746 -169.457624)
		(mid 17.278019 -170.127635)
		(end 17.657572 -170.69562)
		(width 0.09525)
		(layer "B.Cu")
		(net "SAS2X28_B_HDD5_TX_+")
	)
	(arc
		(start 16.509746 -159.6517)
		(mid 16.979751 -160.355112)
		(end 17.144746 -161.184844)
		(width 0.09525)
		(layer "B.Cu")
		(net "SAS2X28_B_HDD5_TX_+")
	)
	(arc
		(start 46.491398 -206.022702)
		(mid 46.86023 -206.574747)
		(end 46.989746 -207.2259)
		(width 0.09525)
		(layer "B.Cu")
		(net "SAS2X28_B_HDD5_TX_+")
	)
	(arc
		(start 33.032446 -367.696496)
		(mid 32.907216 -368.326071)
		(end 32.550608 -368.859816)
		(width 0.09525)
		(layer "B.Cu")
		(net "SAS2X28_B_HDD5_TX_+")
	)
	(arc
		(start 12.113006 -157.83052)
		(mid 14.492501 -158.303831)
		(end 16.509746 -159.6517)
		(width 0.09525)
		(layer "B.Cu")
		(net "SAS2X28_B_HDD5_TX_+")
	)
	(arc
		(start 41.391332 -304.04054)
		(mid 41.098241 -304.479182)
		(end 40.995346 -304.996596)
		(width 0.09525)
		(layer "B.Cu")
		(net "SAS2X28_B_HDD5_TX_+")
	)
	(arc
		(start 40.995346 -349.167196)
		(mid 40.935873 -349.466188)
		(end 40.766492 -349.719646)
		(width 0.09525)
		(layer "B.Cu")
		(net "SAS2X28_B_HDD5_TX_+")
	)
	(arc
		(start 33.451292 -357.034846)
		(mid 33.141304 -357.498777)
		(end 33.032446 -358.04602)
		(width 0.09525)
		(layer "B.Cu")
		(net "SAS2X28_B_HDD5_TX_+")
	)
	(arc
		(start 28.828746 -418.507164)
		(mid 29.033383 -419.535946)
		(end 29.616146 -420.4081)
		(width 0.09525)
		(layer "B.Cu")
		(net "SAS2X28_B_HDD5_TX_+")
	)
	(arc
		(start 37.794946 -457.149454)
		(mid 37.63218 -457.959506)
		(end 37.156898 -458.635354)
		(width 0.09525)
		(layer "B.Cu")
		(net "SAS2X28_B_HDD5_TX_+")
	)
	(arc
		(start 46.989746 -298.122086)
		(mid 46.93093 -298.417773)
		(end 46.763432 -298.66844)
		(width 0.09525)
		(layer "B.Cu")
		(net "SAS2X28_B_HDD5_TX_+")
	)
	(arc
		(start 35.780218 -194.783964)
		(mid 35.877181 -195.27143)
		(end 36.153344 -195.684648)
		(width 0.09525)
		(layer "B.Cu")
		(net "SAS2X28_B_HDD5_TX_+")
	)
	(arc
		(start 33.7566 -472.546934)
		(mid 33.790996 -472.719856)
		(end 33.888934 -472.866466)
		(width 0.09525)
		(layer "B.Cu")
		(net "SAS2X28_B_HDD5_TX_+")
	)
	(via
		(at 210.693 -382.524)
		(size 0.7112)
		(drill 0.3556)
		(layers "F.Cu" "B.Cu")
		(net "P5V_HDD1")
	)
	(via
		(at 218.059 -383.794)
		(size 0.7112)
		(drill 0.3556)
		(layers "F.Cu" "B.Cu")
		(net "P5V_HDD1")
	)
	(segment
		(start 32.598868 -475.171516)
		(end 32.587946 -475.182692)
		(width 0.09525)
		(layer "F.Cu")
		(net "SAS2X28_B_HDD5_RX_-")
	)
	(segment
		(start 31.439866 -475.295976)
		(end 31.341822 -475.198186)
		(width 0.09525)
		(layer "F.Cu")
		(net "SAS2X28_B_HDD5_RX_-")
	)
	(segment
		(start 32.003746 -475.4245)
		(end 31.749746 -475.4245)
		(width 0.09525)
		(layer "F.Cu")
		(net "SAS2X28_B_HDD5_RX_-")
	)
	(via
		(at 31.341822 -475.198186)
		(size 0.5588)
		(drill 0.3048)
		(layers "F.Cu" "B.Cu")
		(net "SAS2X28_B_HDD5_RX_-")
	)
	(arc
		(start 31.749746 -475.4245)
		(mid 31.58203 -475.391046)
		(end 31.439866 -475.295976)
		(width 0.09525)
		(layer "F.Cu")
		(net "SAS2X28_B_HDD5_RX_-")
	)
	(arc
		(start 32.587946 -475.182692)
		(mid 32.319898 -475.361703)
		(end 32.003746 -475.4245)
		(width 0.09525)
		(layer "F.Cu")
		(net "SAS2X28_B_HDD5_RX_-")
	)
	(segment
		(start 17.957546 -161.162746)
		(end 17.957292 -161.163)
		(width 0.09525)
		(layer "B.Cu")
		(net "SAS2X28_B_HDD5_RX_-")
	)
	(segment
		(start 38.925246 -450.703442)
		(end 38.925246 -450.417692)
		(width 0.09525)
		(layer "B.Cu")
		(net "SAS2X28_B_HDD5_RX_-")
	)
	(segment
		(start 38.692836 -449.952872)
		(end 38.692836 -449.667122)
		(width 0.09525)
		(layer "B.Cu")
		(net "SAS2X28_B_HDD5_RX_-")
	)
	(segment
		(start 30.035246 -372.237508)
		(end 33.0454 -369.227354)
		(width 0.09525)
		(layer "B.Cu")
		(net "SAS2X28_B_HDD5_RX_-")
	)
	(segment
		(start 37.4904 -473.3798)
		(end 37.4904 -460.01686)
		(width 0.09525)
		(layer "B.Cu")
		(net "SAS2X28_B_HDD5_RX_-")
	)
	(segment
		(start 35.986466 -187.901326)
		(end 18.28292 -170.19778)
		(width 0.09525)
		(layer "B.Cu")
		(net "SAS2X28_B_HDD5_RX_-")
	)
	(segment
		(start 41.604692 -349.473012)
		(end 41.604946 -349.473012)
		(width 0.09525)
		(layer "B.Cu")
		(net "SAS2X28_B_HDD5_RX_-")
	)
	(segment
		(start 38.925246 -449.202302)
		(end 38.925246 -448.916552)
		(width 0.09525)
		(layer "B.Cu")
		(net "SAS2X28_B_HDD5_RX_-")
	)
	(segment
		(start 38.048184 -427.977808)
		(end 30.072838 -420.002462)
		(width 0.09525)
		(layer "B.Cu")
		(net "SAS2X28_B_HDD5_RX_-")
	)
	(segment
		(start 38.925246 -457.6064)
		(end 38.925246 -453.419972)
		(width 0.09525)
		(layer "B.Cu")
		(net "SAS2X28_B_HDD5_RX_-")
	)
	(segment
		(start 38.925246 -447.701162)
		(end 38.925246 -447.415412)
		(width 0.09525)
		(layer "B.Cu")
		(net "SAS2X28_B_HDD5_RX_-")
	)
	(segment
		(start 41.604946 -349.473012)
		(end 41.604946 -305.230276)
		(width 0.09525)
		(layer "B.Cu")
		(net "SAS2X28_B_HDD5_RX_-")
	)
	(segment
		(start 16.985488 -158.816548)
		(end 15.514066 -157.345126)
		(width 0.09525)
		(layer "B.Cu")
		(net "SAS2X28_B_HDD5_RX_-")
	)
	(segment
		(start 36.638992 -474.992446)
		(end 36.951412 -474.680026)
		(width 0.09525)
		(layer "B.Cu")
		(net "SAS2X28_B_HDD5_RX_-")
	)
	(segment
		(start 38.502336 -458.49921)
		(end 38.593014 -458.408786)
		(width 0.09525)
		(layer "B.Cu")
		(net "SAS2X28_B_HDD5_RX_-")
	)
	(segment
		(start 47.100236 -205.76921)
		(end 36.914836 -195.58381)
		(width 0.09525)
		(layer "B.Cu")
		(net "SAS2X28_B_HDD5_RX_-")
	)
	(segment
		(start 38.692836 -451.454012)
		(end 38.692836 -451.168262)
		(width 0.09525)
		(layer "B.Cu")
		(net "SAS2X28_B_HDD5_RX_-")
	)
	(segment
		(start 38.692836 -448.451732)
		(end 38.692836 -448.165982)
		(width 0.09525)
		(layer "B.Cu")
		(net "SAS2X28_B_HDD5_RX_-")
	)
	(segment
		(start 4.641596 -156.498798)
		(end 2.811526 -156.498798)
		(width 0.09525)
		(layer "B.Cu")
		(net "SAS2X28_B_HDD5_RX_-")
	)
	(segment
		(start 31.682436 -475.5388)
		(end 35.45967 -475.5388)
		(width 0.09525)
		(layer "B.Cu")
		(net "SAS2X28_B_HDD5_RX_-")
	)
	(segment
		(start 38.692836 -452.955152)
		(end 38.692836 -452.669402)
		(width 0.09525)
		(layer "B.Cu")
		(net "SAS2X28_B_HDD5_RX_-")
	)
	(segment
		(start 37.847778 -459.154022)
		(end 37.847524 -459.153768)
		(width 0.09525)
		(layer "B.Cu")
		(net "SAS2X28_B_HDD5_RX_-")
	)
	(segment
		(start 47.599346 -298.302172)
		(end 47.599346 -206.974186)
		(width 0.09525)
		(layer "B.Cu")
		(net "SAS2X28_B_HDD5_RX_-")
	)
	(segment
		(start 38.925246 -446.200022)
		(end 38.925246 -430.095152)
		(width 0.09525)
		(layer "B.Cu")
		(net "SAS2X28_B_HDD5_RX_-")
	)
	(segment
		(start 29.438346 -418.470588)
		(end 29.438346 -373.678704)
		(width 0.09525)
		(layer "B.Cu")
		(net "SAS2X28_B_HDD5_RX_-")
	)
	(segment
		(start 38.925246 -452.204582)
		(end 38.925246 -451.918832)
		(width 0.09525)
		(layer "B.Cu")
		(net "SAS2X28_B_HDD5_RX_-")
	)
	(segment
		(start 15.513812 -157.345126)
		(end 15.443962 -157.275276)
		(width 0.09525)
		(layer "B.Cu")
		(net "SAS2X28_B_HDD5_RX_-")
	)
	(segment
		(start 17.957546 -169.412158)
		(end 17.957546 -161.162746)
		(width 0.09525)
		(layer "B.Cu")
		(net "SAS2X28_B_HDD5_RX_-")
	)
	(segment
		(start 36.638992 -474.992954)
		(end 36.638992 -474.992446)
		(width 0.09525)
		(layer "B.Cu")
		(net "SAS2X28_B_HDD5_RX_-")
	)
	(segment
		(start 12.754102 -156.160724)
		(end 5.463032 -156.160724)
		(width 0.09525)
		(layer "B.Cu")
		(net "SAS2X28_B_HDD5_RX_-")
	)
	(segment
		(start 38.692836 -446.950592)
		(end 38.692836 -446.664842)
		(width 0.09525)
		(layer "B.Cu")
		(net "SAS2X28_B_HDD5_RX_-")
	)
	(segment
		(start 4.64312 -156.500322)
		(end 4.641596 -156.498798)
		(width 0.09525)
		(layer "B.Cu")
		(net "SAS2X28_B_HDD5_RX_-")
	)
	(segment
		(start 47.599092 -298.302172)
		(end 47.599346 -298.302172)
		(width 0.09525)
		(layer "B.Cu")
		(net "SAS2X28_B_HDD5_RX_-")
	)
	(segment
		(start 37.490654 -473.3798)
		(end 37.4904 -473.3798)
		(width 0.09525)
		(layer "B.Cu")
		(net "SAS2X28_B_HDD5_RX_-")
	)
	(segment
		(start 38.9255 -457.6064)
		(end 38.925246 -457.6064)
		(width 0.09525)
		(layer "B.Cu")
		(net "SAS2X28_B_HDD5_RX_-")
	)
	(segment
		(start 36.541202 -475.090744)
		(end 36.638992 -474.992954)
		(width 0.09525)
		(layer "B.Cu")
		(net "SAS2X28_B_HDD5_RX_-")
	)
	(segment
		(start 33.642046 -367.78692)
		(end 33.642046 -358.639364)
		(width 0.09525)
		(layer "B.Cu")
		(net "SAS2X28_B_HDD5_RX_-")
	)
	(segment
		(start 36.495736 -194.571874)
		(end 36.495736 -189.130686)
		(width 0.09525)
		(layer "B.Cu")
		(net "SAS2X28_B_HDD5_RX_-")
	)
	(segment
		(start 41.98747 -304.306732)
		(end 47.321724 -298.972478)
		(width 0.09525)
		(layer "B.Cu")
		(net "SAS2X28_B_HDD5_RX_-")
	)
	(segment
		(start 37.847524 -459.153768)
		(end 38.502336 -458.49921)
		(width 0.09525)
		(layer "B.Cu")
		(net "SAS2X28_B_HDD5_RX_-")
	)
	(segment
		(start 15.514066 -157.345126)
		(end 15.513812 -157.345126)
		(width 0.09525)
		(layer "B.Cu")
		(net "SAS2X28_B_HDD5_RX_-")
	)
	(segment
		(start 34.301684 -357.046784)
		(end 41.413684 -349.934784)
		(width 0.09525)
		(layer "B.Cu")
		(net "SAS2X28_B_HDD5_RX_-")
	)
	(arc
		(start 38.925246 -447.415412)
		(mid 38.895449 -447.285094)
		(end 38.809168 -447.183002)
		(width 0.09525)
		(layer "B.Cu")
		(net "SAS2X28_B_HDD5_RX_-")
	)
	(arc
		(start 38.809168 -452.436992)
		(mid 38.895399 -452.334875)
		(end 38.925246 -452.204582)
		(width 0.09525)
		(layer "B.Cu")
		(net "SAS2X28_B_HDD5_RX_-")
	)
	(arc
		(start 38.809168 -453.187562)
		(mid 38.722769 -453.085488)
		(end 38.692836 -452.955152)
		(width 0.09525)
		(layer "B.Cu")
		(net "SAS2X28_B_HDD5_RX_-")
	)
	(arc
		(start 38.925246 -453.419972)
		(mid 38.895449 -453.289654)
		(end 38.809168 -453.187562)
		(width 0.09525)
		(layer "B.Cu")
		(net "SAS2X28_B_HDD5_RX_-")
	)
	(arc
		(start 38.692836 -446.664842)
		(mid 38.722772 -446.534507)
		(end 38.809168 -446.432432)
		(width 0.09525)
		(layer "B.Cu")
		(net "SAS2X28_B_HDD5_RX_-")
	)
	(arc
		(start 15.443962 -157.275276)
		(mid 14.209874 -156.450499)
		(end 12.754102 -156.160724)
		(width 0.09525)
		(layer "B.Cu")
		(net "SAS2X28_B_HDD5_RX_-")
	)
	(arc
		(start 36.495736 -189.130686)
		(mid 36.363391 -188.465341)
		(end 35.986466 -187.901326)
		(width 0.09525)
		(layer "B.Cu")
		(net "SAS2X28_B_HDD5_RX_-")
	)
	(arc
		(start 41.413684 -349.934784)
		(mid 41.555056 -349.722878)
		(end 41.604692 -349.473012)
		(width 0.09525)
		(layer "B.Cu")
		(net "SAS2X28_B_HDD5_RX_-")
	)
	(arc
		(start 36.951412 -474.680026)
		(mid 37.350316 -474.083537)
		(end 37.490654 -473.3798)
		(width 0.09525)
		(layer "B.Cu")
		(net "SAS2X28_B_HDD5_RX_-")
	)
	(arc
		(start 33.642046 -358.639364)
		(mid 33.813418 -357.777438)
		(end 34.301684 -357.046784)
		(width 0.09525)
		(layer "B.Cu")
		(net "SAS2X28_B_HDD5_RX_-")
	)
	(arc
		(start 38.809168 -450.935852)
		(mid 38.895399 -450.833735)
		(end 38.925246 -450.703442)
		(width 0.09525)
		(layer "B.Cu")
		(net "SAS2X28_B_HDD5_RX_-")
	)
	(arc
		(start 38.925246 -450.417692)
		(mid 38.895449 -450.287374)
		(end 38.809168 -450.185282)
		(width 0.09525)
		(layer "B.Cu")
		(net "SAS2X28_B_HDD5_RX_-")
	)
	(arc
		(start 31.341822 -475.198186)
		(mid 31.441586 -475.439036)
		(end 31.682436 -475.5388)
		(width 0.09525)
		(layer "B.Cu")
		(net "SAS2X28_B_HDD5_RX_-")
	)
	(arc
		(start 47.599346 -206.974186)
		(mid 47.46963 -206.322061)
		(end 47.100236 -205.76921)
		(width 0.09525)
		(layer "B.Cu")
		(net "SAS2X28_B_HDD5_RX_-")
	)
	(arc
		(start 37.4904 -460.01686)
		(mid 37.583215 -459.549864)
		(end 37.847778 -459.154022)
		(width 0.09525)
		(layer "B.Cu")
		(net "SAS2X28_B_HDD5_RX_-")
	)
	(arc
		(start 38.809168 -450.185282)
		(mid 38.722769 -450.083208)
		(end 38.692836 -449.952872)
		(width 0.09525)
		(layer "B.Cu")
		(net "SAS2X28_B_HDD5_RX_-")
	)
	(arc
		(start 5.463032 -156.160724)
		(mid 5.322284 -156.18872)
		(end 5.202936 -156.26842)
		(width 0.09525)
		(layer "B.Cu")
		(net "SAS2X28_B_HDD5_RX_-")
	)
	(arc
		(start 38.809168 -447.933572)
		(mid 38.895399 -447.831455)
		(end 38.925246 -447.701162)
		(width 0.09525)
		(layer "B.Cu")
		(net "SAS2X28_B_HDD5_RX_-")
	)
	(arc
		(start 17.957292 -161.163)
		(mid 17.70472 -159.893144)
		(end 16.985488 -158.816548)
		(width 0.09525)
		(layer "B.Cu")
		(net "SAS2X28_B_HDD5_RX_-")
	)
	(arc
		(start 38.809168 -451.686422)
		(mid 38.722769 -451.584348)
		(end 38.692836 -451.454012)
		(width 0.09525)
		(layer "B.Cu")
		(net "SAS2X28_B_HDD5_RX_-")
	)
	(arc
		(start 38.925246 -430.095152)
		(mid 38.69731 -428.949242)
		(end 38.048184 -427.977808)
		(width 0.09525)
		(layer "B.Cu")
		(net "SAS2X28_B_HDD5_RX_-")
	)
	(arc
		(start 38.692836 -449.667122)
		(mid 38.722772 -449.536787)
		(end 38.809168 -449.434712)
		(width 0.09525)
		(layer "B.Cu")
		(net "SAS2X28_B_HDD5_RX_-")
	)
	(arc
		(start 33.0454 -369.227354)
		(mid 33.486984 -368.566477)
		(end 33.642046 -367.78692)
		(width 0.09525)
		(layer "B.Cu")
		(net "SAS2X28_B_HDD5_RX_-")
	)
	(arc
		(start 35.45967 -475.5388)
		(mid 36.04499 -475.422337)
		(end 36.541202 -475.090744)
		(width 0.09525)
		(layer "B.Cu")
		(net "SAS2X28_B_HDD5_RX_-")
	)
	(arc
		(start 38.692836 -451.168262)
		(mid 38.722772 -451.037927)
		(end 38.809168 -450.935852)
		(width 0.09525)
		(layer "B.Cu")
		(net "SAS2X28_B_HDD5_RX_-")
	)
	(arc
		(start 38.692836 -448.165982)
		(mid 38.722772 -448.035647)
		(end 38.809168 -447.933572)
		(width 0.09525)
		(layer "B.Cu")
		(net "SAS2X28_B_HDD5_RX_-")
	)
	(arc
		(start 38.809168 -449.434712)
		(mid 38.895399 -449.332595)
		(end 38.925246 -449.202302)
		(width 0.09525)
		(layer "B.Cu")
		(net "SAS2X28_B_HDD5_RX_-")
	)
	(arc
		(start 18.28292 -170.19778)
		(mid 18.042107 -169.837333)
		(end 17.957546 -169.412158)
		(width 0.09525)
		(layer "B.Cu")
		(net "SAS2X28_B_HDD5_RX_-")
	)
	(arc
		(start 38.809168 -446.432432)
		(mid 38.895399 -446.330315)
		(end 38.925246 -446.200022)
		(width 0.09525)
		(layer "B.Cu")
		(net "SAS2X28_B_HDD5_RX_-")
	)
	(arc
		(start 38.809168 -447.183002)
		(mid 38.722769 -447.080928)
		(end 38.692836 -446.950592)
		(width 0.09525)
		(layer "B.Cu")
		(net "SAS2X28_B_HDD5_RX_-")
	)
	(arc
		(start 5.202936 -156.26842)
		(mid 4.94609 -156.440039)
		(end 4.64312 -156.500322)
		(width 0.09525)
		(layer "B.Cu")
		(net "SAS2X28_B_HDD5_RX_-")
	)
	(arc
		(start 47.321724 -298.972478)
		(mid 47.527025 -298.664896)
		(end 47.599092 -298.302172)
		(width 0.09525)
		(layer "B.Cu")
		(net "SAS2X28_B_HDD5_RX_-")
	)
	(arc
		(start 29.438346 -373.678704)
		(mid 29.59354 -372.898784)
		(end 30.035246 -372.237508)
		(width 0.09525)
		(layer "B.Cu")
		(net "SAS2X28_B_HDD5_RX_-")
	)
	(arc
		(start 38.692836 -452.669402)
		(mid 38.722772 -452.539067)
		(end 38.809168 -452.436992)
		(width 0.09525)
		(layer "B.Cu")
		(net "SAS2X28_B_HDD5_RX_-")
	)
	(arc
		(start 38.809168 -448.684142)
		(mid 38.722769 -448.582068)
		(end 38.692836 -448.451732)
		(width 0.09525)
		(layer "B.Cu")
		(net "SAS2X28_B_HDD5_RX_-")
	)
	(arc
		(start 38.925246 -448.916552)
		(mid 38.895449 -448.786234)
		(end 38.809168 -448.684142)
		(width 0.09525)
		(layer "B.Cu")
		(net "SAS2X28_B_HDD5_RX_-")
	)
	(arc
		(start 30.072838 -420.002462)
		(mid 29.603251 -419.299631)
		(end 29.438346 -418.470588)
		(width 0.09525)
		(layer "B.Cu")
		(net "SAS2X28_B_HDD5_RX_-")
	)
	(arc
		(start 36.914836 -195.58381)
		(mid 36.604643 -195.119529)
		(end 36.495736 -194.571874)
		(width 0.09525)
		(layer "B.Cu")
		(net "SAS2X28_B_HDD5_RX_-")
	)
	(arc
		(start 41.604946 -305.230276)
		(mid 41.704417 -304.730491)
		(end 41.98747 -304.306732)
		(width 0.09525)
		(layer "B.Cu")
		(net "SAS2X28_B_HDD5_RX_-")
	)
	(arc
		(start 38.925246 -451.918832)
		(mid 38.895449 -451.788514)
		(end 38.809168 -451.686422)
		(width 0.09525)
		(layer "B.Cu")
		(net "SAS2X28_B_HDD5_RX_-")
	)
	(arc
		(start 38.593014 -458.408786)
		(mid 38.839025 -458.040649)
		(end 38.9255 -457.6064)
		(width 0.09525)
		(layer "B.Cu")
		(net "SAS2X28_B_HDD5_RX_-")
	)
	(segment
		(start 5.193792 -401.027392)
		(end 4.666742 -400.500342)
		(width 0.111252)
		(layer "F.Cu")
		(net "HB_EXP_A_INPUT")
	)
	(segment
		(start 10.368026 -399.402808)
		(end 10.368026 -399.860516)
		(width 0.111252)
		(layer "F.Cu")
		(net "HB_EXP_A_INPUT")
	)
	(segment
		(start 3.19405 -400.500342)
		(end 3.192526 -400.498818)
		(width 0.111252)
		(layer "F.Cu")
		(net "HB_EXP_A_INPUT")
	)
	(segment
		(start 4.666742 -400.500342)
		(end 3.19405 -400.500342)
		(width 0.111252)
		(layer "F.Cu")
		(net "HB_EXP_A_INPUT")
	)
	(segment
		(start 10.368026 -399.860516)
		(end 9.20115 -401.027392)
		(width 0.111252)
		(layer "F.Cu")
		(net "HB_EXP_A_INPUT")
	)
	(segment
		(start 9.20115 -401.027392)
		(end 5.193792 -401.027392)
		(width 0.111252)
		(layer "F.Cu")
		(net "HB_EXP_A_INPUT")
	)
	(segment
		(start 11.290808 -162.331908)
		(end 10.507218 -162.331908)
		(width 0.111252)
		(layer "F.Cu")
		(net "HB_EXP_A_INPUT")
	)
	(segment
		(start 9.704832 -398.739614)
		(end 10.368026 -399.402808)
		(width 0.111252)
		(layer "F.Cu")
		(net "HB_EXP_A_INPUT")
	)
	(segment
		(start 10.507218 -163.237418)
		(end 10.507218 -162.331908)
		(width 0.111252)
		(layer "F.Cu")
		(net "HB_EXP_A_INPUT")
	)
	(segment
		(start 11.4173 -162.4584)
		(end 11.290808 -162.331908)
		(width 0.111252)
		(layer "F.Cu")
		(net "HB_EXP_A_INPUT")
	)
	(segment
		(start 10.541 -163.2712)
		(end 10.507218 -163.237418)
		(width 0.111252)
		(layer "F.Cu")
		(net "HB_EXP_A_INPUT")
	)
	(via
		(at 10.541 -163.2712)
		(size 0.5588)
		(drill 0.3048)
		(layers "F.Cu" "B.Cu")
		(net "HB_EXP_A_INPUT")
	)
	(via
		(at 9.704832 -398.739614)
		(size 0.5588)
		(drill 0.3048)
		(layers "F.Cu" "B.Cu")
		(net "HB_EXP_A_INPUT")
	)
	(via
		(at 10.507218 -162.331908)
		(size 0.7112)
		(drill 0.3556)
		(layers "F.Cu" "B.Cu")
		(net "HB_EXP_A_INPUT")
	)
	(segment
		(start 8.238744 -211.845144)
		(end 8.238744 -208.02854)
		(width 0.14605)
		(layer "In2.Cu")
		(net "HB_EXP_A_INPUT")
	)
	(segment
		(start 10.58164 -268.836394)
		(end 10.581386 -268.83614)
		(width 0.14605)
		(layer "In2.Cu")
		(net "HB_EXP_A_INPUT")
	)
	(segment
		(start 7.486396 -189.218824)
		(end 7.486396 -178.7271)
		(width 0.14605)
		(layer "In2.Cu")
		(net "HB_EXP_A_INPUT")
	)
	(segment
		(start 10.287 -163.5252)
		(end 10.541 -163.2712)
		(width 0.14605)
		(layer "In2.Cu")
		(net "HB_EXP_A_INPUT")
	)
	(segment
		(start 8.724138 -217.619326)
		(end 8.724138 -212.330538)
		(width 0.14605)
		(layer "In2.Cu")
		(net "HB_EXP_A_INPUT")
	)
	(segment
		(start 11.04265 -367.368836)
		(end 10.58164 -366.907826)
		(width 0.14605)
		(layer "In2.Cu")
		(net "HB_EXP_A_INPUT")
	)
	(segment
		(start 8.724138 -212.330538)
		(end 8.238744 -211.845144)
		(width 0.14605)
		(layer "In2.Cu")
		(net "HB_EXP_A_INPUT")
	)
	(segment
		(start 10.581386 -264.72388)
		(end 11.3538 -263.951466)
		(width 0.14605)
		(layer "In2.Cu")
		(net "HB_EXP_A_INPUT")
	)
	(segment
		(start 8.238744 -208.02854)
		(end 8.531098 -207.736186)
		(width 0.14605)
		(layer "In2.Cu")
		(net "HB_EXP_A_INPUT")
	)
	(segment
		(start 10.273538 -257.605784)
		(end 10.273538 -219.168726)
		(width 0.14605)
		(layer "In2.Cu")
		(net "HB_EXP_A_INPUT")
	)
	(segment
		(start 9.419844 -391.720578)
		(end 10.524998 -390.615424)
		(width 0.14605)
		(layer "In2.Cu")
		(net "HB_EXP_A_INPUT")
	)
	(segment
		(start 10.273538 -219.168726)
		(end 8.724138 -217.619326)
		(width 0.14605)
		(layer "In2.Cu")
		(net "HB_EXP_A_INPUT")
	)
	(segment
		(start 10.836402 -258.168648)
		(end 10.273538 -257.605784)
		(width 0.14605)
		(layer "In2.Cu")
		(net "HB_EXP_A_INPUT")
	)
	(segment
		(start 7.3025 -199.5297)
		(end 7.819898 -199.012302)
		(width 0.14605)
		(layer "In2.Cu")
		(net "HB_EXP_A_INPUT")
	)
	(segment
		(start 10.58164 -366.907826)
		(end 10.58164 -268.836394)
		(width 0.14605)
		(layer "In2.Cu")
		(net "HB_EXP_A_INPUT")
	)
	(segment
		(start 11.3538 -263.951466)
		(end 11.3538 -260.45414)
		(width 0.14605)
		(layer "In2.Cu")
		(net "HB_EXP_A_INPUT")
	)
	(segment
		(start 7.486396 -178.7271)
		(end 8.099298 -178.114198)
		(width 0.14605)
		(layer "In2.Cu")
		(net "HB_EXP_A_INPUT")
	)
	(segment
		(start 7.819898 -189.552326)
		(end 7.486396 -189.218824)
		(width 0.14605)
		(layer "In2.Cu")
		(net "HB_EXP_A_INPUT")
	)
	(segment
		(start 8.099298 -178.114198)
		(end 8.099298 -176.140364)
		(width 0.14605)
		(layer "In2.Cu")
		(net "HB_EXP_A_INPUT")
	)
	(segment
		(start 9.704832 -398.739614)
		(end 9.709912 -398.734534)
		(width 0.14605)
		(layer "In2.Cu")
		(net "HB_EXP_A_INPUT")
	)
	(segment
		(start 5.489194 -173.53026)
		(end 5.489194 -168.78681)
		(width 0.14605)
		(layer "In2.Cu")
		(net "HB_EXP_A_INPUT")
	)
	(segment
		(start 7.3025 -205.283054)
		(end 7.3025 -199.5297)
		(width 0.14605)
		(layer "In2.Cu")
		(net "HB_EXP_A_INPUT")
	)
	(segment
		(start 9.419844 -395.44879)
		(end 9.419844 -391.720578)
		(width 0.14605)
		(layer "In2.Cu")
		(net "HB_EXP_A_INPUT")
	)
	(segment
		(start 9.709912 -395.738858)
		(end 9.419844 -395.44879)
		(width 0.14605)
		(layer "In2.Cu")
		(net "HB_EXP_A_INPUT")
	)
	(segment
		(start 11.353546 -260.453886)
		(end 11.353546 -259.897626)
		(width 0.14605)
		(layer "In2.Cu")
		(net "HB_EXP_A_INPUT")
	)
	(segment
		(start 10.524998 -390.615424)
		(end 10.524998 -374.56364)
		(width 0.14605)
		(layer "In2.Cu")
		(net "HB_EXP_A_INPUT")
	)
	(segment
		(start 6.661404 -167.6146)
		(end 7.624826 -167.6146)
		(width 0.14605)
		(layer "In2.Cu")
		(net "HB_EXP_A_INPUT")
	)
	(segment
		(start 11.3538 -260.45414)
		(end 11.353546 -260.453886)
		(width 0.14605)
		(layer "In2.Cu")
		(net "HB_EXP_A_INPUT")
	)
	(segment
		(start 8.099298 -176.140364)
		(end 5.489194 -173.53026)
		(width 0.14605)
		(layer "In2.Cu")
		(net "HB_EXP_A_INPUT")
	)
	(segment
		(start 7.624826 -167.6146)
		(end 10.287 -164.952426)
		(width 0.14605)
		(layer "In2.Cu")
		(net "HB_EXP_A_INPUT")
	)
	(segment
		(start 11.04265 -374.045988)
		(end 11.04265 -367.368836)
		(width 0.14605)
		(layer "In2.Cu")
		(net "HB_EXP_A_INPUT")
	)
	(segment
		(start 10.287 -164.952426)
		(end 10.287 -163.5252)
		(width 0.14605)
		(layer "In2.Cu")
		(net "HB_EXP_A_INPUT")
	)
	(segment
		(start 8.531098 -207.736186)
		(end 8.531098 -206.511652)
		(width 0.14605)
		(layer "In2.Cu")
		(net "HB_EXP_A_INPUT")
	)
	(segment
		(start 10.524998 -374.56364)
		(end 11.04265 -374.045988)
		(width 0.14605)
		(layer "In2.Cu")
		(net "HB_EXP_A_INPUT")
	)
	(segment
		(start 9.709912 -398.734534)
		(end 9.709912 -395.738858)
		(width 0.14605)
		(layer "In2.Cu")
		(net "HB_EXP_A_INPUT")
	)
	(segment
		(start 7.819898 -199.012302)
		(end 7.819898 -189.552326)
		(width 0.14605)
		(layer "In2.Cu")
		(net "HB_EXP_A_INPUT")
	)
	(segment
		(start 5.489194 -168.78681)
		(end 6.661404 -167.6146)
		(width 0.14605)
		(layer "In2.Cu")
		(net "HB_EXP_A_INPUT")
	)
	(segment
		(start 8.531098 -206.511652)
		(end 7.3025 -205.283054)
		(width 0.14605)
		(layer "In2.Cu")
		(net "HB_EXP_A_INPUT")
	)
	(segment
		(start 11.353546 -259.897626)
		(end 10.836402 -259.342128)
		(width 0.14605)
		(layer "In2.Cu")
		(net "HB_EXP_A_INPUT")
	)
	(segment
		(start 10.581386 -268.83614)
		(end 10.581386 -264.72388)
		(width 0.14605)
		(layer "In2.Cu")
		(net "HB_EXP_A_INPUT")
	)
	(segment
		(start 10.836402 -259.342128)
		(end 10.836402 -258.168648)
		(width 0.14605)
		(layer "In2.Cu")
		(net "HB_EXP_A_INPUT")
	)
	(segment
		(start 15.028672 -472.15552)
		(end 13.568172 -470.69502)
		(width 0.09525)
		(layer "F.Cu")
		(net "SAS2X28_A_HDD5_RX_-")
	)
	(segment
		(start 12.991846 -469.303608)
		(end 12.991846 -425.649644)
		(width 0.09525)
		(layer "F.Cu")
		(net "SAS2X28_A_HDD5_RX_-")
	)
	(segment
		(start 32.000444 -469.19642)
		(end 28.916122 -469.19642)
		(width 0.09525)
		(layer "F.Cu")
		(net "SAS2X28_A_HDD5_RX_-")
	)
	(segment
		(start 7.729982 -421.075104)
		(end 7.729982 -421.075612)
		(width 0.09525)
		(layer "F.Cu")
		(net "SAS2X28_A_HDD5_RX_-")
	)
	(segment
		(start 12.34567 -424.165522)
		(end 9.80567 -421.625522)
		(width 0.09525)
		(layer "F.Cu")
		(net "SAS2X28_A_HDD5_RX_-")
	)
	(segment
		(start 8.66013 -420.770304)
		(end 8.435086 -420.770304)
		(width 0.09525)
		(layer "F.Cu")
		(net "SAS2X28_A_HDD5_RX_-")
	)
	(segment
		(start 27.449526 -469.80348)
		(end 25.227026 -472.026234)
		(width 0.09525)
		(layer "F.Cu")
		(net "SAS2X28_A_HDD5_RX_-")
	)
	(segment
		(start 7.752334 -421.052752)
		(end 7.729982 -421.075104)
		(width 0.09525)
		(layer "F.Cu")
		(net "SAS2X28_A_HDD5_RX_-")
	)
	(segment
		(start 27.44978 -469.803734)
		(end 27.449526 -469.80348)
		(width 0.09525)
		(layer "F.Cu")
		(net "SAS2X28_A_HDD5_RX_-")
	)
	(segment
		(start 24.074882 -472.5035)
		(end 15.86865 -472.5035)
		(width 0.09525)
		(layer "F.Cu")
		(net "SAS2X28_A_HDD5_RX_-")
	)
	(segment
		(start 12.399264 -424.21937)
		(end 12.34567 -424.165522)
		(width 0.09525)
		(layer "F.Cu")
		(net "SAS2X28_A_HDD5_RX_-")
	)
	(segment
		(start 7.491984 -421.676322)
		(end 7.2644 -421.903906)
		(width 0.09525)
		(layer "F.Cu")
		(net "SAS2X28_A_HDD5_RX_-")
	)
	(segment
		(start 9.80567 -421.625522)
		(end 9.156446 -420.976044)
		(width 0.09525)
		(layer "F.Cu")
		(net "SAS2X28_A_HDD5_RX_-")
	)
	(via
		(at 7.2644 -421.903906)
		(size 0.5588)
		(drill 0.3048)
		(layers "F.Cu" "B.Cu")
		(net "SAS2X28_A_HDD5_RX_-")
	)
	(arc
		(start 13.568172 -470.69502)
		(mid 13.141617 -470.056635)
		(end 12.991846 -469.303608)
		(width 0.09525)
		(layer "F.Cu")
		(net "SAS2X28_A_HDD5_RX_-")
	)
	(arc
		(start 12.991846 -425.649644)
		(mid 12.837835 -424.875559)
		(end 12.399264 -424.21937)
		(width 0.09525)
		(layer "F.Cu")
		(net "SAS2X28_A_HDD5_RX_-")
	)
	(arc
		(start 9.156446 -420.976044)
		(mid 9.069169 -420.90193)
		(end 8.971026 -420.842948)
		(width 0.09525)
		(layer "F.Cu")
		(net "SAS2X28_A_HDD5_RX_-")
	)
	(arc
		(start 7.729982 -421.075612)
		(mid 7.59225 -421.281659)
		(end 7.543546 -421.524684)
		(width 0.09525)
		(layer "F.Cu")
		(net "SAS2X28_A_HDD5_RX_-")
	)
	(arc
		(start 32.598868 -468.948516)
		(mid 32.324309 -469.131971)
		(end 32.000444 -469.19642)
		(width 0.09525)
		(layer "F.Cu")
		(net "SAS2X28_A_HDD5_RX_-")
	)
	(arc
		(start 8.435086 -420.770304)
		(mid 8.065638 -420.843662)
		(end 7.752334 -421.052752)
		(width 0.09525)
		(layer "F.Cu")
		(net "SAS2X28_A_HDD5_RX_-")
	)
	(arc
		(start 25.227026 -472.026234)
		(mid 24.698418 -472.379439)
		(end 24.074882 -472.5035)
		(width 0.09525)
		(layer "F.Cu")
		(net "SAS2X28_A_HDD5_RX_-")
	)
	(arc
		(start 7.543546 -421.524684)
		(mid 7.543532 -421.528875)
		(end 7.543546 -421.533066)
		(width 0.09525)
		(layer "F.Cu")
		(net "SAS2X28_A_HDD5_RX_-")
	)
	(arc
		(start 28.916122 -469.19642)
		(mid 28.122529 -469.3542)
		(end 27.44978 -469.803734)
		(width 0.09525)
		(layer "F.Cu")
		(net "SAS2X28_A_HDD5_RX_-")
	)
	(arc
		(start 7.543546 -421.533066)
		(mid 7.543642 -421.539544)
		(end 7.5438 -421.54602)
		(width 0.09525)
		(layer "F.Cu")
		(net "SAS2X28_A_HDD5_RX_-")
	)
	(arc
		(start 7.5438 -421.54602)
		(mid 7.531346 -421.616524)
		(end 7.491984 -421.676322)
		(width 0.09525)
		(layer "F.Cu")
		(net "SAS2X28_A_HDD5_RX_-")
	)
	(arc
		(start 8.971026 -420.842948)
		(mid 8.819766 -420.788703)
		(end 8.66013 -420.770304)
		(width 0.09525)
		(layer "F.Cu")
		(net "SAS2X28_A_HDD5_RX_-")
	)
	(arc
		(start 15.86865 -472.5035)
		(mid 15.414038 -472.413072)
		(end 15.028672 -472.15552)
		(width 0.09525)
		(layer "F.Cu")
		(net "SAS2X28_A_HDD5_RX_-")
	)
	(segment
		(start 7.241794 -418.982652)
		(end 6.9088 -418.649658)
		(width 0.09525)
		(layer "B.Cu")
		(net "SAS2X28_A_HDD5_RX_-")
	)
	(segment
		(start 6.9088 -418.64915)
		(end 6.860794 -418.601398)
		(width 0.09525)
		(layer "B.Cu")
		(net "SAS2X28_A_HDD5_RX_-")
	)
	(segment
		(start 4.675378 -418.498782)
		(end 2.811526 -418.498782)
		(width 0.09525)
		(layer "B.Cu")
		(net "SAS2X28_A_HDD5_RX_-")
	)
	(segment
		(start 6.860794 -418.601398)
		(end 6.649974 -418.390578)
		(width 0.09525)
		(layer "B.Cu")
		(net "SAS2X28_A_HDD5_RX_-")
	)
	(segment
		(start 6.095746 -418.160708)
		(end 5.496814 -418.160708)
		(width 0.09525)
		(layer "B.Cu")
		(net "SAS2X28_A_HDD5_RX_-")
	)
	(segment
		(start 6.9088 -418.649658)
		(end 6.9088 -418.64915)
		(width 0.09525)
		(layer "B.Cu")
		(net "SAS2X28_A_HDD5_RX_-")
	)
	(segment
		(start 7.543546 -421.230044)
		(end 7.543546 -419.711124)
		(width 0.09525)
		(layer "B.Cu")
		(net "SAS2X28_A_HDD5_RX_-")
	)
	(segment
		(start 4.676902 -418.500306)
		(end 4.675378 -418.498782)
		(width 0.09525)
		(layer "B.Cu")
		(net "SAS2X28_A_HDD5_RX_-")
	)
	(segment
		(start 6.46811 -418.254942)
		(end 6.46811 -418.255196)
		(width 0.09525)
		(layer "B.Cu")
		(net "SAS2X28_A_HDD5_RX_-")
	)
	(arc
		(start 5.496814 -418.160708)
		(mid 5.372979 -418.18534)
		(end 5.26796 -418.25545)
		(width 0.09525)
		(layer "B.Cu")
		(net "SAS2X28_A_HDD5_RX_-")
	)
	(arc
		(start 5.26796 -418.25545)
		(mid 4.99678 -418.436646)
		(end 4.676902 -418.500306)
		(width 0.09525)
		(layer "B.Cu")
		(net "SAS2X28_A_HDD5_RX_-")
	)
	(arc
		(start 7.543546 -419.711124)
		(mid 7.465125 -419.316874)
		(end 7.241794 -418.982652)
		(width 0.09525)
		(layer "B.Cu")
		(net "SAS2X28_A_HDD5_RX_-")
	)
	(arc
		(start 7.2644 -421.903906)
		(mid 7.470981 -421.594735)
		(end 7.543546 -421.230044)
		(width 0.09525)
		(layer "B.Cu")
		(net "SAS2X28_A_HDD5_RX_-")
	)
	(arc
		(start 6.649974 -418.390578)
		(mid 6.563979 -418.31614)
		(end 6.46811 -418.254942)
		(width 0.09525)
		(layer "B.Cu")
		(net "SAS2X28_A_HDD5_RX_-")
	)
	(arc
		(start 6.46811 -418.255196)
		(mid 6.287807 -418.18478)
		(end 6.095746 -418.160708)
		(width 0.09525)
		(layer "B.Cu")
		(net "SAS2X28_A_HDD5_RX_-")
	)
	(segment
		(start 30.608778 -335.647284)
		(end 30.608778 -334.5307)
		(width 0.111252)
		(layer "F.Cu")
		(net "SAS2X28_B_HDD11_FLT")
	)
	(segment
		(start 8.559546 -142.7099)
		(end 8.349996 -142.50035)
		(width 0.111252)
		(layer "F.Cu")
		(net "SAS2X28_B_HDD11_FLT")
	)
	(segment
		(start 3.19405 -142.50035)
		(end 3.192526 -142.498826)
		(width 0.111252)
		(layer "F.Cu")
		(net "SAS2X28_B_HDD11_FLT")
	)
	(segment
		(start 30.494986 -334.416908)
		(end 30.494986 -333.1972)
		(width 0.111252)
		(layer "F.Cu")
		(net "SAS2X28_B_HDD11_FLT")
	)
	(segment
		(start 8.349996 -142.50035)
		(end 3.19405 -142.50035)
		(width 0.111252)
		(layer "F.Cu")
		(net "SAS2X28_B_HDD11_FLT")
	)
	(segment
		(start 30.608778 -334.5307)
		(end 30.494986 -334.416908)
		(width 0.111252)
		(layer "F.Cu")
		(net "SAS2X28_B_HDD11_FLT")
	)
	(via
		(at 30.608778 -334.5307)
		(size 0.5588)
		(drill 0.3048)
		(layers "F.Cu" "B.Cu")
		(net "SAS2X28_B_HDD11_FLT")
	)
	(via
		(at 94.017846 -335.2927)
		(size 0.5588)
		(drill 0.3048)
		(layers "F.Cu" "B.Cu")
		(net "SAS2X28_B_HDD11_FLT")
	)
	(via
		(at 8.559546 -142.7099)
		(size 0.5588)
		(drill 0.3048)
		(layers "F.Cu" "B.Cu")
		(net "SAS2X28_B_HDD11_FLT")
	)
	(via
		(at 9.613646 -142.6083)
		(size 0.7112)
		(drill 0.3556)
		(layers "F.Cu" "B.Cu")
		(net "SAS2X28_B_HDD11_FLT")
	)
	(segment
		(start 8.673846 -142.6083)
		(end 9.613646 -142.6083)
		(width 0.111252)
		(layer "B.Cu")
		(net "SAS2X28_B_HDD11_FLT")
	)
	(segment
		(start 8.559546 -142.7099)
		(end 8.673846 -142.6083)
		(width 0.111252)
		(layer "B.Cu")
		(net "SAS2X28_B_HDD11_FLT")
	)
	(segment
		(start 42.443146 -336.0547)
		(end 93.255846 -336.0547)
		(width 0.14605)
		(layer "In2.Cu")
		(net "SAS2X28_B_HDD11_FLT")
	)
	(segment
		(start 39.776146 -333.3877)
		(end 42.443146 -336.0547)
		(width 0.14605)
		(layer "In2.Cu")
		(net "SAS2X28_B_HDD11_FLT")
	)
	(segment
		(start 30.608778 -334.5307)
		(end 31.751778 -333.3877)
		(width 0.14605)
		(layer "In2.Cu")
		(net "SAS2X28_B_HDD11_FLT")
	)
	(segment
		(start 31.751778 -333.3877)
		(end 39.776146 -333.3877)
		(width 0.14605)
		(layer "In2.Cu")
		(net "SAS2X28_B_HDD11_FLT")
	)
	(segment
		(start 93.255846 -336.0547)
		(end 94.017846 -335.2927)
		(width 0.14605)
		(layer "In2.Cu")
		(net "SAS2X28_B_HDD11_FLT")
	)
	(segment
		(start 9.785604 -134.433564)
		(end 9.785604 -136.728454)
		(width 0.14605)
		(layer "In5.Cu")
		(net "SAS2X28_B_HDD11_FLT")
	)
	(segment
		(start 10.696448 -129.77368)
		(end 11.134852 -130.212084)
		(width 0.14605)
		(layer "In5.Cu")
		(net "SAS2X28_B_HDD11_FLT")
	)
	(segment
		(start 95.983298 -106.540046)
		(end 88.03005 -98.586798)
		(width 0.14605)
		(layer "In5.Cu")
		(net "SAS2X28_B_HDD11_FLT")
	)
	(segment
		(start 9.137396 -142.13205)
		(end 8.559546 -142.7099)
		(width 0.14605)
		(layer "In5.Cu")
		(net "SAS2X28_B_HDD11_FLT")
	)
	(segment
		(start 94.017846 -335.2927)
		(end 94.017846 -225.765614)
		(width 0.14605)
		(layer "In5.Cu")
		(net "SAS2X28_B_HDD11_FLT")
	)
	(segment
		(start 95.983298 -223.800162)
		(end 95.983298 -106.540046)
		(width 0.14605)
		(layer "In5.Cu")
		(net "SAS2X28_B_HDD11_FLT")
	)
	(segment
		(start 10.696448 -109.037882)
		(end 10.696448 -129.77368)
		(width 0.14605)
		(layer "In5.Cu")
		(net "SAS2X28_B_HDD11_FLT")
	)
	(segment
		(start 88.03005 -98.586798)
		(end 21.147532 -98.586798)
		(width 0.14605)
		(layer "In5.Cu")
		(net "SAS2X28_B_HDD11_FLT")
	)
	(segment
		(start 9.506966 -138.733784)
		(end 9.506966 -139.555982)
		(width 0.14605)
		(layer "In5.Cu")
		(net "SAS2X28_B_HDD11_FLT")
	)
	(segment
		(start 9.137396 -139.925044)
		(end 9.137396 -142.13205)
		(width 0.14605)
		(layer "In5.Cu")
		(net "SAS2X28_B_HDD11_FLT")
	)
	(segment
		(start 9.506966 -139.555982)
		(end 9.137396 -139.925044)
		(width 0.14605)
		(layer "In5.Cu")
		(net "SAS2X28_B_HDD11_FLT")
	)
	(segment
		(start 11.134852 -133.084316)
		(end 9.785604 -134.433564)
		(width 0.14605)
		(layer "In5.Cu")
		(net "SAS2X28_B_HDD11_FLT")
	)
	(segment
		(start 94.017846 -225.765614)
		(end 95.983298 -223.800162)
		(width 0.14605)
		(layer "In5.Cu")
		(net "SAS2X28_B_HDD11_FLT")
	)
	(segment
		(start 11.134852 -130.212084)
		(end 11.134852 -133.084316)
		(width 0.14605)
		(layer "In5.Cu")
		(net "SAS2X28_B_HDD11_FLT")
	)
	(segment
		(start 9.785604 -136.728454)
		(end 9.515094 -136.998964)
		(width 0.14605)
		(layer "In5.Cu")
		(net "SAS2X28_B_HDD11_FLT")
	)
	(segment
		(start 21.147532 -98.586798)
		(end 10.696448 -109.037882)
		(width 0.14605)
		(layer "In5.Cu")
		(net "SAS2X28_B_HDD11_FLT")
	)
	(segment
		(start 9.515094 -138.725656)
		(end 9.506966 -138.733784)
		(width 0.14605)
		(layer "In5.Cu")
		(net "SAS2X28_B_HDD11_FLT")
	)
	(segment
		(start 9.515094 -136.998964)
		(end 9.515094 -138.725656)
		(width 0.14605)
		(layer "In5.Cu")
		(net "SAS2X28_B_HDD11_FLT")
	)
	(segment
		(start 31.876746 -469.52662)
		(end 28.915868 -469.52662)
		(width 0.09525)
		(layer "F.Cu")
		(net "SAS2X28_A_HDD5_RX_+")
	)
	(segment
		(start 8.659114 -421.100504)
		(end 8.435086 -421.100504)
		(width 0.09525)
		(layer "F.Cu")
		(net "SAS2X28_A_HDD5_RX_+")
	)
	(segment
		(start 8.000746 -421.272208)
		(end 7.963662 -421.309292)
		(width 0.09525)
		(layer "F.Cu")
		(net "SAS2X28_A_HDD5_RX_+")
	)
	(segment
		(start 27.683206 -470.03716)
		(end 25.460452 -472.259914)
		(width 0.09525)
		(layer "F.Cu")
		(net "SAS2X28_A_HDD5_RX_+")
	)
	(segment
		(start 14.795246 -472.388946)
		(end 14.794992 -472.388946)
		(width 0.09525)
		(layer "F.Cu")
		(net "SAS2X28_A_HDD5_RX_+")
	)
	(segment
		(start 12.661646 -469.303608)
		(end 12.661646 -425.649644)
		(width 0.09525)
		(layer "F.Cu")
		(net "SAS2X28_A_HDD5_RX_+")
	)
	(segment
		(start 14.794992 -472.388946)
		(end 13.334746 -470.9287)
		(width 0.09525)
		(layer "F.Cu")
		(net "SAS2X28_A_HDD5_RX_+")
	)
	(segment
		(start 12.112244 -424.399202)
		(end 8.922766 -421.209724)
		(width 0.09525)
		(layer "F.Cu")
		(net "SAS2X28_A_HDD5_RX_+")
	)
	(segment
		(start 12.165838 -424.45305)
		(end 12.112244 -424.399202)
		(width 0.09525)
		(layer "F.Cu")
		(net "SAS2X28_A_HDD5_RX_+")
	)
	(segment
		(start 24.075136 -472.8337)
		(end 15.868396 -472.8337)
		(width 0.09525)
		(layer "F.Cu")
		(net "SAS2X28_A_HDD5_RX_+")
	)
	(segment
		(start 32.598868 -469.837516)
		(end 32.578802 -469.81745)
		(width 0.09525)
		(layer "F.Cu")
		(net "SAS2X28_A_HDD5_RX_+")
	)
	(segment
		(start 7.919466 -421.717978)
		(end 8.127746 -421.926258)
		(width 0.09525)
		(layer "F.Cu")
		(net "SAS2X28_A_HDD5_RX_+")
	)
	(segment
		(start 7.905496 -421.390318)
		(end 7.905242 -421.390318)
		(width 0.09525)
		(layer "F.Cu")
		(net "SAS2X28_A_HDD5_RX_+")
	)
	(via
		(at 8.127746 -421.926258)
		(size 0.5588)
		(drill 0.3048)
		(layers "F.Cu" "B.Cu")
		(net "SAS2X28_A_HDD5_RX_+")
	)
	(arc
		(start 8.824722 -421.139112)
		(mid 8.819282 -421.136527)
		(end 8.8138 -421.134032)
		(width 0.09525)
		(layer "F.Cu")
		(net "SAS2X28_A_HDD5_RX_+")
	)
	(arc
		(start 7.963662 -421.309292)
		(mid 7.931263 -421.347424)
		(end 7.905496 -421.390318)
		(width 0.09525)
		(layer "F.Cu")
		(net "SAS2X28_A_HDD5_RX_+")
	)
	(arc
		(start 15.868396 -472.8337)
		(mid 15.287612 -472.718006)
		(end 14.795246 -472.388946)
		(width 0.09525)
		(layer "F.Cu")
		(net "SAS2X28_A_HDD5_RX_+")
	)
	(arc
		(start 8.435086 -421.100504)
		(mid 8.20156 -421.144985)
		(end 8.000746 -421.272208)
		(width 0.09525)
		(layer "F.Cu")
		(net "SAS2X28_A_HDD5_RX_+")
	)
	(arc
		(start 7.905242 -421.390318)
		(mid 7.881685 -421.456323)
		(end 7.873746 -421.525954)
		(width 0.09525)
		(layer "F.Cu")
		(net "SAS2X28_A_HDD5_RX_+")
	)
	(arc
		(start 8.8138 -421.134032)
		(mid 8.764551 -421.115742)
		(end 8.713216 -421.104568)
		(width 0.09525)
		(layer "F.Cu")
		(net "SAS2X28_A_HDD5_RX_+")
	)
	(arc
		(start 8.713216 -421.104568)
		(mid 8.686239 -421.101546)
		(end 8.659114 -421.100504)
		(width 0.09525)
		(layer "F.Cu")
		(net "SAS2X28_A_HDD5_RX_+")
	)
	(arc
		(start 8.922766 -421.209724)
		(mid 8.87663 -421.170411)
		(end 8.824722 -421.139112)
		(width 0.09525)
		(layer "F.Cu")
		(net "SAS2X28_A_HDD5_RX_+")
	)
	(arc
		(start 28.915868 -469.52662)
		(mid 28.248773 -469.659313)
		(end 27.683206 -470.03716)
		(width 0.09525)
		(layer "F.Cu")
		(net "SAS2X28_A_HDD5_RX_+")
	)
	(arc
		(start 7.873746 -421.530272)
		(mid 7.873858 -421.533448)
		(end 7.874 -421.536622)
		(width 0.09525)
		(layer "F.Cu")
		(net "SAS2X28_A_HDD5_RX_+")
	)
	(arc
		(start 25.460452 -472.259914)
		(mid 24.82485 -472.684576)
		(end 24.075136 -472.8337)
		(width 0.09525)
		(layer "F.Cu")
		(net "SAS2X28_A_HDD5_RX_+")
	)
	(arc
		(start 7.874 -421.536622)
		(mid 7.874109 -421.564071)
		(end 7.87273 -421.591486)
		(width 0.09525)
		(layer "F.Cu")
		(net "SAS2X28_A_HDD5_RX_+")
	)
	(arc
		(start 32.578802 -469.81745)
		(mid 32.256696 -469.602226)
		(end 31.876746 -469.52662)
		(width 0.09525)
		(layer "F.Cu")
		(net "SAS2X28_A_HDD5_RX_+")
	)
	(arc
		(start 13.334746 -470.9287)
		(mid 12.836582 -470.183101)
		(end 12.661646 -469.303608)
		(width 0.09525)
		(layer "F.Cu")
		(net "SAS2X28_A_HDD5_RX_+")
	)
	(arc
		(start 7.87273 -421.591486)
		(mid 7.882252 -421.659845)
		(end 7.919466 -421.717978)
		(width 0.09525)
		(layer "F.Cu")
		(net "SAS2X28_A_HDD5_RX_+")
	)
	(arc
		(start 12.661646 -425.649644)
		(mid 12.532737 -425.002043)
		(end 12.165838 -424.45305)
		(width 0.09525)
		(layer "F.Cu")
		(net "SAS2X28_A_HDD5_RX_+")
	)
	(arc
		(start 7.873746 -421.525954)
		(mid 7.873739 -421.528113)
		(end 7.873746 -421.530272)
		(width 0.09525)
		(layer "F.Cu")
		(net "SAS2X28_A_HDD5_RX_+")
	)
	(segment
		(start 7.873746 -421.313102)
		(end 7.873746 -419.71087)
		(width 0.09525)
		(layer "B.Cu")
		(net "SAS2X28_A_HDD5_RX_+")
	)
	(segment
		(start 6.095746 -417.830508)
		(end 5.51434 -417.830508)
		(width 0.09525)
		(layer "B.Cu")
		(net "SAS2X28_A_HDD5_RX_+")
	)
	(segment
		(start 7.411974 -418.685472)
		(end 7.411974 -418.685218)
		(width 0.09525)
		(layer "B.Cu")
		(net "SAS2X28_A_HDD5_RX_+")
	)
	(segment
		(start 7.475474 -418.748972)
		(end 7.411974 -418.685472)
		(width 0.09525)
		(layer "B.Cu")
		(net "SAS2X28_A_HDD5_RX_+")
	)
	(segment
		(start 7.239 -418.512244)
		(end 6.883654 -418.156898)
		(width 0.09525)
		(layer "B.Cu")
		(net "SAS2X28_A_HDD5_RX_+")
	)
	(segment
		(start 7.411974 -418.685218)
		(end 7.26948 -418.542978)
		(width 0.09525)
		(layer "B.Cu")
		(net "SAS2X28_A_HDD5_RX_+")
	)
	(segment
		(start 4.717288 -417.500308)
		(end 4.715764 -417.498784)
		(width 0.09525)
		(layer "B.Cu")
		(net "SAS2X28_A_HDD5_RX_+")
	)
	(segment
		(start 7.239 -418.512498)
		(end 7.239 -418.512244)
		(width 0.09525)
		(layer "B.Cu")
		(net "SAS2X28_A_HDD5_RX_+")
	)
	(segment
		(start 7.26948 -418.542978)
		(end 7.239 -418.512498)
		(width 0.09525)
		(layer "B.Cu")
		(net "SAS2X28_A_HDD5_RX_+")
	)
	(segment
		(start 4.715764 -417.498784)
		(end 2.811526 -417.498784)
		(width 0.09525)
		(layer "B.Cu")
		(net "SAS2X28_A_HDD5_RX_+")
	)
	(arc
		(start 8.127746 -421.926258)
		(mid 7.939775 -421.64494)
		(end 7.873746 -421.313102)
		(width 0.09525)
		(layer "B.Cu")
		(net "SAS2X28_A_HDD5_RX_+")
	)
	(arc
		(start 6.883654 -418.156898)
		(mid 6.522159 -417.915355)
		(end 6.095746 -417.830508)
		(width 0.09525)
		(layer "B.Cu")
		(net "SAS2X28_A_HDD5_RX_+")
	)
	(arc
		(start 5.239004 -417.716462)
		(mid 4.999639 -417.556523)
		(end 4.717288 -417.500308)
		(width 0.09525)
		(layer "B.Cu")
		(net "SAS2X28_A_HDD5_RX_+")
	)
	(arc
		(start 7.873746 -419.71087)
		(mid 7.770239 -419.190327)
		(end 7.475474 -418.748972)
		(width 0.09525)
		(layer "B.Cu")
		(net "SAS2X28_A_HDD5_RX_+")
	)
	(arc
		(start 5.51434 -417.830508)
		(mid 5.36533 -417.800868)
		(end 5.239004 -417.716462)
		(width 0.09525)
		(layer "B.Cu")
		(net "SAS2X28_A_HDD5_RX_+")
	)
	(segment
		(start 3.19405 -154.500326)
		(end 3.192526 -154.498802)
		(width 0.111252)
		(layer "F.Cu")
		(net "PWM_EXP_B")
	)
	(segment
		(start 3.406902 -154.287474)
		(end 3.19405 -154.500326)
		(width 0.111252)
		(layer "F.Cu")
		(net "PWM_EXP_B")
	)
	(segment
		(start 7.48792 -156.91612)
		(end 7.48792 -155.348178)
		(width 0.111252)
		(layer "F.Cu")
		(net "PWM_EXP_B")
	)
	(segment
		(start 6.427216 -154.287474)
		(end 3.406902 -154.287474)
		(width 0.111252)
		(layer "F.Cu")
		(net "PWM_EXP_B")
	)
	(segment
		(start 8.8138 -160.0708)
		(end 8.8138 -158.242)
		(width 0.111252)
		(layer "F.Cu")
		(net "PWM_EXP_B")
	)
	(segment
		(start 8.8138 -158.242)
		(end 7.48792 -156.91612)
		(width 0.111252)
		(layer "F.Cu")
		(net "PWM_EXP_B")
	)
	(segment
		(start 9.7282 -160.9852)
		(end 8.8138 -160.0708)
		(width 0.111252)
		(layer "F.Cu")
		(net "PWM_EXP_B")
	)
	(segment
		(start 7.48792 -155.348178)
		(end 6.427216 -154.287474)
		(width 0.111252)
		(layer "F.Cu")
		(net "PWM_EXP_B")
	)
	(via
		(at 88.842596 -402.0566)
		(size 0.5588)
		(drill 0.3048)
		(layers "F.Cu" "B.Cu")
		(net "PWM_EXP_B")
	)
	(via
		(at 250.5456 -416.382708)
		(size 0.5588)
		(drill 0.3048)
		(layers "F.Cu" "B.Cu")
		(net "PWM_EXP_B")
	)
	(via
		(at 9.7282 -160.9852)
		(size 0.5588)
		(drill 0.3048)
		(layers "F.Cu" "B.Cu")
		(net "PWM_EXP_B")
	)
	(via
		(at 8.8138 -158.242)
		(size 0.7112)
		(drill 0.3556)
		(layers "F.Cu" "B.Cu")
		(net "PWM_EXP_B")
	)
	(segment
		(start 250.5456 -416.382708)
		(end 250.5456 -416.4076)
		(width 0.111252)
		(layer "B.Cu")
		(net "PWM_EXP_B")
	)
	(segment
		(start 250.977908 -416.839908)
		(end 255.093978 -416.839908)
		(width 0.111252)
		(layer "B.Cu")
		(net "PWM_EXP_B")
	)
	(segment
		(start 250.5456 -416.4076)
		(end 250.977908 -416.839908)
		(width 0.111252)
		(layer "B.Cu")
		(net "PWM_EXP_B")
	)
	(segment
		(start 248.758964 -413.762444)
		(end 249.0089 -414.012634)
		(width 0.14605)
		(layer "In2.Cu")
		(net "PWM_EXP_B")
	)
	(segment
		(start 249.0089 -414.012634)
		(end 249.42927 -414.433258)
		(width 0.14605)
		(layer "In2.Cu")
		(net "PWM_EXP_B")
	)
	(segment
		(start 237.05312 -402.0566)
		(end 248.758964 -413.762444)
		(width 0.14605)
		(layer "In2.Cu")
		(net "PWM_EXP_B")
	)
	(segment
		(start 88.842596 -402.0566)
		(end 237.05312 -402.0566)
		(width 0.14605)
		(layer "In2.Cu")
		(net "PWM_EXP_B")
	)
	(segment
		(start 249.42927 -415.266378)
		(end 250.5456 -416.382708)
		(width 0.14605)
		(layer "In2.Cu")
		(net "PWM_EXP_B")
	)
	(segment
		(start 249.42927 -414.433258)
		(end 249.42927 -415.266378)
		(width 0.14605)
		(layer "In2.Cu")
		(net "PWM_EXP_B")
	)
	(segment
		(start 10.061448 -161.318448)
		(end 10.061448 -163.469828)
		(width 0.14605)
		(layer "In5.Cu")
		(net "PWM_EXP_B")
	)
	(segment
		(start 9.7282 -160.9852)
		(end 10.061448 -161.318448)
		(width 0.14605)
		(layer "In5.Cu")
		(net "PWM_EXP_B")
	)
	(segment
		(start 10.82167 -164.23005)
		(end 16.695928 -164.23005)
		(width 0.14605)
		(layer "In5.Cu")
		(net "PWM_EXP_B")
	)
	(segment
		(start 82.746088 -198.894446)
		(end 89.150698 -205.299056)
		(width 0.14605)
		(layer "In5.Cu")
		(net "PWM_EXP_B")
	)
	(segment
		(start 10.061448 -163.469828)
		(end 10.82167 -164.23005)
		(width 0.14605)
		(layer "In5.Cu")
		(net "PWM_EXP_B")
	)
	(segment
		(start 88.826594 -387.805676)
		(end 88.826594 -402.040598)
		(width 0.14605)
		(layer "In5.Cu")
		(net "PWM_EXP_B")
	)
	(segment
		(start 16.695928 -164.23005)
		(end 19.819112 -167.353234)
		(width 0.14605)
		(layer "In5.Cu")
		(net "PWM_EXP_B")
	)
	(segment
		(start 89.150698 -205.299056)
		(end 89.150698 -387.481572)
		(width 0.14605)
		(layer "In5.Cu")
		(net "PWM_EXP_B")
	)
	(segment
		(start 20.225512 -167.353234)
		(end 51.766724 -198.894446)
		(width 0.14605)
		(layer "In5.Cu")
		(net "PWM_EXP_B")
	)
	(segment
		(start 19.819112 -167.353234)
		(end 20.225512 -167.353234)
		(width 0.14605)
		(layer "In5.Cu")
		(net "PWM_EXP_B")
	)
	(segment
		(start 88.826594 -402.040598)
		(end 88.842596 -402.0566)
		(width 0.14605)
		(layer "In5.Cu")
		(net "PWM_EXP_B")
	)
	(segment
		(start 51.766724 -198.894446)
		(end 82.746088 -198.894446)
		(width 0.14605)
		(layer "In5.Cu")
		(net "PWM_EXP_B")
	)
	(segment
		(start 89.150698 -387.481572)
		(end 88.826594 -387.805676)
		(width 0.14605)
		(layer "In5.Cu")
		(net "PWM_EXP_B")
	)
	(segment
		(start 3.192526 -404.49881)
		(end 3.19405 -404.500334)
		(width 0.111252)
		(layer "F.Cu")
		(net "PWM_EXP_A")
	)
	(segment
		(start 8.572754 -405.828754)
		(end 9.4107 -406.6667)
		(width 0.111252)
		(layer "F.Cu")
		(net "PWM_EXP_A")
	)
	(segment
		(start 10.718546 -406.6667)
		(end 9.778746 -406.6667)
		(width 0.111252)
		(layer "F.Cu")
		(net "PWM_EXP_A")
	)
	(segment
		(start 9.4107 -406.6667)
		(end 9.778746 -406.6667)
		(width 0.111252)
		(layer "F.Cu")
		(net "PWM_EXP_A")
	)
	(segment
		(start 5.366766 -404.500334)
		(end 5.4737 -404.3934)
		(width 0.111252)
		(layer "F.Cu")
		(net "PWM_EXP_A")
	)
	(segment
		(start 3.19405 -404.500334)
		(end 5.366766 -404.500334)
		(width 0.111252)
		(layer "F.Cu")
		(net "PWM_EXP_A")
	)
	(segment
		(start 5.4737 -404.3934)
		(end 5.9436 -404.3934)
		(width 0.111252)
		(layer "F.Cu")
		(net "PWM_EXP_A")
	)
	(segment
		(start 5.9436 -404.3934)
		(end 7.378954 -405.828754)
		(width 0.111252)
		(layer "F.Cu")
		(net "PWM_EXP_A")
	)
	(segment
		(start 7.378954 -405.828754)
		(end 8.572754 -405.828754)
		(width 0.111252)
		(layer "F.Cu")
		(net "PWM_EXP_A")
	)
	(via
		(at 245.7704 -419.3794)
		(size 0.5588)
		(drill 0.3048)
		(layers "F.Cu" "B.Cu")
		(net "PWM_EXP_A")
	)
	(via
		(at 9.778746 -406.6667)
		(size 0.7112)
		(drill 0.3556)
		(layers "F.Cu" "B.Cu")
		(net "PWM_EXP_A")
	)
	(via
		(at 10.718546 -406.6667)
		(size 0.5588)
		(drill 0.3048)
		(layers "F.Cu" "B.Cu")
		(net "PWM_EXP_A")
	)
	(segment
		(start 245.7704 -419.3794)
		(end 245.770908 -419.379908)
		(width 0.111252)
		(layer "B.Cu")
		(net "PWM_EXP_A")
	)
	(segment
		(start 249.249184 -419.384734)
		(end 249.632216 -419.384734)
		(width 0.111252)
		(layer "B.Cu")
		(net "PWM_EXP_A")
	)
	(segment
		(start 249.632216 -419.384734)
		(end 249.637042 -419.379908)
		(width 0.111252)
		(layer "B.Cu")
		(net "PWM_EXP_A")
	)
	(segment
		(start 245.770908 -419.379908)
		(end 249.244358 -419.379908)
		(width 0.111252)
		(layer "B.Cu")
		(net "PWM_EXP_A")
	)
	(segment
		(start 249.637042 -419.379908)
		(end 255.093978 -419.379908)
		(width 0.111252)
		(layer "B.Cu")
		(net "PWM_EXP_A")
	)
	(segment
		(start 249.244358 -419.379908)
		(end 249.249184 -419.384734)
		(width 0.111252)
		(layer "B.Cu")
		(net "PWM_EXP_A")
	)
	(segment
		(start 245.7704 -427.188122)
		(end 245.7704 -419.3794)
		(width 0.14605)
		(layer "In5.Cu")
		(net "PWM_EXP_A")
	)
	(segment
		(start 6.5278 -456.335384)
		(end 8.18769 -457.995274)
		(width 0.14605)
		(layer "In5.Cu")
		(net "PWM_EXP_A")
	)
	(segment
		(start 5.679948 -435.348126)
		(end 5.679948 -442.702188)
		(width 0.14605)
		(layer "In5.Cu")
		(net "PWM_EXP_A")
	)
	(segment
		(start 8.18769 -457.995274)
		(end 8.18769 -461.519524)
		(width 0.14605)
		(layer "In5.Cu")
		(net "PWM_EXP_A")
	)
	(segment
		(start 34.636964 -469.52535)
		(end 203.433172 -469.52535)
		(width 0.14605)
		(layer "In5.Cu")
		(net "PWM_EXP_A")
	)
	(segment
		(start 8.18769 -461.519524)
		(end 16.336518 -469.668352)
		(width 0.14605)
		(layer "In5.Cu")
		(net "PWM_EXP_A")
	)
	(segment
		(start 34.493962 -469.668352)
		(end 34.636964 -469.52535)
		(width 0.14605)
		(layer "In5.Cu")
		(net "PWM_EXP_A")
	)
	(segment
		(start 10.718546 -406.6667)
		(end 10.718546 -430.309528)
		(width 0.14605)
		(layer "In5.Cu")
		(net "PWM_EXP_A")
	)
	(segment
		(start 6.5278 -443.55004)
		(end 6.5278 -456.335384)
		(width 0.14605)
		(layer "In5.Cu")
		(net "PWM_EXP_A")
	)
	(segment
		(start 10.718546 -430.309528)
		(end 5.679948 -435.348126)
		(width 0.14605)
		(layer "In5.Cu")
		(net "PWM_EXP_A")
	)
	(segment
		(start 16.336518 -469.668352)
		(end 34.493962 -469.668352)
		(width 0.14605)
		(layer "In5.Cu")
		(net "PWM_EXP_A")
	)
	(segment
		(start 203.433172 -469.52535)
		(end 245.7704 -427.188122)
		(width 0.14605)
		(layer "In5.Cu")
		(net "PWM_EXP_A")
	)
	(segment
		(start 5.679948 -442.702188)
		(end 6.5278 -443.55004)
		(width 0.14605)
		(layer "In5.Cu")
		(net "PWM_EXP_A")
	)
	(segment
		(start 7.238492 -140.500354)
		(end 3.19405 -140.500354)
		(width 0.111252)
		(layer "F.Cu")
		(net "SAS2X28_B_HDD5_FLT")
	)
	(segment
		(start 7.302246 -140.4366)
		(end 7.238492 -140.500354)
		(width 0.111252)
		(layer "F.Cu")
		(net "SAS2X28_B_HDD5_FLT")
	)
	(segment
		(start 10.947146 -141.1859)
		(end 10.947146 -141.1097)
		(width 0.111252)
		(layer "F.Cu")
		(net "SAS2X28_B_HDD5_FLT")
	)
	(segment
		(start 10.274046 -140.4366)
		(end 7.302246 -140.4366)
		(width 0.111252)
		(layer "F.Cu")
		(net "SAS2X28_B_HDD5_FLT")
	)
	(segment
		(start 73.242932 -495.700812)
		(end 73.242932 -494.891822)
		(width 0.111252)
		(layer "F.Cu")
		(net "SAS2X28_B_HDD5_FLT")
	)
	(segment
		(start 73.332086 -494.802668)
		(end 73.332086 -493.4458)
		(width 0.111252)
		(layer "F.Cu")
		(net "SAS2X28_B_HDD5_FLT")
	)
	(segment
		(start 73.242932 -494.891822)
		(end 73.332086 -494.802668)
		(width 0.111252)
		(layer "F.Cu")
		(net "SAS2X28_B_HDD5_FLT")
	)
	(segment
		(start 3.19405 -140.500354)
		(end 3.192526 -140.49883)
		(width 0.111252)
		(layer "F.Cu")
		(net "SAS2X28_B_HDD5_FLT")
	)
	(segment
		(start 10.947146 -141.1097)
		(end 10.274046 -140.4366)
		(width 0.111252)
		(layer "F.Cu")
		(net "SAS2X28_B_HDD5_FLT")
	)
	(via
		(at 88.518746 -447.5607)
		(size 0.5588)
		(drill 0.3048)
		(layers "F.Cu" "B.Cu")
		(net "SAS2X28_B_HDD5_FLT")
	)
	(via
		(at 76.19873 -459.880716)
		(size 0.7112)
		(drill 0.3556)
		(layers "F.Cu" "B.Cu")
		(net "SAS2X28_B_HDD5_FLT")
	)
	(via
		(at 73.332086 -494.802668)
		(size 0.5588)
		(drill 0.3048)
		(layers "F.Cu" "B.Cu")
		(net "SAS2X28_B_HDD5_FLT")
	)
	(via
		(at 10.947146 -141.1859)
		(size 0.5588)
		(drill 0.3048)
		(layers "F.Cu" "B.Cu")
		(net "SAS2X28_B_HDD5_FLT")
	)
	(segment
		(start 73.659746 -462.4197)
		(end 76.19873 -459.880716)
		(width 0.111252)
		(layer "B.Cu")
		(net "SAS2X28_B_HDD5_FLT")
	)
	(segment
		(start 88.518746 -447.5607)
		(end 76.19873 -459.880716)
		(width 0.111252)
		(layer "B.Cu")
		(net "SAS2X28_B_HDD5_FLT")
	)
	(segment
		(start 73.659746 -494.475008)
		(end 73.659746 -462.4197)
		(width 0.111252)
		(layer "B.Cu")
		(net "SAS2X28_B_HDD5_FLT")
	)
	(segment
		(start 73.332086 -494.802668)
		(end 73.659746 -494.475008)
		(width 0.111252)
		(layer "B.Cu")
		(net "SAS2X28_B_HDD5_FLT")
	)
	(segment
		(start 88.26754 -101.375464)
		(end 93.513148 -106.621072)
		(width 0.14605)
		(layer "In5.Cu")
		(net "SAS2X28_B_HDD5_FLT")
	)
	(segment
		(start 20.910042 -101.375464)
		(end 88.26754 -101.375464)
		(width 0.14605)
		(layer "In5.Cu")
		(net "SAS2X28_B_HDD5_FLT")
	)
	(segment
		(start 12.499848 -129.025904)
		(end 12.499848 -109.785658)
		(width 0.14605)
		(layer "In5.Cu")
		(net "SAS2X28_B_HDD5_FLT")
	)
	(segment
		(start 10.947146 -141.1859)
		(end 10.947146 -140.356336)
		(width 0.14605)
		(layer "In5.Cu")
		(net "SAS2X28_B_HDD5_FLT")
	)
	(segment
		(start 12.938252 -133.832092)
		(end 12.938252 -129.464308)
		(width 0.14605)
		(layer "In5.Cu")
		(net "SAS2X28_B_HDD5_FLT")
	)
	(segment
		(start 12.499848 -109.785658)
		(end 20.910042 -101.375464)
		(width 0.14605)
		(layer "In5.Cu")
		(net "SAS2X28_B_HDD5_FLT")
	)
	(segment
		(start 93.513148 -106.621072)
		(end 93.513148 -442.566298)
		(width 0.14605)
		(layer "In5.Cu")
		(net "SAS2X28_B_HDD5_FLT")
	)
	(segment
		(start 93.513148 -442.566298)
		(end 88.518746 -447.5607)
		(width 0.14605)
		(layer "In5.Cu")
		(net "SAS2X28_B_HDD5_FLT")
	)
	(segment
		(start 11.589004 -139.714478)
		(end 11.589004 -135.18134)
		(width 0.14605)
		(layer "In5.Cu")
		(net "SAS2X28_B_HDD5_FLT")
	)
	(segment
		(start 12.938252 -129.464308)
		(end 12.499848 -129.025904)
		(width 0.14605)
		(layer "In5.Cu")
		(net "SAS2X28_B_HDD5_FLT")
	)
	(segment
		(start 11.589004 -135.18134)
		(end 12.938252 -133.832092)
		(width 0.14605)
		(layer "In5.Cu")
		(net "SAS2X28_B_HDD5_FLT")
	)
	(segment
		(start 10.947146 -140.356336)
		(end 11.589004 -139.714478)
		(width 0.14605)
		(layer "In5.Cu")
		(net "SAS2X28_B_HDD5_FLT")
	)
	(segment
		(start 22.362414 -471.597482)
		(end 15.961614 -471.597482)
		(width 0.09525)
		(layer "F.Cu")
		(net "SAS2X28_A_HDD5_TX_-")
	)
	(segment
		(start 38.250114 -466.34019)
		(end 37.173916 -466.34019)
		(width 0.09525)
		(layer "F.Cu")
		(net "SAS2X28_A_HDD5_TX_-")
	)
	(segment
		(start 4.715764 -420.500302)
		(end 4.71424 -420.498778)
		(width 0.09525)
		(layer "F.Cu")
		(net "SAS2X28_A_HDD5_TX_-")
	)
	(segment
		(start 36.7538 -466.1662)
		(end 36.688014 -466.100668)
		(width 0.09525)
		(layer "F.Cu")
		(net "SAS2X28_A_HDD5_TX_-")
	)
	(segment
		(start 4.71424 -420.498778)
		(end 3.192526 -420.498778)
		(width 0.09525)
		(layer "F.Cu")
		(net "SAS2X28_A_HDD5_TX_-")
	)
	(segment
		(start 14.888464 -471.152728)
		(end 14.88821 -471.152728)
		(width 0.09525)
		(layer "F.Cu")
		(net "SAS2X28_A_HDD5_TX_-")
	)
	(segment
		(start 12.967462 -423.797984)
		(end 9.51611 -420.346632)
		(width 0.09525)
		(layer "F.Cu")
		(net "SAS2X28_A_HDD5_TX_-")
	)
	(segment
		(start 28.58389 -466.492844)
		(end 24.268938 -470.807796)
		(width 0.09525)
		(layer "F.Cu")
		(net "SAS2X28_A_HDD5_TX_-")
	)
	(segment
		(start 5.221224 -420.291006)
		(end 5.22097 -420.291006)
		(width 0.09525)
		(layer "F.Cu")
		(net "SAS2X28_A_HDD5_TX_-")
	)
	(segment
		(start 36.6522 -466.0138)
		(end 36.6522 -465.993988)
		(width 0.09525)
		(layer "F.Cu")
		(net "SAS2X28_A_HDD5_TX_-")
	)
	(segment
		(start 14.88821 -471.152728)
		(end 14.25321 -470.517728)
		(width 0.09525)
		(layer "F.Cu")
		(net "SAS2X28_A_HDD5_TX_-")
	)
	(segment
		(start 13.601446 -468.944198)
		(end 13.601446 -425.328588)
		(width 0.09525)
		(layer "F.Cu")
		(net "SAS2X28_A_HDD5_TX_-")
	)
	(segment
		(start 36.5252 -465.866988)
		(end 30.094936 -465.866988)
		(width 0.09525)
		(layer "F.Cu")
		(net "SAS2X28_A_HDD5_TX_-")
	)
	(segment
		(start 9.067038 -420.160704)
		(end 5.535422 -420.160704)
		(width 0.09525)
		(layer "F.Cu")
		(net "SAS2X28_A_HDD5_TX_-")
	)
	(arc
		(start 36.6522 -465.993988)
		(mid 36.615003 -465.904185)
		(end 36.5252 -465.866988)
		(width 0.09525)
		(layer "F.Cu")
		(net "SAS2X28_A_HDD5_TX_-")
	)
	(arc
		(start 36.688014 -466.100668)
		(mid 36.661467 -466.060798)
		(end 36.6522 -466.0138)
		(width 0.09525)
		(layer "F.Cu")
		(net "SAS2X28_A_HDD5_TX_-")
	)
	(arc
		(start 30.094936 -465.866988)
		(mid 29.277179 -466.02965)
		(end 28.58389 -466.492844)
		(width 0.09525)
		(layer "F.Cu")
		(net "SAS2X28_A_HDD5_TX_-")
	)
	(arc
		(start 5.22097 -420.291006)
		(mid 4.98918 -420.445883)
		(end 4.715764 -420.500302)
		(width 0.09525)
		(layer "F.Cu")
		(net "SAS2X28_A_HDD5_TX_-")
	)
	(arc
		(start 5.535422 -420.160704)
		(mid 5.365373 -420.194622)
		(end 5.221224 -420.291006)
		(width 0.09525)
		(layer "F.Cu")
		(net "SAS2X28_A_HDD5_TX_-")
	)
	(arc
		(start 37.173916 -466.34019)
		(mid 36.946561 -466.294966)
		(end 36.7538 -466.1662)
		(width 0.09525)
		(layer "F.Cu")
		(net "SAS2X28_A_HDD5_TX_-")
	)
	(arc
		(start 15.961614 -471.597482)
		(mid 15.38083 -471.481788)
		(end 14.888464 -471.152728)
		(width 0.09525)
		(layer "F.Cu")
		(net "SAS2X28_A_HDD5_TX_-")
	)
	(arc
		(start 9.51611 -420.346632)
		(mid 9.31006 -420.209017)
		(end 9.067038 -420.160704)
		(width 0.09525)
		(layer "F.Cu")
		(net "SAS2X28_A_HDD5_TX_-")
	)
	(arc
		(start 24.268938 -470.807796)
		(mid 23.394204 -471.392241)
		(end 22.362414 -471.597482)
		(width 0.09525)
		(layer "F.Cu")
		(net "SAS2X28_A_HDD5_TX_-")
	)
	(arc
		(start 14.25321 -470.517728)
		(mid 13.770848 -469.795773)
		(end 13.601446 -468.944198)
		(width 0.09525)
		(layer "F.Cu")
		(net "SAS2X28_A_HDD5_TX_-")
	)
	(arc
		(start 13.601446 -425.328588)
		(mid 13.436677 -424.500236)
		(end 12.967462 -423.797984)
		(width 0.09525)
		(layer "F.Cu")
		(net "SAS2X28_A_HDD5_TX_-")
	)
	(segment
		(start 7.340346 -409.754324)
		(end 7.340346 -409.835096)
		(width 0.09525)
		(layer "F.Cu")
		(net "SAS2X28_A_HDD1_RX_-")
	)
	(segment
		(start 216.952576 -366.241584)
		(end 210.946746 -366.241584)
		(width 0.09525)
		(layer "F.Cu")
		(net "SAS2X28_A_HDD1_RX_-")
	)
	(segment
		(start 82.422746 -408.791918)
		(end 8.314436 -408.791918)
		(width 0.09525)
		(layer "F.Cu")
		(net "SAS2X28_A_HDD1_RX_-")
	)
	(segment
		(start 202.762866 -368.796316)
		(end 83.28279 -408.66314)
		(width 0.09525)
		(layer "F.Cu")
		(net "SAS2X28_A_HDD1_RX_-")
	)
	(segment
		(start 210.002882 -366.380522)
		(end 202.762866 -368.796316)
		(width 0.09525)
		(layer "F.Cu")
		(net "SAS2X28_A_HDD1_RX_-")
	)
	(via
		(at 7.340346 -409.835096)
		(size 0.5588)
		(drill 0.3048)
		(layers "F.Cu" "B.Cu")
		(net "SAS2X28_A_HDD1_RX_-")
	)
	(arc
		(start 83.28279 -408.66314)
		(mid 82.913883 -408.750521)
		(end 82.536792 -408.789632)
		(width 0.09525)
		(layer "F.Cu")
		(net "SAS2X28_A_HDD1_RX_-")
	)
	(arc
		(start 217.697558 -365.962184)
		(mid 217.350405 -366.169447)
		(end 216.952576 -366.241584)
		(width 0.09525)
		(layer "F.Cu")
		(net "SAS2X28_A_HDD1_RX_-")
	)
	(arc
		(start 82.536792 -408.789632)
		(mid 82.47978 -408.791328)
		(end 82.422746 -408.791918)
		(width 0.09525)
		(layer "F.Cu")
		(net "SAS2X28_A_HDD1_RX_-")
	)
	(arc
		(start 8.314436 -408.791918)
		(mid 7.93846 -408.866704)
		(end 7.619746 -409.0797)
		(width 0.09525)
		(layer "F.Cu")
		(net "SAS2X28_A_HDD1_RX_-")
	)
	(arc
		(start 210.946746 -366.241584)
		(mid 210.469728 -366.276504)
		(end 210.002882 -366.380522)
		(width 0.09525)
		(layer "F.Cu")
		(net "SAS2X28_A_HDD1_RX_-")
	)
	(arc
		(start 7.619746 -409.0797)
		(mid 7.412931 -409.38922)
		(end 7.340346 -409.754324)
		(width 0.09525)
		(layer "F.Cu")
		(net "SAS2X28_A_HDD1_RX_-")
	)
	(segment
		(start 4.570476 -406.50033)
		(end 4.568952 -406.498806)
		(width 0.09525)
		(layer "B.Cu")
		(net "SAS2X28_A_HDD1_RX_-")
	)
	(segment
		(start 7.340346 -409.835096)
		(end 7.497572 -409.678124)
		(width 0.09525)
		(layer "B.Cu")
		(net "SAS2X28_A_HDD1_RX_-")
	)
	(segment
		(start 4.568952 -406.498806)
		(end 2.811526 -406.498806)
		(width 0.09525)
		(layer "B.Cu")
		(net "SAS2X28_A_HDD1_RX_-")
	)
	(segment
		(start 7.640066 -409.3337)
		(end 7.640066 -407.4033)
		(width 0.09525)
		(layer "B.Cu")
		(net "SAS2X28_A_HDD1_RX_-")
	)
	(segment
		(start 7.492746 -407.0477)
		(end 7.055866 -406.61082)
		(width 0.09525)
		(layer "B.Cu")
		(net "SAS2X28_A_HDD1_RX_-")
	)
	(segment
		(start 5.24637 -406.220422)
		(end 5.246116 -406.220422)
		(width 0.09525)
		(layer "B.Cu")
		(net "SAS2X28_A_HDD1_RX_-")
	)
	(segment
		(start 5.841746 -406.1079)
		(end 5.517642 -406.1079)
		(width 0.09525)
		(layer "B.Cu")
		(net "SAS2X28_A_HDD1_RX_-")
	)
	(arc
		(start 7.497572 -409.678124)
		(mid 7.603077 -409.520086)
		(end 7.640066 -409.3337)
		(width 0.09525)
		(layer "B.Cu")
		(net "SAS2X28_A_HDD1_RX_-")
	)
	(arc
		(start 7.055866 -406.61082)
		(mid 6.498823 -406.238616)
		(end 5.841746 -406.1079)
		(width 0.09525)
		(layer "B.Cu")
		(net "SAS2X28_A_HDD1_RX_-")
	)
	(arc
		(start 5.246116 -406.220422)
		(mid 4.93613 -406.427548)
		(end 4.570476 -406.50033)
		(width 0.09525)
		(layer "B.Cu")
		(net "SAS2X28_A_HDD1_RX_-")
	)
	(arc
		(start 7.640066 -407.4033)
		(mid 7.601783 -407.210841)
		(end 7.492746 -407.0477)
		(width 0.09525)
		(layer "B.Cu")
		(net "SAS2X28_A_HDD1_RX_-")
	)
	(arc
		(start 5.517642 -406.1079)
		(mid 5.370824 -406.137198)
		(end 5.24637 -406.220422)
		(width 0.09525)
		(layer "B.Cu")
		(net "SAS2X28_A_HDD1_RX_-")
	)
	(segment
		(start 246.6848 -423.037)
		(end 247.777 -423.037)
		(width 0.111252)
		(layer "F.Cu")
		(net "I2C_C_SCL")
	)
	(segment
		(start 247.777 -423.037)
		(end 248.412 -423.672)
		(width 0.111252)
		(layer "F.Cu")
		(net "I2C_C_SCL")
	)
	(segment
		(start 13.062204 -156.69006)
		(end 10.848086 -158.904178)
		(width 0.111252)
		(layer "F.Cu")
		(net "I2C_C_SCL")
	)
	(segment
		(start 13.062204 -152.355804)
		(end 13.062204 -156.69006)
		(width 0.111252)
		(layer "F.Cu")
		(net "I2C_C_SCL")
	)
	(segment
		(start 19.05 -397.5481)
		(end 19.05 -396.6972)
		(width 0.111252)
		(layer "F.Cu")
		(net "I2C_C_SCL")
	)
	(segment
		(start 11.4046 -150.6982)
		(end 13.062204 -152.355804)
		(width 0.111252)
		(layer "F.Cu")
		(net "I2C_C_SCL")
	)
	(segment
		(start 9.0297 -150.6982)
		(end 11.4046 -150.6982)
		(width 0.111252)
		(layer "F.Cu")
		(net "I2C_C_SCL")
	)
	(via
		(at 248.412 -423.672)
		(size 0.5588)
		(drill 0.3048)
		(layers "F.Cu" "B.Cu")
		(net "I2C_C_SCL")
	)
	(via
		(at 19.05 -396.6972)
		(size 0.5588)
		(drill 0.3048)
		(layers "F.Cu" "B.Cu")
		(net "I2C_C_SCL")
	)
	(via
		(at 18.9484 -395.605)
		(size 0.7112)
		(drill 0.3556)
		(layers "F.Cu" "B.Cu")
		(net "I2C_C_SCL")
	)
	(via
		(at 10.848086 -158.904178)
		(size 0.5588)
		(drill 0.3048)
		(layers "F.Cu" "B.Cu")
		(net "I2C_C_SCL")
	)
	(segment
		(start 19.05 -395.7066)
		(end 18.9484 -395.605)
		(width 0.111252)
		(layer "B.Cu")
		(net "I2C_C_SCL")
	)
	(segment
		(start 248.412 -423.6974)
		(end 249.174508 -424.459908)
		(width 0.111252)
		(layer "B.Cu")
		(net "I2C_C_SCL")
	)
	(segment
		(start 249.174508 -424.459908)
		(end 255.093978 -424.459908)
		(width 0.111252)
		(layer "B.Cu")
		(net "I2C_C_SCL")
	)
	(segment
		(start 19.05 -396.6972)
		(end 19.05 -395.7066)
		(width 0.111252)
		(layer "B.Cu")
		(net "I2C_C_SCL")
	)
	(segment
		(start 248.412 -423.672)
		(end 248.412 -423.6974)
		(width 0.111252)
		(layer "B.Cu")
		(net "I2C_C_SCL")
	)
	(segment
		(start 245.798848 -416.326828)
		(end 247.4214 -417.94938)
		(width 0.14605)
		(layer "In2.Cu")
		(net "I2C_C_SCL")
	)
	(segment
		(start 242.93449 -411.765496)
		(end 245.798848 -414.629854)
		(width 0.14605)
		(layer "In2.Cu")
		(net "I2C_C_SCL")
	)
	(segment
		(start 19.05 -396.6972)
		(end 19.05 -399.172938)
		(width 0.14605)
		(layer "In2.Cu")
		(net "I2C_C_SCL")
	)
	(segment
		(start 247.4214 -417.94938)
		(end 247.4214 -422.6814)
		(width 0.14605)
		(layer "In2.Cu")
		(net "I2C_C_SCL")
	)
	(segment
		(start 25.97785 -403.67585)
		(end 84.575396 -403.67585)
		(width 0.14605)
		(layer "In2.Cu")
		(net "I2C_C_SCL")
	)
	(segment
		(start 19.05 -399.172938)
		(end 20.282662 -400.4056)
		(width 0.14605)
		(layer "In2.Cu")
		(net "I2C_C_SCL")
	)
	(segment
		(start 242.934236 -411.765496)
		(end 242.93449 -411.765496)
		(width 0.14605)
		(layer "In2.Cu")
		(net "I2C_C_SCL")
	)
	(segment
		(start 247.4214 -422.6814)
		(end 248.412 -423.672)
		(width 0.14605)
		(layer "In2.Cu")
		(net "I2C_C_SCL")
	)
	(segment
		(start 236.102906 -404.93315)
		(end 242.934236 -411.765496)
		(width 0.14605)
		(layer "In2.Cu")
		(net "I2C_C_SCL")
	)
	(segment
		(start 85.832696 -404.93315)
		(end 236.102906 -404.93315)
		(width 0.14605)
		(layer "In2.Cu")
		(net "I2C_C_SCL")
	)
	(segment
		(start 20.282662 -400.4056)
		(end 22.7076 -400.4056)
		(width 0.14605)
		(layer "In2.Cu")
		(net "I2C_C_SCL")
	)
	(segment
		(start 84.575396 -403.67585)
		(end 85.832696 -404.93315)
		(width 0.14605)
		(layer "In2.Cu")
		(net "I2C_C_SCL")
	)
	(segment
		(start 245.798848 -414.629854)
		(end 245.798848 -416.326828)
		(width 0.14605)
		(layer "In2.Cu")
		(net "I2C_C_SCL")
	)
	(segment
		(start 22.7076 -400.4056)
		(end 25.97785 -403.67585)
		(width 0.14605)
		(layer "In2.Cu")
		(net "I2C_C_SCL")
	)
	(segment
		(start 8.035798 -203.02093)
		(end 8.510016 -203.495148)
		(width 0.14605)
		(layer "In5.Cu")
		(net "I2C_C_SCL")
	)
	(segment
		(start 8.810752 -203.795884)
		(end 10.825734 -205.810866)
		(width 0.14605)
		(layer "In5.Cu")
		(net "I2C_C_SCL")
	)
	(segment
		(start 10.848086 -158.904178)
		(end 10.718292 -158.774384)
		(width 0.14605)
		(layer "In5.Cu")
		(net "I2C_C_SCL")
	)
	(segment
		(start 8.035798 -178.546506)
		(end 8.035798 -203.02093)
		(width 0.14605)
		(layer "In5.Cu")
		(net "I2C_C_SCL")
	)
	(segment
		(start 10.825734 -205.810866)
		(end 10.825734 -215.08593)
		(width 0.14605)
		(layer "In5.Cu")
		(net "I2C_C_SCL")
	)
	(segment
		(start 13.093446 -388.097522)
		(end 19.05 -394.054076)
		(width 0.14605)
		(layer "In5.Cu")
		(net "I2C_C_SCL")
	)
	(segment
		(start 8.804148 -163.617148)
		(end 8.804148 -177.778156)
		(width 0.14605)
		(layer "In5.Cu")
		(net "I2C_C_SCL")
	)
	(segment
		(start 8.529828 -203.495148)
		(end 8.810752 -203.776072)
		(width 0.14605)
		(layer "In5.Cu")
		(net "I2C_C_SCL")
	)
	(segment
		(start 8.797798 -163.610798)
		(end 8.804148 -163.617148)
		(width 0.14605)
		(layer "In5.Cu")
		(net "I2C_C_SCL")
	)
	(segment
		(start 8.510016 -203.495148)
		(end 8.529828 -203.495148)
		(width 0.14605)
		(layer "In5.Cu")
		(net "I2C_C_SCL")
	)
	(segment
		(start 10.718292 -158.774384)
		(end 9.859772 -158.774384)
		(width 0.14605)
		(layer "In5.Cu")
		(net "I2C_C_SCL")
	)
	(segment
		(start 10.825734 -215.08593)
		(end 13.093446 -217.353642)
		(width 0.14605)
		(layer "In5.Cu")
		(net "I2C_C_SCL")
	)
	(segment
		(start 19.05 -394.054076)
		(end 19.05 -396.6972)
		(width 0.14605)
		(layer "In5.Cu")
		(net "I2C_C_SCL")
	)
	(segment
		(start 8.804148 -177.778156)
		(end 8.035798 -178.546506)
		(width 0.14605)
		(layer "In5.Cu")
		(net "I2C_C_SCL")
	)
	(segment
		(start 8.810752 -203.776072)
		(end 8.810752 -203.795884)
		(width 0.14605)
		(layer "In5.Cu")
		(net "I2C_C_SCL")
	)
	(segment
		(start 8.797798 -159.836358)
		(end 8.797798 -163.610798)
		(width 0.14605)
		(layer "In5.Cu")
		(net "I2C_C_SCL")
	)
	(segment
		(start 9.859772 -158.774384)
		(end 8.797798 -159.836358)
		(width 0.14605)
		(layer "In5.Cu")
		(net "I2C_C_SCL")
	)
	(segment
		(start 13.093446 -217.353642)
		(end 13.093446 -388.097522)
		(width 0.14605)
		(layer "In5.Cu")
		(net "I2C_C_SCL")
	)
	(segment
		(start 20.446746 -458.787754)
		(end 20.446746 -458.7875)
		(width 0.09525)
		(layer "F.Cu")
		(net "SAS2X28_A_HDD10_RX_-")
	)
	(segment
		(start 28.600146 -449.373244)
		(end 28.600146 -451.059804)
		(width 0.09525)
		(layer "F.Cu")
		(net "SAS2X28_A_HDD10_RX_-")
	)
	(segment
		(start 7.650988 -413.874458)
		(end 7.492746 -414.0327)
		(width 0.09525)
		(layer "F.Cu")
		(net "SAS2X28_A_HDD10_RX_-")
	)
	(segment
		(start 8.12419 -412.912052)
		(end 8.071104 -412.964884)
		(width 0.09525)
		(layer "F.Cu")
		(net "SAS2X28_A_HDD10_RX_-")
	)
	(segment
		(start 8.673846 -412.81604)
		(end 8.355584 -412.81604)
		(width 0.09525)
		(layer "F.Cu")
		(net "SAS2X28_A_HDD10_RX_-")
	)
	(segment
		(start 28.354274 -448.864228)
		(end 28.414218 -448.924172)
		(width 0.09525)
		(layer "F.Cu")
		(net "SAS2X28_A_HDD10_RX_-")
	)
	(segment
		(start 28.414218 -451.508876)
		(end 21.622258 -458.300836)
		(width 0.09525)
		(layer "F.Cu")
		(net "SAS2X28_A_HDD10_RX_-")
	)
	(segment
		(start 20.446746 -458.7875)
		(end 19.303746 -458.7875)
		(width 0.09525)
		(layer "F.Cu")
		(net "SAS2X28_A_HDD10_RX_-")
	)
	(segment
		(start 18.089626 -458.28458)
		(end 17.48155 -457.676504)
		(width 0.09525)
		(layer "F.Cu")
		(net "SAS2X28_A_HDD10_RX_-")
	)
	(segment
		(start 16.751046 -455.912982)
		(end 16.751046 -421.641016)
		(width 0.09525)
		(layer "F.Cu")
		(net "SAS2X28_A_HDD10_RX_-")
	)
	(segment
		(start 15.959836 -419.730936)
		(end 9.307322 -413.078422)
		(width 0.09525)
		(layer "F.Cu")
		(net "SAS2X28_A_HDD10_RX_-")
	)
	(via
		(at 7.492746 -414.0327)
		(size 0.5588)
		(drill 0.3048)
		(layers "F.Cu" "B.Cu")
		(net "SAS2X28_A_HDD10_RX_-")
	)
	(arc
		(start 19.303746 -458.7875)
		(mid 18.646663 -458.656798)
		(end 18.089626 -458.28458)
		(width 0.09525)
		(layer "F.Cu")
		(net "SAS2X28_A_HDD10_RX_-")
	)
	(arc
		(start 9.307322 -413.078422)
		(mid 9.016681 -412.884222)
		(end 8.673846 -412.81604)
		(width 0.09525)
		(layer "F.Cu")
		(net "SAS2X28_A_HDD10_RX_-")
	)
	(arc
		(start 28.600146 -451.059804)
		(mid 28.551825 -451.302822)
		(end 28.414218 -451.508876)
		(width 0.09525)
		(layer "F.Cu")
		(net "SAS2X28_A_HDD10_RX_-")
	)
	(arc
		(start 27.241246 -448.9577)
		(mid 27.447276 -448.799291)
		(end 27.689048 -448.703954)
		(width 0.09525)
		(layer "F.Cu")
		(net "SAS2X28_A_HDD10_RX_-")
	)
	(arc
		(start 21.622258 -458.300836)
		(mid 21.082929 -458.661204)
		(end 20.446746 -458.787754)
		(width 0.09525)
		(layer "F.Cu")
		(net "SAS2X28_A_HDD10_RX_-")
	)
	(arc
		(start 27.689048 -448.703954)
		(mid 27.796371 -448.684773)
		(end 27.905202 -448.6783)
		(width 0.09525)
		(layer "F.Cu")
		(net "SAS2X28_A_HDD10_RX_-")
	)
	(arc
		(start 17.48155 -457.676504)
		(mid 16.940919 -456.867393)
		(end 16.751046 -455.912982)
		(width 0.09525)
		(layer "F.Cu")
		(net "SAS2X28_A_HDD10_RX_-")
	)
	(arc
		(start 8.071104 -412.964884)
		(mid 7.927177 -413.162025)
		(end 7.850124 -413.393636)
		(width 0.09525)
		(layer "F.Cu")
		(net "SAS2X28_A_HDD10_RX_-")
	)
	(arc
		(start 27.905202 -448.6783)
		(mid 28.14822 -448.726621)
		(end 28.354274 -448.864228)
		(width 0.09525)
		(layer "F.Cu")
		(net "SAS2X28_A_HDD10_RX_-")
	)
	(arc
		(start 7.850124 -413.393636)
		(mid 7.798365 -413.653845)
		(end 7.650988 -413.874458)
		(width 0.09525)
		(layer "F.Cu")
		(net "SAS2X28_A_HDD10_RX_-")
	)
	(arc
		(start 16.751046 -421.641016)
		(mid 16.545423 -420.607277)
		(end 15.959836 -419.730936)
		(width 0.09525)
		(layer "F.Cu")
		(net "SAS2X28_A_HDD10_RX_-")
	)
	(arc
		(start 8.355584 -412.81604)
		(mid 8.230345 -412.841045)
		(end 8.12419 -412.912052)
		(width 0.09525)
		(layer "F.Cu")
		(net "SAS2X28_A_HDD10_RX_-")
	)
	(arc
		(start 28.414218 -448.924172)
		(mid 28.551833 -449.130222)
		(end 28.600146 -449.373244)
		(width 0.09525)
		(layer "F.Cu")
		(net "SAS2X28_A_HDD10_RX_-")
	)
	(segment
		(start 7.670546 -413.60344)
		(end 7.670546 -412.078424)
		(width 0.09525)
		(layer "B.Cu")
		(net "SAS2X28_A_HDD10_RX_-")
	)
	(segment
		(start 6.06552 -410.160724)
		(end 5.523738 -410.160724)
		(width 0.09525)
		(layer "B.Cu")
		(net "SAS2X28_A_HDD10_RX_-")
	)
	(segment
		(start 4.703826 -410.500322)
		(end 4.702302 -410.498798)
		(width 0.09525)
		(layer "B.Cu")
		(net "SAS2X28_A_HDD10_RX_-")
	)
	(segment
		(start 7.263384 -411.095444)
		(end 6.514592 -410.346652)
		(width 0.09525)
		(layer "B.Cu")
		(net "SAS2X28_A_HDD10_RX_-")
	)
	(segment
		(start 4.702302 -410.498798)
		(end 2.811526 -410.498798)
		(width 0.09525)
		(layer "B.Cu")
		(net "SAS2X28_A_HDD10_RX_-")
	)
	(arc
		(start 7.492746 -414.0327)
		(mid 7.624341 -413.835754)
		(end 7.670546 -413.60344)
		(width 0.09525)
		(layer "B.Cu")
		(net "SAS2X28_A_HDD10_RX_-")
	)
	(arc
		(start 5.523738 -410.160724)
		(mid 5.36841 -410.191621)
		(end 5.236718 -410.279596)
		(width 0.09525)
		(layer "B.Cu")
		(net "SAS2X28_A_HDD10_RX_-")
	)
	(arc
		(start 6.085332 -410.160978)
		(mid 6.075427 -410.160774)
		(end 6.06552 -410.160724)
		(width 0.09525)
		(layer "B.Cu")
		(net "SAS2X28_A_HDD10_RX_-")
	)
	(arc
		(start 6.514592 -410.346652)
		(mid 6.317665 -410.212898)
		(end 6.085332 -410.160978)
		(width 0.09525)
		(layer "B.Cu")
		(net "SAS2X28_A_HDD10_RX_-")
	)
	(arc
		(start 7.670546 -412.078424)
		(mid 7.564728 -411.54644)
		(end 7.263384 -411.095444)
		(width 0.09525)
		(layer "B.Cu")
		(net "SAS2X28_A_HDD10_RX_-")
	)
	(arc
		(start 5.236718 -410.279596)
		(mid 4.992225 -410.442961)
		(end 4.703826 -410.500322)
		(width 0.09525)
		(layer "B.Cu")
		(net "SAS2X28_A_HDD10_RX_-")
	)
	(segment
		(start 22.36216 -471.267282)
		(end 15.961868 -471.267282)
		(width 0.09525)
		(layer "F.Cu")
		(net "SAS2X28_A_HDD5_TX_+")
	)
	(segment
		(start 4.713732 -419.49878)
		(end 3.192526 -419.49878)
		(width 0.09525)
		(layer "F.Cu")
		(net "SAS2X28_A_HDD5_TX_+")
	)
	(segment
		(start 36.550346 -465.536788)
		(end 30.09519 -465.536788)
		(width 0.09525)
		(layer "F.Cu")
		(net "SAS2X28_A_HDD5_TX_+")
	)
	(segment
		(start 9.03605 -419.830504)
		(end 5.512562 -419.830504)
		(width 0.09525)
		(layer "F.Cu")
		(net "SAS2X28_A_HDD5_TX_+")
	)
	(segment
		(start 13.931646 -468.943944)
		(end 13.931646 -425.328588)
		(width 0.09525)
		(layer "F.Cu")
		(net "SAS2X28_A_HDD5_TX_+")
	)
	(segment
		(start 4.715256 -419.500304)
		(end 4.713732 -419.49878)
		(width 0.09525)
		(layer "F.Cu")
		(net "SAS2X28_A_HDD5_TX_+")
	)
	(segment
		(start 15.12189 -470.919302)
		(end 14.48689 -470.284302)
		(width 0.09525)
		(layer "F.Cu")
		(net "SAS2X28_A_HDD5_TX_+")
	)
	(segment
		(start 38.250114 -465.07019)
		(end 37.096192 -465.07019)
		(width 0.09525)
		(layer "F.Cu")
		(net "SAS2X28_A_HDD5_TX_+")
	)
	(segment
		(start 28.35021 -466.259164)
		(end 24.035512 -470.574116)
		(width 0.09525)
		(layer "F.Cu")
		(net "SAS2X28_A_HDD5_TX_+")
	)
	(segment
		(start 28.350464 -466.259418)
		(end 28.35021 -466.259164)
		(width 0.09525)
		(layer "F.Cu")
		(net "SAS2X28_A_HDD5_TX_+")
	)
	(segment
		(start 13.200888 -423.564304)
		(end 9.771888 -420.135304)
		(width 0.09525)
		(layer "F.Cu")
		(net "SAS2X28_A_HDD5_TX_+")
	)
	(arc
		(start 5.512562 -419.830504)
		(mid 5.366176 -419.801386)
		(end 5.242052 -419.71849)
		(width 0.09525)
		(layer "F.Cu")
		(net "SAS2X28_A_HDD5_TX_+")
	)
	(arc
		(start 37.096192 -465.07019)
		(mid 36.924228 -465.104378)
		(end 36.778438 -465.201762)
		(width 0.09525)
		(layer "F.Cu")
		(net "SAS2X28_A_HDD5_TX_+")
	)
	(arc
		(start 5.242052 -419.71849)
		(mid 5.000356 -419.556994)
		(end 4.715256 -419.500304)
		(width 0.09525)
		(layer "F.Cu")
		(net "SAS2X28_A_HDD5_TX_+")
	)
	(arc
		(start 36.599114 -465.528406)
		(mid 36.575088 -465.534678)
		(end 36.550346 -465.536788)
		(width 0.09525)
		(layer "F.Cu")
		(net "SAS2X28_A_HDD5_TX_+")
	)
	(arc
		(start 9.771888 -420.135304)
		(mid 9.434283 -419.909723)
		(end 9.03605 -419.830504)
		(width 0.09525)
		(layer "F.Cu")
		(net "SAS2X28_A_HDD5_TX_+")
	)
	(arc
		(start 36.702746 -465.384388)
		(mid 36.674146 -465.473103)
		(end 36.599114 -465.528406)
		(width 0.09525)
		(layer "F.Cu")
		(net "SAS2X28_A_HDD5_TX_+")
	)
	(arc
		(start 24.035512 -470.574116)
		(mid 23.267772 -471.087104)
		(end 22.36216 -471.267282)
		(width 0.09525)
		(layer "F.Cu")
		(net "SAS2X28_A_HDD5_TX_+")
	)
	(arc
		(start 36.778438 -465.201762)
		(mid 36.722398 -465.285537)
		(end 36.702746 -465.384388)
		(width 0.09525)
		(layer "F.Cu")
		(net "SAS2X28_A_HDD5_TX_+")
	)
	(arc
		(start 14.48689 -470.284302)
		(mid 14.075986 -469.669341)
		(end 13.931646 -468.943944)
		(width 0.09525)
		(layer "F.Cu")
		(net "SAS2X28_A_HDD5_TX_+")
	)
	(arc
		(start 13.931646 -425.328588)
		(mid 13.741722 -424.373777)
		(end 13.200888 -423.564304)
		(width 0.09525)
		(layer "F.Cu")
		(net "SAS2X28_A_HDD5_TX_+")
	)
	(arc
		(start 30.09519 -465.536788)
		(mid 29.150934 -465.724536)
		(end 28.350464 -466.259418)
		(width 0.09525)
		(layer "F.Cu")
		(net "SAS2X28_A_HDD5_TX_+")
	)
	(arc
		(start 15.961868 -471.267282)
		(mid 15.507256 -471.176854)
		(end 15.12189 -470.919302)
		(width 0.09525)
		(layer "F.Cu")
		(net "SAS2X28_A_HDD5_TX_+")
	)
	(segment
		(start 10.5156 -155.1686)
		(end 10.5156 -155.321)
		(width 0.111252)
		(layer "F.Cu")
		(net "I2C_D_SDA")
	)
	(segment
		(start 22.186646 -255.1303)
		(end 23.3426 -253.974346)
		(width 0.111252)
		(layer "F.Cu")
		(net "I2C_D_SDA")
	)
	(segment
		(start 21.082 -392.591798)
		(end 21.318728 -392.35507)
		(width 0.111252)
		(layer "F.Cu")
		(net "I2C_D_SDA")
	)
	(segment
		(start 9.8679 -154.5209)
		(end 10.5156 -155.1686)
		(width 0.111252)
		(layer "F.Cu")
		(net "I2C_D_SDA")
	)
	(segment
		(start 23.4315 -253.0094)
		(end 23.5204 -253.0094)
		(width 0.111252)
		(layer "F.Cu")
		(net "I2C_D_SDA")
	)
	(segment
		(start 21.082 -393.2555)
		(end 21.082 -392.591798)
		(width 0.111252)
		(layer "F.Cu")
		(net "I2C_D_SDA")
	)
	(segment
		(start 23.3426 -253.974346)
		(end 23.3426 -253.0983)
		(width 0.111252)
		(layer "F.Cu")
		(net "I2C_D_SDA")
	)
	(segment
		(start 9.8679 -154.260804)
		(end 9.8679 -154.5209)
		(width 0.111252)
		(layer "F.Cu")
		(net "I2C_D_SDA")
	)
	(segment
		(start 23.3426 -253.0983)
		(end 23.4315 -253.0094)
		(width 0.111252)
		(layer "F.Cu")
		(net "I2C_D_SDA")
	)
	(via
		(at 10.5156 -155.321)
		(size 0.5588)
		(drill 0.3048)
		(layers "F.Cu" "B.Cu")
		(net "I2C_D_SDA")
	)
	(via
		(at 21.318728 -392.35507)
		(size 0.5588)
		(drill 0.3048)
		(layers "F.Cu" "B.Cu")
		(net "I2C_D_SDA")
	)
	(via
		(at 23.749 -254.0762)
		(size 0.7112)
		(drill 0.3556)
		(layers "F.Cu" "B.Cu")
		(net "I2C_D_SDA")
	)
	(via
		(at 19.177 -215.3158)
		(size 0.5588)
		(drill 0.3048)
		(layers "F.Cu" "B.Cu")
		(net "I2C_D_SDA")
	)
	(via
		(at 23.5204 -253.0094)
		(size 0.5588)
		(drill 0.3048)
		(layers "F.Cu" "B.Cu")
		(net "I2C_D_SDA")
	)
	(segment
		(start 23.5204 -253.0094)
		(end 23.749 -253.238)
		(width 0.111252)
		(layer "B.Cu")
		(net "I2C_D_SDA")
	)
	(segment
		(start 23.749 -253.238)
		(end 23.749 -254.0762)
		(width 0.111252)
		(layer "B.Cu")
		(net "I2C_D_SDA")
	)
	(segment
		(start 24.3967 -340.3473)
		(end 23.524972 -339.475572)
		(width 0.14605)
		(layer "In2.Cu")
		(net "I2C_D_SDA")
	)
	(segment
		(start 21.318728 -379.693424)
		(end 21.318728 -361.354624)
		(width 0.14605)
		(layer "In2.Cu")
		(net "I2C_D_SDA")
	)
	(segment
		(start 23.524972 -339.475572)
		(end 23.524972 -315.864748)
		(width 0.14605)
		(layer "In2.Cu")
		(net "I2C_D_SDA")
	)
	(segment
		(start 22.3266 -167.132)
		(end 22.3266 -206.9338)
		(width 0.14605)
		(layer "In2.Cu")
		(net "I2C_D_SDA")
	)
	(segment
		(start 20.193 -215.392)
		(end 19.2532 -215.392)
		(width 0.14605)
		(layer "In2.Cu")
		(net "I2C_D_SDA")
	)
	(segment
		(start 24.3967 -346.329)
		(end 24.3967 -340.3473)
		(width 0.14605)
		(layer "In2.Cu")
		(net "I2C_D_SDA")
	)
	(segment
		(start 21.318728 -361.354624)
		(end 26.186892 -356.48646)
		(width 0.14605)
		(layer "In2.Cu")
		(net "I2C_D_SDA")
	)
	(segment
		(start 22.0218 -207.2386)
		(end 22.0218 -213.5632)
		(width 0.14605)
		(layer "In2.Cu")
		(net "I2C_D_SDA")
	)
	(segment
		(start 10.5156 -155.321)
		(end 22.3266 -167.132)
		(width 0.14605)
		(layer "In2.Cu")
		(net "I2C_D_SDA")
	)
	(segment
		(start 23.5204 -315.841888)
		(end 23.5204 -253.0094)
		(width 0.14605)
		(layer "In2.Cu")
		(net "I2C_D_SDA")
	)
	(segment
		(start 22.3266 -206.9338)
		(end 22.0218 -207.2386)
		(width 0.14605)
		(layer "In2.Cu")
		(net "I2C_D_SDA")
	)
	(segment
		(start 21.339048 -381.295656)
		(end 21.339048 -379.713744)
		(width 0.14605)
		(layer "In2.Cu")
		(net "I2C_D_SDA")
	)
	(segment
		(start 26.186892 -356.48646)
		(end 26.186892 -348.119192)
		(width 0.14605)
		(layer "In2.Cu")
		(net "I2C_D_SDA")
	)
	(segment
		(start 19.2532 -215.392)
		(end 19.177 -215.3158)
		(width 0.14605)
		(layer "In2.Cu")
		(net "I2C_D_SDA")
	)
	(segment
		(start 21.318728 -381.315976)
		(end 21.339048 -381.295656)
		(width 0.14605)
		(layer "In2.Cu")
		(net "I2C_D_SDA")
	)
	(segment
		(start 26.186892 -348.119192)
		(end 24.3967 -346.329)
		(width 0.14605)
		(layer "In2.Cu")
		(net "I2C_D_SDA")
	)
	(segment
		(start 23.524972 -315.864748)
		(end 23.5204 -315.841888)
		(width 0.14605)
		(layer "In2.Cu")
		(net "I2C_D_SDA")
	)
	(segment
		(start 21.318728 -392.35507)
		(end 21.318728 -381.315976)
		(width 0.14605)
		(layer "In2.Cu")
		(net "I2C_D_SDA")
	)
	(segment
		(start 21.339048 -379.713744)
		(end 21.318728 -379.693424)
		(width 0.14605)
		(layer "In2.Cu")
		(net "I2C_D_SDA")
	)
	(segment
		(start 22.0218 -213.5632)
		(end 20.193 -215.392)
		(width 0.14605)
		(layer "In2.Cu")
		(net "I2C_D_SDA")
	)
	(segment
		(start 22.3647 -252.43028)
		(end 22.3647 -251.780294)
		(width 0.14605)
		(layer "In5.Cu")
		(net "I2C_D_SDA")
	)
	(segment
		(start 18.163794 -216.715086)
		(end 19.177 -215.70188)
		(width 0.14605)
		(layer "In5.Cu")
		(net "I2C_D_SDA")
	)
	(segment
		(start 22.94382 -253.0094)
		(end 22.3647 -252.43028)
		(width 0.14605)
		(layer "In5.Cu")
		(net "I2C_D_SDA")
	)
	(segment
		(start 18.163794 -247.579388)
		(end 18.163794 -216.715086)
		(width 0.14605)
		(layer "In5.Cu")
		(net "I2C_D_SDA")
	)
	(segment
		(start 23.5204 -253.0094)
		(end 22.94382 -253.0094)
		(width 0.14605)
		(layer "In5.Cu")
		(net "I2C_D_SDA")
	)
	(segment
		(start 19.177 -215.70188)
		(end 19.177 -215.3158)
		(width 0.14605)
		(layer "In5.Cu")
		(net "I2C_D_SDA")
	)
	(segment
		(start 22.3647 -251.780294)
		(end 18.163794 -247.579388)
		(width 0.14605)
		(layer "In5.Cu")
		(net "I2C_D_SDA")
	)
	(segment
		(start 3.19024 -211.504784)
		(end 6.373876 -211.504784)
		(width 0.111252)
		(layer "F.Cu")
		(net "SAS_EXP_B_PWR5")
	)
	(segment
		(start 84.617814 -493.970818)
		(end 84.231988 -493.970818)
		(width 0.111252)
		(layer "F.Cu")
		(net "SAS_EXP_B_PWR5")
	)
	(segment
		(start 6.373876 -211.504784)
		(end 7.441946 -212.572854)
		(width 0.111252)
		(layer "F.Cu")
		(net "SAS_EXP_B_PWR5")
	)
	(segment
		(start 84.231988 -493.970818)
		(end 84.125816 -493.864646)
		(width 0.111252)
		(layer "F.Cu")
		(net "SAS_EXP_B_PWR5")
	)
	(segment
		(start 84.962746 -493.625886)
		(end 84.617814 -493.970818)
		(width 0.111252)
		(layer "F.Cu")
		(net "SAS_EXP_B_PWR5")
	)
	(segment
		(start 85.336634 -493.625886)
		(end 84.962746 -493.625886)
		(width 0.111252)
		(layer "F.Cu")
		(net "SAS_EXP_B_PWR5")
	)
	(segment
		(start 84.125816 -493.864646)
		(end 83.050634 -493.864646)
		(width 0.111252)
		(layer "F.Cu")
		(net "SAS_EXP_B_PWR5")
	)
	(via
		(at 7.441946 -212.572854)
		(size 0.5588)
		(drill 0.3048)
		(layers "F.Cu" "B.Cu")
		(net "SAS_EXP_B_PWR5")
	)
	(via
		(at 84.200746 -492.9505)
		(size 0.7112)
		(drill 0.3556)
		(layers "F.Cu" "B.Cu")
		(net "SAS_EXP_B_PWR5")
	)
	(via
		(at 84.231988 -493.970818)
		(size 0.5588)
		(drill 0.3048)
		(layers "F.Cu" "B.Cu")
		(net "SAS_EXP_B_PWR5")
	)
	(segment
		(start 84.231988 -493.970818)
		(end 84.200746 -493.8903)
		(width 0.111252)
		(layer "B.Cu")
		(net "SAS_EXP_B_PWR5")
	)
	(segment
		(start 84.200746 -493.8903)
		(end 84.200746 -492.9505)
		(width 0.111252)
		(layer "B.Cu")
		(net "SAS_EXP_B_PWR5")
	)
	(segment
		(start 10.836402 -400.054572)
		(end 10.836402 -398.55521)
		(width 0.14605)
		(layer "In5.Cu")
		(net "SAS_EXP_B_PWR5")
	)
	(segment
		(start 84.328 -490.4486)
		(end 69.456554 -475.577154)
		(width 0.14605)
		(layer "In5.Cu")
		(net "SAS_EXP_B_PWR5")
	)
	(segment
		(start 84.328 -493.874806)
		(end 84.328 -490.4486)
		(width 0.14605)
		(layer "In5.Cu")
		(net "SAS_EXP_B_PWR5")
	)
	(segment
		(start 7.28599 -461.07223)
		(end 7.28599 -458.408024)
		(width 0.14605)
		(layer "In5.Cu")
		(net "SAS_EXP_B_PWR5")
	)
	(segment
		(start 9.790938 -410.010864)
		(end 9.788144 -410.00807)
		(width 0.14605)
		(layer "In5.Cu")
		(net "SAS_EXP_B_PWR5")
	)
	(segment
		(start 4.778248 -443.076076)
		(end 4.778248 -434.974238)
		(width 0.14605)
		(layer "In5.Cu")
		(net "SAS_EXP_B_PWR5")
	)
	(segment
		(start 10.090404 -397.809212)
		(end 9.148318 -397.809212)
		(width 0.14605)
		(layer "In5.Cu")
		(net "SAS_EXP_B_PWR5")
	)
	(segment
		(start 5.6261 -456.748134)
		(end 5.6261 -443.923928)
		(width 0.14605)
		(layer "In5.Cu")
		(net "SAS_EXP_B_PWR5")
	)
	(segment
		(start 8.795512 -467.97341)
		(end 6.149594 -465.327492)
		(width 0.14605)
		(layer "In5.Cu")
		(net "SAS_EXP_B_PWR5")
	)
	(segment
		(start 13.273786 -473.128848)
		(end 13.093192 -472.948254)
		(width 0.14605)
		(layer "In5.Cu")
		(net "SAS_EXP_B_PWR5")
	)
	(segment
		(start 6.542786 -433.2097)
		(end 9.790938 -429.961548)
		(width 0.14605)
		(layer "In5.Cu")
		(net "SAS_EXP_B_PWR5")
	)
	(segment
		(start 9.148318 -397.809212)
		(end 7.036054 -395.696948)
		(width 0.14605)
		(layer "In5.Cu")
		(net "SAS_EXP_B_PWR5")
	)
	(segment
		(start 10.836402 -398.55521)
		(end 10.090404 -397.809212)
		(width 0.14605)
		(layer "In5.Cu")
		(net "SAS_EXP_B_PWR5")
	)
	(segment
		(start 84.231988 -493.970818)
		(end 84.328 -493.874806)
		(width 0.14605)
		(layer "In5.Cu")
		(net "SAS_EXP_B_PWR5")
	)
	(segment
		(start 9.788144 -406.125426)
		(end 10.343642 -405.569928)
		(width 0.14605)
		(layer "In5.Cu")
		(net "SAS_EXP_B_PWR5")
	)
	(segment
		(start 6.303518 -389.639302)
		(end 8.761222 -387.181598)
		(width 0.14605)
		(layer "In5.Cu")
		(net "SAS_EXP_B_PWR5")
	)
	(segment
		(start 4.778248 -434.974238)
		(end 4.885944 -434.866542)
		(width 0.14605)
		(layer "In5.Cu")
		(net "SAS_EXP_B_PWR5")
	)
	(segment
		(start 9.126982 -387.181598)
		(end 10.388346 -385.920234)
		(width 0.14605)
		(layer "In5.Cu")
		(net "SAS_EXP_B_PWR5")
	)
	(segment
		(start 7.28599 -458.408024)
		(end 5.6261 -456.748134)
		(width 0.14605)
		(layer "In5.Cu")
		(net "SAS_EXP_B_PWR5")
	)
	(segment
		(start 10.388346 -385.920234)
		(end 10.388346 -218.475306)
		(width 0.14605)
		(layer "In5.Cu")
		(net "SAS_EXP_B_PWR5")
	)
	(segment
		(start 7.276338 -461.120998)
		(end 7.28599 -461.07223)
		(width 0.14605)
		(layer "In5.Cu")
		(net "SAS_EXP_B_PWR5")
	)
	(segment
		(start 13.093192 -472.948254)
		(end 13.092938 -472.948254)
		(width 0.14605)
		(layer "In5.Cu")
		(net "SAS_EXP_B_PWR5")
	)
	(segment
		(start 8.761222 -387.181598)
		(end 9.126982 -387.181598)
		(width 0.14605)
		(layer "In5.Cu")
		(net "SAS_EXP_B_PWR5")
	)
	(segment
		(start 7.036054 -392.502644)
		(end 6.303518 -391.770108)
		(width 0.14605)
		(layer "In5.Cu")
		(net "SAS_EXP_B_PWR5")
	)
	(segment
		(start 5.6261 -443.923928)
		(end 4.778248 -443.076076)
		(width 0.14605)
		(layer "In5.Cu")
		(net "SAS_EXP_B_PWR5")
	)
	(segment
		(start 8.795512 -468.650828)
		(end 8.795512 -467.97341)
		(width 0.14605)
		(layer "In5.Cu")
		(net "SAS_EXP_B_PWR5")
	)
	(segment
		(start 10.343642 -405.569928)
		(end 10.343642 -400.547332)
		(width 0.14605)
		(layer "In5.Cu")
		(net "SAS_EXP_B_PWR5")
	)
	(segment
		(start 6.542532 -433.2097)
		(end 6.542786 -433.2097)
		(width 0.14605)
		(layer "In5.Cu")
		(net "SAS_EXP_B_PWR5")
	)
	(segment
		(start 6.149594 -465.327492)
		(end 6.149594 -462.247742)
		(width 0.14605)
		(layer "In5.Cu")
		(net "SAS_EXP_B_PWR5")
	)
	(segment
		(start 7.036054 -395.696948)
		(end 7.036054 -392.502644)
		(width 0.14605)
		(layer "In5.Cu")
		(net "SAS_EXP_B_PWR5")
	)
	(segment
		(start 32.08401 -473.128848)
		(end 13.273786 -473.128848)
		(width 0.14605)
		(layer "In5.Cu")
		(net "SAS_EXP_B_PWR5")
	)
	(segment
		(start 6.149594 -462.247742)
		(end 7.276338 -461.120998)
		(width 0.14605)
		(layer "In5.Cu")
		(net "SAS_EXP_B_PWR5")
	)
	(segment
		(start 10.343642 -400.547332)
		(end 10.836402 -400.054572)
		(width 0.14605)
		(layer "In5.Cu")
		(net "SAS_EXP_B_PWR5")
	)
	(segment
		(start 6.303518 -391.770108)
		(end 6.303518 -389.639302)
		(width 0.14605)
		(layer "In5.Cu")
		(net "SAS_EXP_B_PWR5")
	)
	(segment
		(start 9.790938 -429.961548)
		(end 9.790938 -410.010864)
		(width 0.14605)
		(layer "In5.Cu")
		(net "SAS_EXP_B_PWR5")
	)
	(segment
		(start 10.388346 -218.475306)
		(end 7.441946 -215.528906)
		(width 0.14605)
		(layer "In5.Cu")
		(net "SAS_EXP_B_PWR5")
	)
	(segment
		(start 7.441946 -215.528906)
		(end 7.441946 -212.572854)
		(width 0.14605)
		(layer "In5.Cu")
		(net "SAS_EXP_B_PWR5")
	)
	(segment
		(start 34.532316 -475.577154)
		(end 32.08401 -473.128848)
		(width 0.14605)
		(layer "In5.Cu")
		(net "SAS_EXP_B_PWR5")
	)
	(segment
		(start 4.885944 -434.866542)
		(end 4.885944 -434.866288)
		(width 0.14605)
		(layer "In5.Cu")
		(net "SAS_EXP_B_PWR5")
	)
	(segment
		(start 13.092938 -472.948254)
		(end 8.795512 -468.650828)
		(width 0.14605)
		(layer "In5.Cu")
		(net "SAS_EXP_B_PWR5")
	)
	(segment
		(start 9.788144 -410.00807)
		(end 9.788144 -406.125426)
		(width 0.14605)
		(layer "In5.Cu")
		(net "SAS_EXP_B_PWR5")
	)
	(segment
		(start 69.456554 -475.577154)
		(end 34.532316 -475.577154)
		(width 0.14605)
		(layer "In5.Cu")
		(net "SAS_EXP_B_PWR5")
	)
	(segment
		(start 4.885944 -434.866288)
		(end 6.542532 -433.2097)
		(width 0.14605)
		(layer "In5.Cu")
		(net "SAS_EXP_B_PWR5")
	)
	(segment
		(start 10.0584 -159.253936)
		(end 10.0584 -158.9786)
		(width 0.111252)
		(layer "F.Cu")
		(net "I2C_C_SDA")
	)
	(segment
		(start 9.5885 -151.1808)
		(end 9.0297 -151.7396)
		(width 0.111252)
		(layer "F.Cu")
		(net "I2C_C_SDA")
	)
	(segment
		(start 12.579604 -152.559004)
		(end 11.2014 -151.1808)
		(width 0.111252)
		(layer "F.Cu")
		(net "I2C_C_SDA")
	)
	(segment
		(start 246.6848 -421.767)
		(end 248.285 -421.767)
		(width 0.111252)
		(layer "F.Cu")
		(net "I2C_C_SDA")
	)
	(segment
		(start 10.0584 -158.9786)
		(end 12.579604 -156.457396)
		(width 0.111252)
		(layer "F.Cu")
		(net "I2C_C_SDA")
	)
	(segment
		(start 12.579604 -156.457396)
		(end 12.579604 -152.559004)
		(width 0.111252)
		(layer "F.Cu")
		(net "I2C_C_SDA")
	)
	(segment
		(start 20.066 -396.8496)
		(end 19.9644 -396.748)
		(width 0.111252)
		(layer "F.Cu")
		(net "I2C_C_SDA")
	)
	(segment
		(start 20.066 -397.5481)
		(end 20.066 -396.8496)
		(width 0.111252)
		(layer "F.Cu")
		(net "I2C_C_SDA")
	)
	(segment
		(start 11.2014 -151.1808)
		(end 9.5885 -151.1808)
		(width 0.111252)
		(layer "F.Cu")
		(net "I2C_C_SDA")
	)
	(segment
		(start 19.9644 -396.748)
		(end 19.9644 -396.7226)
		(width 0.111252)
		(layer "F.Cu")
		(net "I2C_C_SDA")
	)
	(via
		(at 19.9644 -396.7226)
		(size 0.5588)
		(drill 0.3048)
		(layers "F.Cu" "B.Cu")
		(net "I2C_C_SDA")
	)
	(via
		(at 248.285 -421.767)
		(size 0.5588)
		(drill 0.3048)
		(layers "F.Cu" "B.Cu")
		(net "I2C_C_SDA")
	)
	(via
		(at 10.0584 -159.253936)
		(size 0.5588)
		(drill 0.3048)
		(layers "F.Cu" "B.Cu")
		(net "I2C_C_SDA")
	)
	(via
		(at 19.9136 -397.8656)
		(size 0.7112)
		(drill 0.3556)
		(layers "F.Cu" "B.Cu")
		(net "I2C_C_SDA")
	)
	(segment
		(start 249.681492 -421.919908)
		(end 255.093978 -421.919908)
		(width 0.111252)
		(layer "B.Cu")
		(net "I2C_C_SDA")
	)
	(segment
		(start 19.9644 -397.8148)
		(end 19.9136 -397.8656)
		(width 0.111252)
		(layer "B.Cu")
		(net "I2C_C_SDA")
	)
	(segment
		(start 248.285 -421.767)
		(end 248.6406 -422.1226)
		(width 0.111252)
		(layer "B.Cu")
		(net "I2C_C_SDA")
	)
	(segment
		(start 249.4788 -422.1226)
		(end 249.681492 -421.919908)
		(width 0.111252)
		(layer "B.Cu")
		(net "I2C_C_SDA")
	)
	(segment
		(start 248.6406 -422.1226)
		(end 249.4788 -422.1226)
		(width 0.111252)
		(layer "B.Cu")
		(net "I2C_C_SDA")
	)
	(segment
		(start 19.9644 -396.7226)
		(end 19.9644 -397.8148)
		(width 0.111252)
		(layer "B.Cu")
		(net "I2C_C_SDA")
	)
	(segment
		(start 84.792058 -403.21865)
		(end 86.0298 -404.456392)
		(width 0.14605)
		(layer "In2.Cu")
		(net "I2C_C_SDA")
	)
	(segment
		(start 19.583908 -397.103092)
		(end 19.583908 -399.069052)
		(width 0.14605)
		(layer "In2.Cu")
		(net "I2C_C_SDA")
	)
	(segment
		(start 247.904 -421.386)
		(end 248.285 -421.767)
		(width 0.14605)
		(layer "In2.Cu")
		(net "I2C_C_SDA")
	)
	(segment
		(start 247.904 -417.598606)
		(end 247.904 -421.386)
		(width 0.14605)
		(layer "In2.Cu")
		(net "I2C_C_SDA")
	)
	(segment
		(start 242.510056 -410.703268)
		(end 246.249698 -414.44291)
		(width 0.14605)
		(layer "In2.Cu")
		(net "I2C_C_SDA")
	)
	(segment
		(start 26.28265 -403.21865)
		(end 84.792058 -403.21865)
		(width 0.14605)
		(layer "In2.Cu")
		(net "I2C_C_SDA")
	)
	(segment
		(start 20.361656 -399.8468)
		(end 22.9108 -399.8468)
		(width 0.14605)
		(layer "In2.Cu")
		(net "I2C_C_SDA")
	)
	(segment
		(start 19.583908 -399.069052)
		(end 20.361656 -399.8468)
		(width 0.14605)
		(layer "In2.Cu")
		(net "I2C_C_SDA")
	)
	(segment
		(start 236.289342 -404.4823)
		(end 236.28985 -404.4823)
		(width 0.14605)
		(layer "In2.Cu")
		(net "I2C_C_SDA")
	)
	(segment
		(start 239.40516 -407.597864)
		(end 242.510056 -410.703268)
		(width 0.14605)
		(layer "In2.Cu")
		(net "I2C_C_SDA")
	)
	(segment
		(start 22.9108 -399.8468)
		(end 26.28265 -403.21865)
		(width 0.14605)
		(layer "In2.Cu")
		(net "I2C_C_SDA")
	)
	(segment
		(start 247.17502 -416.869626)
		(end 247.904 -417.598606)
		(width 0.14605)
		(layer "In2.Cu")
		(net "I2C_C_SDA")
	)
	(segment
		(start 246.249698 -414.44291)
		(end 246.249698 -414.443164)
		(width 0.14605)
		(layer "In2.Cu")
		(net "I2C_C_SDA")
	)
	(segment
		(start 236.28985 -404.4823)
		(end 239.40516 -407.597864)
		(width 0.14605)
		(layer "In2.Cu")
		(net "I2C_C_SDA")
	)
	(segment
		(start 246.249698 -414.443164)
		(end 247.17502 -415.368486)
		(width 0.14605)
		(layer "In2.Cu")
		(net "I2C_C_SDA")
	)
	(segment
		(start 86.0298 -404.456392)
		(end 236.263434 -404.456392)
		(width 0.14605)
		(layer "In2.Cu")
		(net "I2C_C_SDA")
	)
	(segment
		(start 236.263434 -404.456392)
		(end 236.289342 -404.4823)
		(width 0.14605)
		(layer "In2.Cu")
		(net "I2C_C_SDA")
	)
	(segment
		(start 19.9644 -396.7226)
		(end 19.583908 -397.103092)
		(width 0.14605)
		(layer "In2.Cu")
		(net "I2C_C_SDA")
	)
	(segment
		(start 247.17502 -415.368486)
		(end 247.17502 -416.869626)
		(width 0.14605)
		(layer "In2.Cu")
		(net "I2C_C_SDA")
	)
	(segment
		(start 8.486648 -199.590152)
		(end 9.254998 -198.821802)
		(width 0.14605)
		(layer "In5.Cu")
		(net "I2C_C_SDA")
	)
	(segment
		(start 9.254998 -163.341304)
		(end 9.248648 -163.334954)
		(width 0.14605)
		(layer "In5.Cu")
		(net "I2C_C_SDA")
	)
	(segment
		(start 9.248648 -163.334954)
		(end 9.248648 -160.063688)
		(width 0.14605)
		(layer "In5.Cu")
		(net "I2C_C_SDA")
	)
	(segment
		(start 19.9644 -396.7226)
		(end 19.5453 -396.3035)
		(width 0.14605)
		(layer "In5.Cu")
		(net "I2C_C_SDA")
	)
	(segment
		(start 11.321034 -205.605634)
		(end 8.486648 -202.771248)
		(width 0.14605)
		(layer "In5.Cu")
		(net "I2C_C_SDA")
	)
	(segment
		(start 9.254998 -198.821802)
		(end 9.254998 -163.341304)
		(width 0.14605)
		(layer "In5.Cu")
		(net "I2C_C_SDA")
	)
	(segment
		(start 19.5453 -396.3035)
		(end 19.5453 -393.875514)
		(width 0.14605)
		(layer "In5.Cu")
		(net "I2C_C_SDA")
	)
	(segment
		(start 13.569696 -217.156538)
		(end 11.321034 -214.907876)
		(width 0.14605)
		(layer "In5.Cu")
		(net "I2C_C_SDA")
	)
	(segment
		(start 9.248648 -160.063688)
		(end 10.0584 -159.253936)
		(width 0.14605)
		(layer "In5.Cu")
		(net "I2C_C_SDA")
	)
	(segment
		(start 11.321034 -214.907876)
		(end 11.321034 -205.605634)
		(width 0.14605)
		(layer "In5.Cu")
		(net "I2C_C_SDA")
	)
	(segment
		(start 13.569696 -387.89991)
		(end 13.569696 -217.156538)
		(width 0.14605)
		(layer "In5.Cu")
		(net "I2C_C_SDA")
	)
	(segment
		(start 19.5453 -393.875514)
		(end 13.569696 -387.89991)
		(width 0.14605)
		(layer "In5.Cu")
		(net "I2C_C_SDA")
	)
	(segment
		(start 8.486648 -202.771248)
		(end 8.486648 -199.590152)
		(width 0.14605)
		(layer "In5.Cu")
		(net "I2C_C_SDA")
	)
	(segment
		(start 45.926756 -452.783702)
		(end 45.955458 -452.755)
		(width 0.111252)
		(layer "F.Cu")
		(net "DRIVE_ACT_5")
	)
	(segment
		(start 45.955458 -452.755)
		(end 47.383446 -452.755)
		(width 0.111252)
		(layer "F.Cu")
		(net "DRIVE_ACT_5")
	)
	(segment
		(start 47.383446 -452.755)
		(end 50.533046 -452.755)
		(width 0.111252)
		(layer "F.Cu")
		(net "DRIVE_ACT_5")
	)
	(segment
		(start 51.104546 -453.3265)
		(end 51.180746 -453.3265)
		(width 0.111252)
		(layer "F.Cu")
		(net "DRIVE_ACT_5")
	)
	(segment
		(start 45.926756 -453.799702)
		(end 45.926756 -452.783702)
		(width 0.111252)
		(layer "F.Cu")
		(net "DRIVE_ACT_5")
	)
	(segment
		(start 50.533046 -452.755)
		(end 51.104546 -453.3265)
		(width 0.111252)
		(layer "F.Cu")
		(net "DRIVE_ACT_5")
	)
	(via
		(at 51.180746 -453.3265)
		(size 0.7112)
		(drill 0.3556)
		(layers "F.Cu" "B.Cu")
		(net "DRIVE_ACT_5")
	)
	(segment
		(start 10.719308 -154.252168)
		(end 10.719308 -154.48153)
		(width 0.111252)
		(layer "F.Cu")
		(net "I2C_D_SCL")
	)
	(segment
		(start 22.186646 -254.1143)
		(end 22.86 -253.440946)
		(width 0.111252)
		(layer "F.Cu")
		(net "I2C_D_SCL")
	)
	(segment
		(start 9.8679 -153.2128)
		(end 9.8679 -153.40076)
		(width 0.111252)
		(layer "F.Cu")
		(net "I2C_D_SCL")
	)
	(segment
		(start 20.066 -393.2555)
		(end 20.066 -392.6078)
		(width 0.111252)
		(layer "F.Cu")
		(net "I2C_D_SCL")
	)
	(segment
		(start 22.86 -253.440946)
		(end 22.86 -252.2474)
		(width 0.111252)
		(layer "F.Cu")
		(net "I2C_D_SCL")
	)
	(segment
		(start 20.066 -392.6078)
		(end 20.322286 -392.351514)
		(width 0.111252)
		(layer "F.Cu")
		(net "I2C_D_SCL")
	)
	(segment
		(start 9.8679 -153.40076)
		(end 10.719308 -154.252168)
		(width 0.111252)
		(layer "F.Cu")
		(net "I2C_D_SCL")
	)
	(segment
		(start 20.322286 -392.351514)
		(end 20.330922 -392.351514)
		(width 0.111252)
		(layer "F.Cu")
		(net "I2C_D_SCL")
	)
	(via
		(at 19.44116 -216.138252)
		(size 0.5588)
		(drill 0.3048)
		(layers "F.Cu" "B.Cu")
		(net "I2C_D_SCL")
	)
	(via
		(at 10.719308 -154.48153)
		(size 0.5588)
		(drill 0.3048)
		(layers "F.Cu" "B.Cu")
		(net "I2C_D_SCL")
	)
	(via
		(at 22.86 -252.2474)
		(size 0.5588)
		(drill 0.3048)
		(layers "F.Cu" "B.Cu")
		(net "I2C_D_SCL")
	)
	(via
		(at 20.330922 -392.351514)
		(size 0.5588)
		(drill 0.3048)
		(layers "F.Cu" "B.Cu")
		(net "I2C_D_SCL")
	)
	(via
		(at 22.35327 -253.039118)
		(size 0.7112)
		(drill 0.3556)
		(layers "F.Cu" "B.Cu")
		(net "I2C_D_SCL")
	)
	(segment
		(start 22.86 -252.2474)
		(end 22.35327 -252.75413)
		(width 0.111252)
		(layer "B.Cu")
		(net "I2C_D_SCL")
	)
	(segment
		(start 22.35327 -252.75413)
		(end 22.35327 -253.039118)
		(width 0.111252)
		(layer "B.Cu")
		(net "I2C_D_SCL")
	)
	(segment
		(start 20.823428 -391.859008)
		(end 20.330922 -392.351514)
		(width 0.14605)
		(layer "In2.Cu")
		(net "I2C_D_SCL")
	)
	(segment
		(start 22.86 -252.2474)
		(end 22.86 -256.707386)
		(width 0.14605)
		(layer "In2.Cu")
		(net "I2C_D_SCL")
	)
	(segment
		(start 24.244554 -357.043228)
		(end 24.244808 -357.043482)
		(width 0.14605)
		(layer "In2.Cu")
		(net "I2C_D_SCL")
	)
	(segment
		(start 20.823428 -379.835918)
		(end 20.888198 -379.900688)
		(width 0.14605)
		(layer "In2.Cu")
		(net "I2C_D_SCL")
	)
	(segment
		(start 23.625302 -351.878138)
		(end 24.244554 -352.49739)
		(width 0.14605)
		(layer "In2.Cu")
		(net "I2C_D_SCL")
	)
	(segment
		(start 24.244554 -352.49739)
		(end 24.244554 -357.043228)
		(width 0.14605)
		(layer "In2.Cu")
		(net "I2C_D_SCL")
	)
	(segment
		(start 20.927568 -342.643206)
		(end 23.625302 -345.34094)
		(width 0.14605)
		(layer "In2.Cu")
		(net "I2C_D_SCL")
	)
	(segment
		(start 10.719308 -154.48153)
		(end 10.719308 -154.824176)
		(width 0.14605)
		(layer "In2.Cu")
		(net "I2C_D_SCL")
	)
	(segment
		(start 20.888198 -379.900688)
		(end 20.888198 -381.108712)
		(width 0.14605)
		(layer "In2.Cu")
		(net "I2C_D_SCL")
	)
	(segment
		(start 23.6728 -167.777668)
		(end 23.6728 -212.6742)
		(width 0.14605)
		(layer "In2.Cu")
		(net "I2C_D_SCL")
	)
	(segment
		(start 22.86 -256.707386)
		(end 22.958552 -256.805938)
		(width 0.14605)
		(layer "In2.Cu")
		(net "I2C_D_SCL")
	)
	(segment
		(start 20.32 -216.027)
		(end 19.552412 -216.027)
		(width 0.14605)
		(layer "In2.Cu")
		(net "I2C_D_SCL")
	)
	(segment
		(start 22.86 -336.339688)
		(end 22.86 -336.506312)
		(width 0.14605)
		(layer "In2.Cu")
		(net "I2C_D_SCL")
	)
	(segment
		(start 19.552412 -216.027)
		(end 19.44116 -216.138252)
		(width 0.14605)
		(layer "In2.Cu")
		(net "I2C_D_SCL")
	)
	(segment
		(start 22.86 -336.506312)
		(end 20.927568 -338.438744)
		(width 0.14605)
		(layer "In2.Cu")
		(net "I2C_D_SCL")
	)
	(segment
		(start 22.958552 -256.805938)
		(end 22.958552 -336.241136)
		(width 0.14605)
		(layer "In2.Cu")
		(net "I2C_D_SCL")
	)
	(segment
		(start 23.6728 -212.6742)
		(end 20.32 -216.027)
		(width 0.14605)
		(layer "In2.Cu")
		(net "I2C_D_SCL")
	)
	(segment
		(start 22.958552 -336.241136)
		(end 22.86 -336.339688)
		(width 0.14605)
		(layer "In2.Cu")
		(net "I2C_D_SCL")
	)
	(segment
		(start 24.244808 -357.043482)
		(end 24.244808 -357.79075)
		(width 0.14605)
		(layer "In2.Cu")
		(net "I2C_D_SCL")
	)
	(segment
		(start 20.888198 -381.108712)
		(end 20.823428 -381.173482)
		(width 0.14605)
		(layer "In2.Cu")
		(net "I2C_D_SCL")
	)
	(segment
		(start 10.719308 -154.824176)
		(end 23.6728 -167.777668)
		(width 0.14605)
		(layer "In2.Cu")
		(net "I2C_D_SCL")
	)
	(segment
		(start 23.625302 -345.34094)
		(end 23.625302 -351.878138)
		(width 0.14605)
		(layer "In2.Cu")
		(net "I2C_D_SCL")
	)
	(segment
		(start 20.927568 -338.438744)
		(end 20.927568 -342.643206)
		(width 0.14605)
		(layer "In2.Cu")
		(net "I2C_D_SCL")
	)
	(segment
		(start 20.823428 -361.21213)
		(end 20.823428 -379.835918)
		(width 0.14605)
		(layer "In2.Cu")
		(net "I2C_D_SCL")
	)
	(segment
		(start 20.823428 -381.173482)
		(end 20.823428 -391.859008)
		(width 0.14605)
		(layer "In2.Cu")
		(net "I2C_D_SCL")
	)
	(segment
		(start 24.244808 -357.79075)
		(end 20.823428 -361.21213)
		(width 0.14605)
		(layer "In2.Cu")
		(net "I2C_D_SCL")
	)
	(segment
		(start 18.614644 -217.869516)
		(end 19.44116 -217.043)
		(width 0.14605)
		(layer "In5.Cu")
		(net "I2C_D_SCL")
	)
	(segment
		(start 22.86 -252.2474)
		(end 22.86 -251.6378)
		(width 0.14605)
		(layer "In5.Cu")
		(net "I2C_D_SCL")
	)
	(segment
		(start 19.44116 -217.043)
		(end 19.44116 -216.138252)
		(width 0.14605)
		(layer "In5.Cu")
		(net "I2C_D_SCL")
	)
	(segment
		(start 18.614644 -247.392444)
		(end 18.614644 -217.869516)
		(width 0.14605)
		(layer "In5.Cu")
		(net "I2C_D_SCL")
	)
	(segment
		(start 22.86 -251.6378)
		(end 18.614644 -247.392444)
		(width 0.14605)
		(layer "In5.Cu")
		(net "I2C_D_SCL")
	)
	(segment
		(start 217.0176 -63.493396)
		(end 216.224612 -63.493396)
		(width 0.09525)
		(layer "F.Cu")
		(net "SAS2X28_B_HDD4_RX_-")
	)
	(via
		(at 216.224612 -63.493396)
		(size 0.5588)
		(drill 0.3048)
		(layers "F.Cu" "B.Cu")
		(net "SAS2X28_B_HDD4_RX_-")
	)
	(arc
		(start 217.354912 -63.353696)
		(mid 217.200152 -63.457103)
		(end 217.0176 -63.493396)
		(width 0.09525)
		(layer "F.Cu")
		(net "SAS2X28_B_HDD4_RX_-")
	)
	(segment
		(start 17.449546 -90.105992)
		(end 17.449546 -74.323956)
		(width 0.09525)
		(layer "B.Cu")
		(net "SAS2X28_B_HDD4_RX_-")
	)
	(segment
		(start 2.811526 -100.498402)
		(end 4.994656 -100.498402)
		(width 0.09525)
		(layer "B.Cu")
		(net "SAS2X28_B_HDD4_RX_-")
	)
	(segment
		(start 215.9 -63.818008)
		(end 216.224612 -63.493396)
		(width 0.09525)
		(layer "B.Cu")
		(net "SAS2X28_B_HDD4_RX_-")
	)
	(segment
		(start 8.419846 -99.7458)
		(end 17.018 -91.147646)
		(width 0.09525)
		(layer "B.Cu")
		(net "SAS2X28_B_HDD4_RX_-")
	)
	(segment
		(start 213.833202 -63.96736)
		(end 215.53932 -63.96736)
		(width 0.09525)
		(layer "B.Cu")
		(net "SAS2X28_B_HDD4_RX_-")
	)
	(segment
		(start 17.784318 -73.515728)
		(end 31.732474 -59.567572)
		(width 0.09525)
		(layer "B.Cu")
		(net "SAS2X28_B_HDD4_RX_-")
	)
	(segment
		(start 4.994656 -100.498402)
		(end 4.99618 -100.499926)
		(width 0.09525)
		(layer "B.Cu")
		(net "SAS2X28_B_HDD4_RX_-")
	)
	(segment
		(start 209.145886 -59.67984)
		(end 213.150704 -63.684658)
		(width 0.09525)
		(layer "B.Cu")
		(net "SAS2X28_B_HDD4_RX_-")
	)
	(segment
		(start 32.540702 -59.2328)
		(end 208.06664 -59.2328)
		(width 0.09525)
		(layer "B.Cu")
		(net "SAS2X28_B_HDD4_RX_-")
	)
	(segment
		(start 5.216906 -100.408486)
		(end 5.384546 -100.2411)
		(width 0.09525)
		(layer "B.Cu")
		(net "SAS2X28_B_HDD4_RX_-")
	)
	(segment
		(start 5.579618 -100.160328)
		(end 7.419086 -100.160328)
		(width 0.09525)
		(layer "B.Cu")
		(net "SAS2X28_B_HDD4_RX_-")
	)
	(arc
		(start 31.732474 -59.567572)
		(mid 32.103292 -59.319799)
		(end 32.540702 -59.2328)
		(width 0.09525)
		(layer "B.Cu")
		(net "SAS2X28_B_HDD4_RX_-")
	)
	(arc
		(start 17.018 -91.147646)
		(mid 17.337333 -90.669731)
		(end 17.449546 -90.105992)
		(width 0.09525)
		(layer "B.Cu")
		(net "SAS2X28_B_HDD4_RX_-")
	)
	(arc
		(start 7.419086 -100.160328)
		(mid 7.960693 -100.052596)
		(end 8.419846 -99.7458)
		(width 0.09525)
		(layer "B.Cu")
		(net "SAS2X28_B_HDD4_RX_-")
	)
	(arc
		(start 213.150704 -63.684658)
		(mid 213.463837 -63.893887)
		(end 213.833202 -63.96736)
		(width 0.09525)
		(layer "B.Cu")
		(net "SAS2X28_B_HDD4_RX_-")
	)
	(arc
		(start 208.06664 -59.2328)
		(mid 208.650739 -59.348967)
		(end 209.145886 -59.67984)
		(width 0.09525)
		(layer "B.Cu")
		(net "SAS2X28_B_HDD4_RX_-")
	)
	(arc
		(start 17.449546 -74.323956)
		(mid 17.536552 -73.886549)
		(end 17.784318 -73.515728)
		(width 0.09525)
		(layer "B.Cu")
		(net "SAS2X28_B_HDD4_RX_-")
	)
	(arc
		(start 215.53932 -63.96736)
		(mid 215.734501 -63.928536)
		(end 215.9 -63.818008)
		(width 0.09525)
		(layer "B.Cu")
		(net "SAS2X28_B_HDD4_RX_-")
	)
	(arc
		(start 4.99618 -100.499926)
		(mid 5.115641 -100.476164)
		(end 5.216906 -100.408486)
		(width 0.09525)
		(layer "B.Cu")
		(net "SAS2X28_B_HDD4_RX_-")
	)
	(arc
		(start 5.384546 -100.2411)
		(mid 5.474046 -100.181298)
		(end 5.579618 -100.160328)
		(width 0.09525)
		(layer "B.Cu")
		(net "SAS2X28_B_HDD4_RX_-")
	)
	(segment
		(start 15.526766 -272.97634)
		(end 13.866114 -274.636992)
		(width 0.09525)
		(layer "F.Cu")
		(net "SAS2X28_A_HDD9_TX_-")
	)
	(segment
		(start 36.82746 -54.189376)
		(end 36.82746 -53.968396)
		(width 0.09525)
		(layer "F.Cu")
		(net "SAS2X28_A_HDD9_TX_-")
	)
	(segment
		(start 32.2072 -127.544068)
		(end 32.2072 -153.658824)
		(width 0.09525)
		(layer "F.Cu")
		(net "SAS2X28_A_HDD9_TX_-")
	)
	(segment
		(start 33.043114 -255.460246)
		(end 24.28494 -264.21842)
		(width 0.09525)
		(layer "F.Cu")
		(net "SAS2X28_A_HDD9_TX_-")
	)
	(segment
		(start 29.1592 -59.421268)
		(end 29.1592 -122.391932)
		(width 0.09525)
		(layer "F.Cu")
		(net "SAS2X28_A_HDD9_TX_-")
	)
	(segment
		(start 31.463488 -155.454858)
		(end 29.6291 -157.289246)
		(width 0.09525)
		(layer "F.Cu")
		(net "SAS2X28_A_HDD9_TX_-")
	)
	(segment
		(start 11.256264 -358.869742)
		(end 11.256264 -362.470446)
		(width 0.09525)
		(layer "F.Cu")
		(net "SAS2X28_A_HDD9_TX_-")
	)
	(segment
		(start 13.402818 -275.30425)
		(end 13.40231 -275.305012)
		(width 0.09525)
		(layer "F.Cu")
		(net "SAS2X28_A_HDD9_TX_-")
	)
	(segment
		(start 24.28494 -264.21842)
		(end 15.526766 -272.97634)
		(width 0.09525)
		(layer "F.Cu")
		(net "SAS2X28_A_HDD9_TX_-")
	)
	(segment
		(start 29.806646 -123.954286)
		(end 31.366714 -125.514354)
		(width 0.09525)
		(layer "F.Cu")
		(net "SAS2X28_A_HDD9_TX_-")
	)
	(segment
		(start 27.051254 -160.919922)
		(end 27.051 -160.919668)
		(width 0.09525)
		(layer "F.Cu")
		(net "SAS2X28_A_HDD9_TX_-")
	)
	(segment
		(start 13.194538 -276.257512)
		(end 13.194538 -355.946456)
		(width 0.09525)
		(layer "F.Cu")
		(net "SAS2X28_A_HDD9_TX_-")
	)
	(segment
		(start 10.713974 -363.780578)
		(end 8.612886 -365.88192)
		(width 0.09525)
		(layer "F.Cu")
		(net "SAS2X28_A_HDD9_TX_-")
	)
	(segment
		(start 4.646422 -366.50041)
		(end 4.644898 -366.498886)
		(width 0.09525)
		(layer "F.Cu")
		(net "SAS2X28_A_HDD9_TX_-")
	)
	(segment
		(start 13.194792 -276.257766)
		(end 13.194538 -276.257512)
		(width 0.09525)
		(layer "F.Cu")
		(net "SAS2X28_A_HDD9_TX_-")
	)
	(segment
		(start 29.6291 -157.289246)
		(end 27.794966 -159.123888)
		(width 0.09525)
		(layer "F.Cu")
		(net "SAS2X28_A_HDD9_TX_-")
	)
	(segment
		(start 32.917638 -54.610762)
		(end 29.903166 -57.625234)
		(width 0.09525)
		(layer "F.Cu")
		(net "SAS2X28_A_HDD9_TX_-")
	)
	(segment
		(start 7.939024 -366.160812)
		(end 5.466334 -366.160812)
		(width 0.09525)
		(layer "F.Cu")
		(net "SAS2X28_A_HDD9_TX_-")
	)
	(segment
		(start 36.72586 -53.866796)
		(end 34.713672 -53.866796)
		(width 0.09525)
		(layer "F.Cu")
		(net "SAS2X28_A_HDD9_TX_-")
	)
	(segment
		(start 27.051 -160.919668)
		(end 27.051 -183.199532)
		(width 0.09525)
		(layer "F.Cu")
		(net "SAS2X28_A_HDD9_TX_-")
	)
	(segment
		(start 33.8836 -192.136268)
		(end 33.8836 -253.430532)
		(width 0.09525)
		(layer "F.Cu")
		(net "SAS2X28_A_HDD9_TX_-")
	)
	(segment
		(start 4.644898 -366.498886)
		(end 3.192526 -366.498886)
		(width 0.09525)
		(layer "F.Cu")
		(net "SAS2X28_A_HDD9_TX_-")
	)
	(segment
		(start 27.698446 -184.761886)
		(end 33.043114 -190.106554)
		(width 0.09525)
		(layer "F.Cu")
		(net "SAS2X28_A_HDD9_TX_-")
	)
	(segment
		(start 12.804648 -356.847648)
		(end 11.592052 -358.060244)
		(width 0.09525)
		(layer "F.Cu")
		(net "SAS2X28_A_HDD9_TX_-")
	)
	(segment
		(start 38.250114 -54.339998)
		(end 36.977828 -54.339998)
		(width 0.09525)
		(layer "F.Cu")
		(net "SAS2X28_A_HDD9_TX_-")
	)
	(arc
		(start 31.366714 -125.514354)
		(mid 31.988866 -126.44561)
		(end 32.2072 -127.544068)
		(width 0.09525)
		(layer "F.Cu")
		(net "SAS2X28_A_HDD9_TX_-")
	)
	(arc
		(start 36.871656 -54.296056)
		(mid 36.838952 -54.247111)
		(end 36.82746 -54.189376)
		(width 0.09525)
		(layer "F.Cu")
		(net "SAS2X28_A_HDD9_TX_-")
	)
	(arc
		(start 36.977828 -54.339998)
		(mid 36.920382 -54.328571)
		(end 36.871656 -54.296056)
		(width 0.09525)
		(layer "F.Cu")
		(net "SAS2X28_A_HDD9_TX_-")
	)
	(arc
		(start 33.043114 -190.106554)
		(mid 33.665266 -191.03781)
		(end 33.8836 -192.136268)
		(width 0.09525)
		(layer "F.Cu")
		(net "SAS2X28_A_HDD9_TX_-")
	)
	(arc
		(start 5.466334 -366.160812)
		(mid 5.32199 -366.189524)
		(end 5.199634 -366.271302)
		(width 0.09525)
		(layer "F.Cu")
		(net "SAS2X28_A_HDD9_TX_-")
	)
	(arc
		(start 32.2072 -153.658824)
		(mid 32.013971 -154.630811)
		(end 31.463488 -155.454858)
		(width 0.09525)
		(layer "F.Cu")
		(net "SAS2X28_A_HDD9_TX_-")
	)
	(arc
		(start 36.82746 -53.968396)
		(mid 36.808399 -53.909152)
		(end 36.758372 -53.87213)
		(width 0.09525)
		(layer "F.Cu")
		(net "SAS2X28_A_HDD9_TX_-")
	)
	(arc
		(start 13.194284 -355.960172)
		(mid 13.082828 -356.440503)
		(end 12.804648 -356.847648)
		(width 0.09525)
		(layer "F.Cu")
		(net "SAS2X28_A_HDD9_TX_-")
	)
	(arc
		(start 13.194538 -355.946456)
		(mid 13.194474 -355.953315)
		(end 13.194284 -355.960172)
		(width 0.09525)
		(layer "F.Cu")
		(net "SAS2X28_A_HDD9_TX_-")
	)
	(arc
		(start 11.592052 -358.060244)
		(mid 11.343538 -358.431559)
		(end 11.256264 -358.869742)
		(width 0.09525)
		(layer "F.Cu")
		(net "SAS2X28_A_HDD9_TX_-")
	)
	(arc
		(start 13.40231 -275.305012)
		(mid 13.247302 -275.770226)
		(end 13.194792 -276.257766)
		(width 0.09525)
		(layer "F.Cu")
		(net "SAS2X28_A_HDD9_TX_-")
	)
	(arc
		(start 29.903166 -57.625234)
		(mid 29.352568 -58.449261)
		(end 29.1592 -59.421268)
		(width 0.09525)
		(layer "F.Cu")
		(net "SAS2X28_A_HDD9_TX_-")
	)
	(arc
		(start 13.866114 -274.636992)
		(mid 13.604634 -274.949909)
		(end 13.402818 -275.30425)
		(width 0.09525)
		(layer "F.Cu")
		(net "SAS2X28_A_HDD9_TX_-")
	)
	(arc
		(start 34.713672 -53.866796)
		(mid 33.741656 -54.060142)
		(end 32.917638 -54.610762)
		(width 0.09525)
		(layer "F.Cu")
		(net "SAS2X28_A_HDD9_TX_-")
	)
	(arc
		(start 33.8836 -253.430532)
		(mid 33.665202 -254.528964)
		(end 33.043114 -255.460246)
		(width 0.09525)
		(layer "F.Cu")
		(net "SAS2X28_A_HDD9_TX_-")
	)
	(arc
		(start 29.1592 -122.391932)
		(mid 29.327509 -123.237518)
		(end 29.806646 -123.954286)
		(width 0.09525)
		(layer "F.Cu")
		(net "SAS2X28_A_HDD9_TX_-")
	)
	(arc
		(start 8.612886 -365.88192)
		(mid 8.303673 -366.08834)
		(end 7.939024 -366.160812)
		(width 0.09525)
		(layer "F.Cu")
		(net "SAS2X28_A_HDD9_TX_-")
	)
	(arc
		(start 27.794966 -159.123888)
		(mid 27.244505 -159.947945)
		(end 27.051254 -160.919922)
		(width 0.09525)
		(layer "F.Cu")
		(net "SAS2X28_A_HDD9_TX_-")
	)
	(arc
		(start 27.051 -183.199532)
		(mid 27.219309 -184.045118)
		(end 27.698446 -184.761886)
		(width 0.09525)
		(layer "F.Cu")
		(net "SAS2X28_A_HDD9_TX_-")
	)
	(arc
		(start 5.199634 -366.271302)
		(mid 4.945818 -366.440896)
		(end 4.646422 -366.50041)
		(width 0.09525)
		(layer "F.Cu")
		(net "SAS2X28_A_HDD9_TX_-")
	)
	(arc
		(start 36.758372 -53.87213)
		(mid 36.742333 -53.868142)
		(end 36.72586 -53.866796)
		(width 0.09525)
		(layer "F.Cu")
		(net "SAS2X28_A_HDD9_TX_-")
	)
	(arc
		(start 11.256264 -362.470446)
		(mid 11.115408 -363.17943)
		(end 10.713974 -363.780578)
		(width 0.09525)
		(layer "F.Cu")
		(net "SAS2X28_A_HDD9_TX_-")
	)
	(segment
		(start 217.354912 -64.242696)
		(end 217.129614 -64.242696)
		(width 0.09525)
		(layer "F.Cu")
		(net "SAS2X28_B_HDD4_RX_+")
	)
	(via
		(at 215.361012 -63.51016)
		(size 0.5588)
		(drill 0.3048)
		(layers "F.Cu" "B.Cu")
		(net "SAS2X28_B_HDD4_RX_+")
	)
	(arc
		(start 217.129614 -64.242696)
		(mid 216.17247 -64.052308)
		(end 215.361012 -63.51016)
		(width 0.09525)
		(layer "F.Cu")
		(net "SAS2X28_B_HDD4_RX_+")
	)
	(segment
		(start 32.540448 -58.9026)
		(end 208.06664 -58.9026)
		(width 0.09525)
		(layer "B.Cu")
		(net "SAS2X28_B_HDD4_RX_+")
	)
	(segment
		(start 213.833456 -63.63716)
		(end 215.054434 -63.63716)
		(width 0.09525)
		(layer "B.Cu")
		(net "SAS2X28_B_HDD4_RX_+")
	)
	(segment
		(start 17.119346 -90.105738)
		(end 17.119346 -74.323702)
		(width 0.09525)
		(layer "B.Cu")
		(net "SAS2X28_B_HDD4_RX_+")
	)
	(segment
		(start 4.951476 -99.498404)
		(end 4.953 -99.499928)
		(width 0.09525)
		(layer "B.Cu")
		(net "SAS2X28_B_HDD4_RX_+")
	)
	(segment
		(start 17.550892 -73.282048)
		(end 31.498794 -59.334146)
		(width 0.09525)
		(layer "B.Cu")
		(net "SAS2X28_B_HDD4_RX_+")
	)
	(segment
		(start 8.186166 -99.512374)
		(end 16.784574 -90.913966)
		(width 0.09525)
		(layer "B.Cu")
		(net "SAS2X28_B_HDD4_RX_+")
	)
	(segment
		(start 2.811526 -99.498404)
		(end 4.951476 -99.498404)
		(width 0.09525)
		(layer "B.Cu")
		(net "SAS2X28_B_HDD4_RX_+")
	)
	(segment
		(start 5.435346 -99.830128)
		(end 7.419086 -99.830128)
		(width 0.09525)
		(layer "B.Cu")
		(net "SAS2X28_B_HDD4_RX_+")
	)
	(segment
		(start 209.379566 -59.446414)
		(end 213.384384 -63.451232)
		(width 0.09525)
		(layer "B.Cu")
		(net "SAS2X28_B_HDD4_RX_+")
	)
	(segment
		(start 5.051806 -99.540822)
		(end 5.274564 -99.76358)
		(width 0.09525)
		(layer "B.Cu")
		(net "SAS2X28_B_HDD4_RX_+")
	)
	(arc
		(start 213.384384 -63.451232)
		(mid 213.59042 -63.588901)
		(end 213.833456 -63.63716)
		(width 0.09525)
		(layer "B.Cu")
		(net "SAS2X28_B_HDD4_RX_+")
	)
	(arc
		(start 7.419086 -99.830128)
		(mid 7.834248 -99.747565)
		(end 8.186166 -99.512374)
		(width 0.09525)
		(layer "B.Cu")
		(net "SAS2X28_B_HDD4_RX_+")
	)
	(arc
		(start 17.119346 -74.323702)
		(mid 17.231487 -73.759933)
		(end 17.550892 -73.282048)
		(width 0.09525)
		(layer "B.Cu")
		(net "SAS2X28_B_HDD4_RX_+")
	)
	(arc
		(start 5.274564 -99.76358)
		(mid 5.348331 -99.81287)
		(end 5.435346 -99.830128)
		(width 0.09525)
		(layer "B.Cu")
		(net "SAS2X28_B_HDD4_RX_+")
	)
	(arc
		(start 16.784574 -90.913966)
		(mid 17.032347 -90.543148)
		(end 17.119346 -90.105738)
		(width 0.09525)
		(layer "B.Cu")
		(net "SAS2X28_B_HDD4_RX_+")
	)
	(arc
		(start 4.953 -99.499928)
		(mid 5.006461 -99.510562)
		(end 5.051806 -99.540822)
		(width 0.09525)
		(layer "B.Cu")
		(net "SAS2X28_B_HDD4_RX_+")
	)
	(arc
		(start 215.054434 -63.63716)
		(mid 215.220357 -63.604156)
		(end 215.361012 -63.51016)
		(width 0.09525)
		(layer "B.Cu")
		(net "SAS2X28_B_HDD4_RX_+")
	)
	(arc
		(start 208.06664 -58.9026)
		(mid 208.777184 -59.043936)
		(end 209.379566 -59.446414)
		(width 0.09525)
		(layer "B.Cu")
		(net "SAS2X28_B_HDD4_RX_+")
	)
	(arc
		(start 31.498794 -59.334146)
		(mid 31.976709 -59.014813)
		(end 32.540448 -58.9026)
		(width 0.09525)
		(layer "B.Cu")
		(net "SAS2X28_B_HDD4_RX_+")
	)
	(segment
		(start 197.167246 -81.9277)
		(end 196.341746 -81.9277)
		(width 0.111252)
		(layer "F.Cu")
		(net "SAS_EXP_B_PWR4")
	)
	(segment
		(start 21.0058 -202.1078)
		(end 13.845286 -202.1078)
		(width 0.111252)
		(layer "F.Cu")
		(net "SAS_EXP_B_PWR4")
	)
	(segment
		(start 196.214746 -82.0547)
		(end 196.00799 -82.261456)
		(width 0.111252)
		(layer "F.Cu")
		(net "SAS_EXP_B_PWR4")
	)
	(segment
		(start 13.845286 -202.1078)
		(end 11.238738 -199.501252)
		(width 0.111252)
		(layer "F.Cu")
		(net "SAS_EXP_B_PWR4")
	)
	(segment
		(start 196.00799 -82.261456)
		(end 195.002912 -82.261456)
		(width 0.111252)
		(layer "F.Cu")
		(net "SAS_EXP_B_PWR4")
	)
	(segment
		(start 22.4028 -200.7108)
		(end 21.0058 -202.1078)
		(width 0.111252)
		(layer "F.Cu")
		(net "SAS_EXP_B_PWR4")
	)
	(segment
		(start 11.238738 -199.501252)
		(end 3.193542 -199.501252)
		(width 0.111252)
		(layer "F.Cu")
		(net "SAS_EXP_B_PWR4")
	)
	(segment
		(start 28.067 -200.7108)
		(end 22.4028 -200.7108)
		(width 0.111252)
		(layer "F.Cu")
		(net "SAS_EXP_B_PWR4")
	)
	(segment
		(start 3.193542 -199.501252)
		(end 3.19024 -199.504554)
		(width 0.111252)
		(layer "F.Cu")
		(net "SAS_EXP_B_PWR4")
	)
	(segment
		(start 196.341746 -81.9277)
		(end 196.214746 -82.0547)
		(width 0.111252)
		(layer "F.Cu")
		(net "SAS_EXP_B_PWR4")
	)
	(via
		(at 196.214746 -82.0547)
		(size 0.5588)
		(drill 0.3048)
		(layers "F.Cu" "B.Cu")
		(net "SAS_EXP_B_PWR4")
	)
	(via
		(at 83.95716 -202.059286)
		(size 0.5588)
		(drill 0.3048)
		(layers "F.Cu" "B.Cu")
		(net "SAS_EXP_B_PWR4")
	)
	(via
		(at 197.154546 -82.0547)
		(size 0.7112)
		(drill 0.3556)
		(layers "F.Cu" "B.Cu")
		(net "SAS_EXP_B_PWR4")
	)
	(via
		(at 28.067 -200.7108)
		(size 0.5588)
		(drill 0.3048)
		(layers "F.Cu" "B.Cu")
		(net "SAS_EXP_B_PWR4")
	)
	(segment
		(start 196.214746 -82.0547)
		(end 197.154546 -82.0547)
		(width 0.111252)
		(layer "B.Cu")
		(net "SAS_EXP_B_PWR4")
	)
	(segment
		(start 86.905846 -185.128154)
		(end 103.658924 -168.375076)
		(width 0.14605)
		(layer "In2.Cu")
		(net "SAS_EXP_B_PWR4")
	)
	(segment
		(start 86.905846 -199.1106)
		(end 86.905846 -185.128154)
		(width 0.14605)
		(layer "In2.Cu")
		(net "SAS_EXP_B_PWR4")
	)
	(segment
		(start 83.95716 -202.059286)
		(end 86.905846 -199.1106)
		(width 0.14605)
		(layer "In2.Cu")
		(net "SAS_EXP_B_PWR4")
	)
	(segment
		(start 201.6506 -84.328)
		(end 199.3773 -82.0547)
		(width 0.14605)
		(layer "In2.Cu")
		(net "SAS_EXP_B_PWR4")
	)
	(segment
		(start 199.3773 -82.0547)
		(end 196.214746 -82.0547)
		(width 0.14605)
		(layer "In2.Cu")
		(net "SAS_EXP_B_PWR4")
	)
	(segment
		(start 200.0504 -86.6648)
		(end 200.3552 -86.6648)
		(width 0.14605)
		(layer "In2.Cu")
		(net "SAS_EXP_B_PWR4")
	)
	(segment
		(start 118.340124 -168.375076)
		(end 200.0504 -86.6648)
		(width 0.14605)
		(layer "In2.Cu")
		(net "SAS_EXP_B_PWR4")
	)
	(segment
		(start 200.3552 -86.6648)
		(end 201.6506 -85.3694)
		(width 0.14605)
		(layer "In2.Cu")
		(net "SAS_EXP_B_PWR4")
	)
	(segment
		(start 103.658924 -168.375076)
		(end 118.340124 -168.375076)
		(width 0.14605)
		(layer "In2.Cu")
		(net "SAS_EXP_B_PWR4")
	)
	(segment
		(start 201.6506 -85.3694)
		(end 201.6506 -84.328)
		(width 0.14605)
		(layer "In2.Cu")
		(net "SAS_EXP_B_PWR4")
	)
	(segment
		(start 28.12288 -200.682098)
		(end 28.095702 -200.682098)
		(width 0.14605)
		(layer "In5.Cu")
		(net "SAS_EXP_B_PWR4")
	)
	(segment
		(start 28.095702 -200.682098)
		(end 28.067 -200.7108)
		(width 0.14605)
		(layer "In5.Cu")
		(net "SAS_EXP_B_PWR4")
	)
	(segment
		(start 28.303728 -200.50125)
		(end 28.12288 -200.682098)
		(width 0.14605)
		(layer "In5.Cu")
		(net "SAS_EXP_B_PWR4")
	)
	(segment
		(start 83.936332 -202.059286)
		(end 82.378296 -200.50125)
		(width 0.14605)
		(layer "In5.Cu")
		(net "SAS_EXP_B_PWR4")
	)
	(segment
		(start 83.95716 -202.059286)
		(end 83.936332 -202.059286)
		(width 0.14605)
		(layer "In5.Cu")
		(net "SAS_EXP_B_PWR4")
	)
	(segment
		(start 82.378296 -200.50125)
		(end 28.303728 -200.50125)
		(width 0.14605)
		(layer "In5.Cu")
		(net "SAS_EXP_B_PWR4")
	)
	(segment
		(start 216.910412 -69.830696)
		(end 216.910412 -68.509388)
		(width 0.111252)
		(layer "F.Cu")
		(net "HDD_PRSNT4")
	)
	(segment
		(start 216.9668 -67.2592)
		(end 216.9668 -68.453)
		(width 0.111252)
		(layer "F.Cu")
		(net "HDD_PRSNT4")
	)
	(segment
		(start 216.910412 -68.509388)
		(end 216.9668 -68.453)
		(width 0.111252)
		(layer "F.Cu")
		(net "HDD_PRSNT4")
	)
	(segment
		(start 217.0176 -67.2084)
		(end 216.9668 -67.2592)
		(width 0.111252)
		(layer "F.Cu")
		(net "HDD_PRSNT4")
	)
	(via
		(at 11.187684 -203.086716)
		(size 0.5588)
		(drill 0.3048)
		(layers "F.Cu" "B.Cu")
		(net "HDD_PRSNT4")
	)
	(via
		(at 7.689596 -453.958452)
		(size 0.5588)
		(drill 0.3048)
		(layers "F.Cu" "B.Cu")
		(net "HDD_PRSNT4")
	)
	(via
		(at 216.9668 -68.453)
		(size 0.7112)
		(drill 0.3556)
		(layers "F.Cu" "B.Cu")
		(net "HDD_PRSNT4")
	)
	(via
		(at 217.0176 -67.2084)
		(size 0.5588)
		(drill 0.3048)
		(layers "F.Cu" "B.Cu")
		(net "HDD_PRSNT4")
	)
	(segment
		(start 2.811018 -199.502776)
		(end 2.80924 -199.504554)
		(width 0.111252)
		(layer "B.Cu")
		(net "HDD_PRSNT4")
	)
	(segment
		(start 7.689596 -453.958452)
		(end 6.1468 -455.501248)
		(width 0.111252)
		(layer "B.Cu")
		(net "HDD_PRSNT4")
	)
	(segment
		(start 11.187684 -201.865484)
		(end 8.824976 -199.502776)
		(width 0.111252)
		(layer "B.Cu")
		(net "HDD_PRSNT4")
	)
	(segment
		(start 8.824976 -199.502776)
		(end 2.811018 -199.502776)
		(width 0.111252)
		(layer "B.Cu")
		(net "HDD_PRSNT4")
	)
	(segment
		(start 11.187684 -203.086716)
		(end 11.187684 -201.865484)
		(width 0.111252)
		(layer "B.Cu")
		(net "HDD_PRSNT4")
	)
	(segment
		(start 2.812542 -455.501248)
		(end 2.80924 -455.50455)
		(width 0.111252)
		(layer "B.Cu")
		(net "HDD_PRSNT4")
	)
	(segment
		(start 6.1468 -455.501248)
		(end 2.812542 -455.501248)
		(width 0.111252)
		(layer "B.Cu")
		(net "HDD_PRSNT4")
	)
	(segment
		(start 11.350752 -211.768182)
		(end 11.781282 -212.198712)
		(width 0.14605)
		(layer "In2.Cu")
		(net "HDD_PRSNT4")
	)
	(segment
		(start 12.211304 -395.760702)
		(end 12.108688 -395.863064)
		(width 0.14605)
		(layer "In2.Cu")
		(net "HDD_PRSNT4")
	)
	(segment
		(start 12.835636 -267.90142)
		(end 12.83589 -267.901674)
		(width 0.14605)
		(layer "In2.Cu")
		(net "HDD_PRSNT4")
	)
	(segment
		(start 12.38885 -204.752956)
		(end 11.350752 -205.791054)
		(width 0.14605)
		(layer "In2.Cu")
		(net "HDD_PRSNT4")
	)
	(segment
		(start 7.385812 -439.146188)
		(end 7.385812 -453.654668)
		(width 0.14605)
		(layer "In2.Cu")
		(net "HDD_PRSNT4")
	)
	(segment
		(start 13.60805 -264.886186)
		(end 12.835636 -265.6586)
		(width 0.14605)
		(layer "In2.Cu")
		(net "HDD_PRSNT4")
	)
	(segment
		(start 7.385812 -453.654668)
		(end 7.689596 -453.958452)
		(width 0.14605)
		(layer "In2.Cu")
		(net "HDD_PRSNT4")
	)
	(segment
		(start 12.38885 -203.868274)
		(end 12.38885 -204.752956)
		(width 0.14605)
		(layer "In2.Cu")
		(net "HDD_PRSNT4")
	)
	(segment
		(start 12.107926 -203.58735)
		(end 12.38885 -203.868274)
		(width 0.14605)
		(layer "In2.Cu")
		(net "HDD_PRSNT4")
	)
	(segment
		(start 12.83589 -267.901674)
		(end 12.83589 -365.973106)
		(width 0.14605)
		(layer "In2.Cu")
		(net "HDD_PRSNT4")
	)
	(segment
		(start 13.2969 -374.980708)
		(end 12.779248 -375.49836)
		(width 0.14605)
		(layer "In2.Cu")
		(net "HDD_PRSNT4")
	)
	(segment
		(start 13.607796 -259.519166)
		(end 13.60805 -259.51942)
		(width 0.14605)
		(layer "In2.Cu")
		(net "HDD_PRSNT4")
	)
	(segment
		(start 11.781282 -212.198712)
		(end 11.781282 -217.4875)
		(width 0.14605)
		(layer "In2.Cu")
		(net "HDD_PRSNT4")
	)
	(segment
		(start 11.93419 -434.59781)
		(end 7.385812 -439.146188)
		(width 0.14605)
		(layer "In2.Cu")
		(net "HDD_PRSNT4")
	)
	(segment
		(start 13.090652 -257.233928)
		(end 13.090652 -258.443476)
		(width 0.14605)
		(layer "In2.Cu")
		(net "HDD_PRSNT4")
	)
	(segment
		(start 11.781282 -217.4875)
		(end 12.527788 -218.234006)
		(width 0.14605)
		(layer "In2.Cu")
		(net "HDD_PRSNT4")
	)
	(segment
		(start 12.527788 -218.234006)
		(end 12.527788 -256.671064)
		(width 0.14605)
		(layer "In2.Cu")
		(net "HDD_PRSNT4")
	)
	(segment
		(start 12.779248 -393.360656)
		(end 12.211304 -393.9286)
		(width 0.14605)
		(layer "In2.Cu")
		(net "HDD_PRSNT4")
	)
	(segment
		(start 12.779248 -375.49836)
		(end 12.779248 -393.360656)
		(width 0.14605)
		(layer "In2.Cu")
		(net "HDD_PRSNT4")
	)
	(segment
		(start 13.2969 -366.434116)
		(end 13.2969 -374.980708)
		(width 0.14605)
		(layer "In2.Cu")
		(net "HDD_PRSNT4")
	)
	(segment
		(start 13.090652 -258.443476)
		(end 13.607796 -258.960874)
		(width 0.14605)
		(layer "In2.Cu")
		(net "HDD_PRSNT4")
	)
	(segment
		(start 12.83589 -365.973106)
		(end 13.2969 -366.434116)
		(width 0.14605)
		(layer "In2.Cu")
		(net "HDD_PRSNT4")
	)
	(segment
		(start 11.187684 -203.086716)
		(end 11.688318 -203.58735)
		(width 0.14605)
		(layer "In2.Cu")
		(net "HDD_PRSNT4")
	)
	(segment
		(start 13.60805 -259.51942)
		(end 13.60805 -264.886186)
		(width 0.14605)
		(layer "In2.Cu")
		(net "HDD_PRSNT4")
	)
	(segment
		(start 11.93419 -414.249108)
		(end 11.93419 -434.59781)
		(width 0.14605)
		(layer "In2.Cu")
		(net "HDD_PRSNT4")
	)
	(segment
		(start 12.211304 -393.9286)
		(end 12.211304 -395.760702)
		(width 0.14605)
		(layer "In2.Cu")
		(net "HDD_PRSNT4")
	)
	(segment
		(start 11.350752 -205.791054)
		(end 11.350752 -211.768182)
		(width 0.14605)
		(layer "In2.Cu")
		(net "HDD_PRSNT4")
	)
	(segment
		(start 12.108688 -395.863064)
		(end 12.108688 -414.07461)
		(width 0.14605)
		(layer "In2.Cu")
		(net "HDD_PRSNT4")
	)
	(segment
		(start 12.527788 -256.671064)
		(end 13.090652 -257.233928)
		(width 0.14605)
		(layer "In2.Cu")
		(net "HDD_PRSNT4")
	)
	(segment
		(start 13.607796 -258.960874)
		(end 13.607796 -259.519166)
		(width 0.14605)
		(layer "In2.Cu")
		(net "HDD_PRSNT4")
	)
	(segment
		(start 12.835636 -265.6586)
		(end 12.835636 -267.90142)
		(width 0.14605)
		(layer "In2.Cu")
		(net "HDD_PRSNT4")
	)
	(segment
		(start 12.108688 -414.07461)
		(end 11.93419 -414.249108)
		(width 0.14605)
		(layer "In2.Cu")
		(net "HDD_PRSNT4")
	)
	(segment
		(start 11.688318 -203.58735)
		(end 12.107926 -203.58735)
		(width 0.14605)
		(layer "In2.Cu")
		(net "HDD_PRSNT4")
	)
	(segment
		(start 231.262428 -377.738132)
		(end 231.262428 -139.210034)
		(width 0.14605)
		(layer "In5.Cu")
		(net "HDD_PRSNT4")
	)
	(segment
		(start 15.739618 -467.077298)
		(end 17.428972 -468.766652)
		(width 0.14605)
		(layer "In5.Cu")
		(net "HDD_PRSNT4")
	)
	(segment
		(start 207.9752 -68.3387)
		(end 215.8873 -68.3387)
		(width 0.14605)
		(layer "In5.Cu")
		(net "HDD_PRSNT4")
	)
	(segment
		(start 201.040746 -81.8007)
		(end 201.040746 -75.273154)
		(width 0.14605)
		(layer "In5.Cu")
		(net "HDD_PRSNT4")
	)
	(segment
		(start 201.040746 -75.273154)
		(end 207.9752 -68.3387)
		(width 0.14605)
		(layer "In5.Cu")
		(net "HDD_PRSNT4")
	)
	(segment
		(start 195.65366 -103.601266)
		(end 195.65366 -87.187786)
		(width 0.14605)
		(layer "In5.Cu")
		(net "HDD_PRSNT4")
	)
	(segment
		(start 10.865104 -462.748122)
		(end 15.19428 -467.077298)
		(width 0.14605)
		(layer "In5.Cu")
		(net "HDD_PRSNT4")
	)
	(segment
		(start 34.263076 -468.62365)
		(end 140.37691 -468.62365)
		(width 0.14605)
		(layer "In5.Cu")
		(net "HDD_PRSNT4")
	)
	(segment
		(start 7.600442 -455.245216)
		(end 8.94461 -456.589384)
		(width 0.14605)
		(layer "In5.Cu")
		(net "HDD_PRSNT4")
	)
	(segment
		(start 7.689596 -453.958452)
		(end 7.600442 -454.047606)
		(width 0.14605)
		(layer "In5.Cu")
		(net "HDD_PRSNT4")
	)
	(segment
		(start 7.600442 -454.047606)
		(end 7.600442 -455.245216)
		(width 0.14605)
		(layer "In5.Cu")
		(net "HDD_PRSNT4")
	)
	(segment
		(start 215.8873 -68.3387)
		(end 217.0176 -67.2084)
		(width 0.14605)
		(layer "In5.Cu")
		(net "HDD_PRSNT4")
	)
	(segment
		(start 140.37691 -468.62365)
		(end 231.262428 -377.738132)
		(width 0.14605)
		(layer "In5.Cu")
		(net "HDD_PRSNT4")
	)
	(segment
		(start 231.262428 -139.210034)
		(end 195.65366 -103.601266)
		(width 0.14605)
		(layer "In5.Cu")
		(net "HDD_PRSNT4")
	)
	(segment
		(start 17.428972 -468.766652)
		(end 34.120074 -468.766652)
		(width 0.14605)
		(layer "In5.Cu")
		(net "HDD_PRSNT4")
	)
	(segment
		(start 15.19428 -467.077298)
		(end 15.739618 -467.077298)
		(width 0.14605)
		(layer "In5.Cu")
		(net "HDD_PRSNT4")
	)
	(segment
		(start 34.120074 -468.766652)
		(end 34.263076 -468.62365)
		(width 0.14605)
		(layer "In5.Cu")
		(net "HDD_PRSNT4")
	)
	(segment
		(start 195.65366 -87.187786)
		(end 201.040746 -81.8007)
		(width 0.14605)
		(layer "In5.Cu")
		(net "HDD_PRSNT4")
	)
	(segment
		(start 10.865104 -459.3971)
		(end 10.865104 -462.748122)
		(width 0.14605)
		(layer "In5.Cu")
		(net "HDD_PRSNT4")
	)
	(segment
		(start 8.94461 -456.589384)
		(end 8.94461 -457.476606)
		(width 0.14605)
		(layer "In5.Cu")
		(net "HDD_PRSNT4")
	)
	(segment
		(start 8.94461 -457.476606)
		(end 10.865104 -459.3971)
		(width 0.14605)
		(layer "In5.Cu")
		(net "HDD_PRSNT4")
	)
	(segment
		(start 224.2566 -61.744606)
		(end 224.124774 -61.612272)
		(width 0.09525)
		(layer "F.Cu")
		(net "SAS2X28_B_HDD4_TX_-")
	)
	(segment
		(start 223.97847 -61.55182)
		(end 223.621346 -61.55182)
		(width 0.09525)
		(layer "F.Cu")
		(net "SAS2X28_B_HDD4_TX_-")
	)
	(segment
		(start 4.727194 -102.499922)
		(end 4.72567 -102.498398)
		(width 0.09525)
		(layer "F.Cu")
		(net "SAS2X28_B_HDD4_TX_-")
	)
	(segment
		(start 223.314768 -61.662056)
		(end 223.031812 -61.945012)
		(width 0.09525)
		(layer "F.Cu")
		(net "SAS2X28_B_HDD4_TX_-")
	)
	(segment
		(start 224.360994 -61.789818)
		(end 224.357692 -61.786516)
		(width 0.09525)
		(layer "F.Cu")
		(net "SAS2X28_B_HDD4_TX_-")
	)
	(segment
		(start 6.452108 -102.160324)
		(end 5.547106 -102.160324)
		(width 0.09525)
		(layer "F.Cu")
		(net "SAS2X28_B_HDD4_TX_-")
	)
	(segment
		(start 225.399854 -61.789818)
		(end 224.360994 -61.789818)
		(width 0.09525)
		(layer "F.Cu")
		(net "SAS2X28_B_HDD4_TX_-")
	)
	(segment
		(start 223.621346 -61.55182)
		(end 223.57842 -61.552836)
		(width 0.09525)
		(layer "F.Cu")
		(net "SAS2X28_B_HDD4_TX_-")
	)
	(segment
		(start 4.72567 -102.498398)
		(end 3.192526 -102.498398)
		(width 0.09525)
		(layer "F.Cu")
		(net "SAS2X28_B_HDD4_TX_-")
	)
	(via
		(at 6.679946 -102.457504)
		(size 0.5588)
		(drill 0.3048)
		(layers "F.Cu" "B.Cu")
		(net "SAS2X28_B_HDD4_TX_-")
	)
	(via
		(at 223.031812 -61.945012)
		(size 0.5588)
		(drill 0.3048)
		(layers "F.Cu" "B.Cu")
		(net "SAS2X28_B_HDD4_TX_-")
	)
	(arc
		(start 223.57842 -61.552836)
		(mid 223.435728 -61.581219)
		(end 223.314768 -61.662056)
		(width 0.09525)
		(layer "F.Cu")
		(net "SAS2X28_B_HDD4_TX_-")
	)
	(arc
		(start 5.547106 -102.160324)
		(mid 5.356299 -102.198278)
		(end 5.194554 -102.306374)
		(width 0.09525)
		(layer "F.Cu")
		(net "SAS2X28_B_HDD4_TX_-")
	)
	(arc
		(start 224.357692 -61.786516)
		(mid 224.302968 -61.775631)
		(end 224.2566 -61.744606)
		(width 0.09525)
		(layer "F.Cu")
		(net "SAS2X28_B_HDD4_TX_-")
	)
	(arc
		(start 5.194554 -102.306374)
		(mid 4.980127 -102.449649)
		(end 4.727194 -102.499922)
		(width 0.09525)
		(layer "F.Cu")
		(net "SAS2X28_B_HDD4_TX_-")
	)
	(arc
		(start 6.530086 -102.192582)
		(mid 6.494309 -102.168677)
		(end 6.452108 -102.160324)
		(width 0.09525)
		(layer "F.Cu")
		(net "SAS2X28_B_HDD4_TX_-")
	)
	(arc
		(start 6.679946 -102.457504)
		(mid 6.639887 -102.305316)
		(end 6.530086 -102.192582)
		(width 0.09525)
		(layer "F.Cu")
		(net "SAS2X28_B_HDD4_TX_-")
	)
	(arc
		(start 224.124774 -61.612272)
		(mid 224.057634 -61.567504)
		(end 223.97847 -61.55182)
		(width 0.09525)
		(layer "F.Cu")
		(net "SAS2X28_B_HDD4_TX_-")
	)
	(segment
		(start 18.389346 -91.10091)
		(end 18.389346 -74.732642)
		(width 0.09525)
		(layer "B.Cu")
		(net "SAS2X28_B_HDD4_TX_-")
	)
	(segment
		(start 8.261096 -101.997256)
		(end 8.621776 -101.63683)
		(width 0.09525)
		(layer "B.Cu")
		(net "SAS2X28_B_HDD4_TX_-")
	)
	(segment
		(start 32.067246 -60.7314)
		(end 32.239712 -60.55868)
		(width 0.09525)
		(layer "B.Cu")
		(net "SAS2X28_B_HDD4_TX_-")
	)
	(segment
		(start 33.172146 -60.1726)
		(end 207.330802 -60.1726)
		(width 0.09525)
		(layer "B.Cu")
		(net "SAS2X28_B_HDD4_TX_-")
	)
	(segment
		(start 7.129018 -102.143052)
		(end 7.909814 -102.143052)
		(width 0.09525)
		(layer "B.Cu")
		(net "SAS2X28_B_HDD4_TX_-")
	)
	(segment
		(start 213.32825 -64.90716)
		(end 218.215972 -64.90716)
		(width 0.09525)
		(layer "B.Cu")
		(net "SAS2X28_B_HDD4_TX_-")
	)
	(segment
		(start 8.621776 -101.63683)
		(end 17.846548 -92.412058)
		(width 0.09525)
		(layer "B.Cu")
		(net "SAS2X28_B_HDD4_TX_-")
	)
	(segment
		(start 208.40827 -60.618878)
		(end 212.250782 -64.460882)
		(width 0.09525)
		(layer "B.Cu")
		(net "SAS2X28_B_HDD4_TX_-")
	)
	(segment
		(start 222.742506 -61.65596)
		(end 223.031812 -61.945012)
		(width 0.09525)
		(layer "B.Cu")
		(net "SAS2X28_B_HDD4_TX_-")
	)
	(segment
		(start 18.617946 -74.1807)
		(end 32.067246 -60.7314)
		(width 0.09525)
		(layer "B.Cu")
		(net "SAS2X28_B_HDD4_TX_-")
	)
	(segment
		(start 218.749372 -64.68618)
		(end 221.746572 -61.68898)
		(width 0.09525)
		(layer "B.Cu")
		(net "SAS2X28_B_HDD4_TX_-")
	)
	(segment
		(start 222.065342 -61.5569)
		(end 222.503746 -61.5569)
		(width 0.09525)
		(layer "B.Cu")
		(net "SAS2X28_B_HDD4_TX_-")
	)
	(segment
		(start 6.679946 -102.457504)
		(end 6.899148 -102.238302)
		(width 0.09525)
		(layer "B.Cu")
		(net "SAS2X28_B_HDD4_TX_-")
	)
	(arc
		(start 17.846548 -92.412058)
		(mid 18.248361 -91.810469)
		(end 18.389346 -91.10091)
		(width 0.09525)
		(layer "B.Cu")
		(net "SAS2X28_B_HDD4_TX_-")
	)
	(arc
		(start 222.503746 -61.5569)
		(mid 222.63297 -61.582698)
		(end 222.742506 -61.65596)
		(width 0.09525)
		(layer "B.Cu")
		(net "SAS2X28_B_HDD4_TX_-")
	)
	(arc
		(start 6.899148 -102.238302)
		(mid 7.004613 -102.167832)
		(end 7.129018 -102.143052)
		(width 0.09525)
		(layer "B.Cu")
		(net "SAS2X28_B_HDD4_TX_-")
	)
	(arc
		(start 218.215972 -64.90716)
		(mid 218.504661 -64.849736)
		(end 218.749372 -64.68618)
		(width 0.09525)
		(layer "B.Cu")
		(net "SAS2X28_B_HDD4_TX_-")
	)
	(arc
		(start 32.239712 -60.55868)
		(mid 32.667531 -60.272913)
		(end 33.172146 -60.1726)
		(width 0.09525)
		(layer "B.Cu")
		(net "SAS2X28_B_HDD4_TX_-")
	)
	(arc
		(start 7.909814 -102.143052)
		(mid 7.993309 -102.135953)
		(end 8.074406 -102.114858)
		(width 0.09525)
		(layer "B.Cu")
		(net "SAS2X28_B_HDD4_TX_-")
	)
	(arc
		(start 8.074406 -102.114858)
		(mid 8.174329 -102.0665)
		(end 8.261096 -101.997256)
		(width 0.09525)
		(layer "B.Cu")
		(net "SAS2X28_B_HDD4_TX_-")
	)
	(arc
		(start 221.746572 -61.68898)
		(mid 221.892825 -61.591257)
		(end 222.065342 -61.5569)
		(width 0.09525)
		(layer "B.Cu")
		(net "SAS2X28_B_HDD4_TX_-")
	)
	(arc
		(start 207.330802 -60.1726)
		(mid 207.913914 -60.288588)
		(end 208.40827 -60.618878)
		(width 0.09525)
		(layer "B.Cu")
		(net "SAS2X28_B_HDD4_TX_-")
	)
	(arc
		(start 18.389346 -74.732642)
		(mid 18.448761 -74.433942)
		(end 18.617946 -74.1807)
		(width 0.09525)
		(layer "B.Cu")
		(net "SAS2X28_B_HDD4_TX_-")
	)
	(arc
		(start 212.250782 -64.460882)
		(mid 212.745129 -64.791194)
		(end 213.32825 -64.90716)
		(width 0.09525)
		(layer "B.Cu")
		(net "SAS2X28_B_HDD4_TX_-")
	)
	(segment
		(start 224.22104 -61.064648)
		(end 224.11055 -61.175392)
		(width 0.09525)
		(layer "F.Cu")
		(net "SAS2X28_B_HDD4_TX_+")
	)
	(segment
		(start 3.19405 -101.499924)
		(end 3.192526 -101.4984)
		(width 0.09525)
		(layer "F.Cu")
		(net "SAS2X28_B_HDD4_TX_+")
	)
	(segment
		(start 6.452108 -101.830124)
		(end 5.612384 -101.830124)
		(width 0.09525)
		(layer "F.Cu")
		(net "SAS2X28_B_HDD4_TX_+")
	)
	(segment
		(start 223.05264 -61.007244)
		(end 223.031812 -60.986162)
		(width 0.09525)
		(layer "F.Cu")
		(net "SAS2X28_B_HDD4_TX_+")
	)
	(segment
		(start 4.815332 -101.499924)
		(end 3.19405 -101.499924)
		(width 0.09525)
		(layer "F.Cu")
		(net "SAS2X28_B_HDD4_TX_+")
	)
	(segment
		(start 223.999044 -61.22162)
		(end 223.570546 -61.22162)
		(width 0.09525)
		(layer "F.Cu")
		(net "SAS2X28_B_HDD4_TX_+")
	)
	(segment
		(start 224.221294 -61.06414)
		(end 224.22104 -61.064648)
		(width 0.09525)
		(layer "F.Cu")
		(net "SAS2X28_B_HDD4_TX_+")
	)
	(segment
		(start 224.412048 -60.989972)
		(end 224.408746 -60.98667)
		(width 0.09525)
		(layer "F.Cu")
		(net "SAS2X28_B_HDD4_TX_+")
	)
	(segment
		(start 6.679946 -101.498654)
		(end 6.679946 -101.602286)
		(width 0.09525)
		(layer "F.Cu")
		(net "SAS2X28_B_HDD4_TX_+")
	)
	(segment
		(start 225.399854 -60.989972)
		(end 224.412048 -60.989972)
		(width 0.09525)
		(layer "F.Cu")
		(net "SAS2X28_B_HDD4_TX_+")
	)
	(segment
		(start 5.293868 -101.698044)
		(end 5.293614 -101.698044)
		(width 0.09525)
		(layer "F.Cu")
		(net "SAS2X28_B_HDD4_TX_+")
	)
	(via
		(at 6.679946 -101.498654)
		(size 0.5588)
		(drill 0.3048)
		(layers "F.Cu" "B.Cu")
		(net "SAS2X28_B_HDD4_TX_+")
	)
	(via
		(at 223.031812 -60.986162)
		(size 0.5588)
		(drill 0.3048)
		(layers "F.Cu" "B.Cu")
		(net "SAS2X28_B_HDD4_TX_+")
	)
	(arc
		(start 223.570546 -61.22162)
		(mid 223.29026 -61.165961)
		(end 223.05264 -61.007244)
		(width 0.09525)
		(layer "F.Cu")
		(net "SAS2X28_B_HDD4_TX_+")
	)
	(arc
		(start 5.293614 -101.698044)
		(mid 5.074176 -101.55142)
		(end 4.815332 -101.499924)
		(width 0.09525)
		(layer "F.Cu")
		(net "SAS2X28_B_HDD4_TX_+")
	)
	(arc
		(start 224.408746 -60.98667)
		(mid 224.307311 -61.006753)
		(end 224.221294 -61.06414)
		(width 0.09525)
		(layer "F.Cu")
		(net "SAS2X28_B_HDD4_TX_+")
	)
	(arc
		(start 6.679946 -101.602286)
		(mid 6.613214 -101.763392)
		(end 6.452108 -101.830124)
		(width 0.09525)
		(layer "F.Cu")
		(net "SAS2X28_B_HDD4_TX_+")
	)
	(arc
		(start 224.11055 -61.175392)
		(mid 224.059391 -61.209576)
		(end 223.999044 -61.22162)
		(width 0.09525)
		(layer "F.Cu")
		(net "SAS2X28_B_HDD4_TX_+")
	)
	(arc
		(start 5.612384 -101.830124)
		(mid 5.440002 -101.795741)
		(end 5.293868 -101.698044)
		(width 0.09525)
		(layer "F.Cu")
		(net "SAS2X28_B_HDD4_TX_+")
	)
	(segment
		(start 18.40738 -73.92416)
		(end 31.871666 -60.459874)
		(width 0.09525)
		(layer "B.Cu")
		(net "SAS2X28_B_HDD4_TX_+")
	)
	(segment
		(start 222.13697 -61.2267)
		(end 222.554546 -61.2267)
		(width 0.09525)
		(layer "B.Cu")
		(net "SAS2X28_B_HDD4_TX_+")
	)
	(segment
		(start 6.994144 -101.812852)
		(end 7.908544 -101.812852)
		(width 0.09525)
		(layer "B.Cu")
		(net "SAS2X28_B_HDD4_TX_+")
	)
	(segment
		(start 31.871666 -60.459874)
		(end 32.006032 -60.325254)
		(width 0.09525)
		(layer "B.Cu")
		(net "SAS2X28_B_HDD4_TX_+")
	)
	(segment
		(start 18.059146 -91.10091)
		(end 18.059146 -74.7649)
		(width 0.09525)
		(layer "B.Cu")
		(net "SAS2X28_B_HDD4_TX_+")
	)
	(segment
		(start 33.172146 -59.8424)
		(end 207.330802 -59.8424)
		(width 0.09525)
		(layer "B.Cu")
		(net "SAS2X28_B_HDD4_TX_+")
	)
	(segment
		(start 8.02767 -101.763576)
		(end 17.612868 -92.178378)
		(width 0.09525)
		(layer "B.Cu")
		(net "SAS2X28_B_HDD4_TX_+")
	)
	(segment
		(start 213.32825 -64.57696)
		(end 218.215464 -64.57696)
		(width 0.09525)
		(layer "B.Cu")
		(net "SAS2X28_B_HDD4_TX_+")
	)
	(segment
		(start 218.515946 -64.4525)
		(end 221.462346 -61.5061)
		(width 0.09525)
		(layer "B.Cu")
		(net "SAS2X28_B_HDD4_TX_+")
	)
	(segment
		(start 208.64195 -60.385198)
		(end 212.484462 -64.227202)
		(width 0.09525)
		(layer "B.Cu")
		(net "SAS2X28_B_HDD4_TX_+")
	)
	(segment
		(start 222.903034 -61.11494)
		(end 223.031812 -60.986162)
		(width 0.09525)
		(layer "B.Cu")
		(net "SAS2X28_B_HDD4_TX_+")
	)
	(arc
		(start 218.215464 -64.57696)
		(mid 218.378082 -64.544613)
		(end 218.515946 -64.4525)
		(width 0.09525)
		(layer "B.Cu")
		(net "SAS2X28_B_HDD4_TX_+")
	)
	(arc
		(start 222.654622 -61.21781)
		(mid 222.789052 -61.19107)
		(end 222.903034 -61.11494)
		(width 0.09525)
		(layer "B.Cu")
		(net "SAS2X28_B_HDD4_TX_+")
	)
	(arc
		(start 18.059146 -74.7649)
		(mid 18.149651 -74.309899)
		(end 18.40738 -73.92416)
		(width 0.09525)
		(layer "B.Cu")
		(net "SAS2X28_B_HDD4_TX_+")
	)
	(arc
		(start 32.006032 -60.325254)
		(mid 32.541065 -59.96785)
		(end 33.172146 -59.8424)
		(width 0.09525)
		(layer "B.Cu")
		(net "SAS2X28_B_HDD4_TX_+")
	)
	(arc
		(start 17.612868 -92.178378)
		(mid 17.94318 -91.684031)
		(end 18.059146 -91.10091)
		(width 0.09525)
		(layer "B.Cu")
		(net "SAS2X28_B_HDD4_TX_+")
	)
	(arc
		(start 212.484462 -64.227202)
		(mid 212.87158 -64.485959)
		(end 213.32825 -64.57696)
		(width 0.09525)
		(layer "B.Cu")
		(net "SAS2X28_B_HDD4_TX_+")
	)
	(arc
		(start 7.908544 -101.812852)
		(mid 7.973003 -101.800048)
		(end 8.02767 -101.763576)
		(width 0.09525)
		(layer "B.Cu")
		(net "SAS2X28_B_HDD4_TX_+")
	)
	(arc
		(start 6.679946 -101.498654)
		(mid 6.771972 -101.720826)
		(end 6.994144 -101.812852)
		(width 0.09525)
		(layer "B.Cu")
		(net "SAS2X28_B_HDD4_TX_+")
	)
	(arc
		(start 207.330802 -59.8424)
		(mid 208.040344 -59.983425)
		(end 208.64195 -60.385198)
		(width 0.09525)
		(layer "B.Cu")
		(net "SAS2X28_B_HDD4_TX_+")
	)
	(arc
		(start 222.554546 -61.2267)
		(mid 222.604781 -61.224465)
		(end 222.654622 -61.21781)
		(width 0.09525)
		(layer "B.Cu")
		(net "SAS2X28_B_HDD4_TX_+")
	)
	(arc
		(start 221.462346 -61.5061)
		(mid 221.771866 -61.299285)
		(end 222.13697 -61.2267)
		(width 0.09525)
		(layer "B.Cu")
		(net "SAS2X28_B_HDD4_TX_+")
	)
	(segment
		(start 213.920832 -57.902348)
		(end 213.720426 -57.99963)
		(width 0.09525)
		(layer "F.Cu")
		(net "SAS2X28_A_HDD4_RX_-")
	)
	(segment
		(start 8.038846 -379.7173)
		(end 8.038846 -379.8697)
		(width 0.09525)
		(layer "F.Cu")
		(net "SAS2X28_A_HDD4_RX_-")
	)
	(segment
		(start 216.631012 -57.330848)
		(end 216.531444 -57.383172)
		(width 0.09525)
		(layer "F.Cu")
		(net "SAS2X28_A_HDD4_RX_-")
	)
	(segment
		(start 9.067038 -378.649992)
		(end 9.005062 -378.715016)
		(width 0.09525)
		(layer "F.Cu")
		(net "SAS2X28_A_HDD4_RX_-")
	)
	(segment
		(start 216.407746 -57.410096)
		(end 216.175082 -57.410096)
		(width 0.09525)
		(layer "F.Cu")
		(net "SAS2X28_A_HDD4_RX_-")
	)
	(segment
		(start 19.152362 -368.56416)
		(end 17.035018 -370.68125)
		(width 0.09525)
		(layer "F.Cu")
		(net "SAS2X28_A_HDD4_RX_-")
	)
	(segment
		(start 17.035018 -370.68125)
		(end 9.644634 -378.071888)
		(width 0.09525)
		(layer "F.Cu")
		(net "SAS2X28_A_HDD4_RX_-")
	)
	(segment
		(start 9.130284 -378.586238)
		(end 9.130284 -378.586492)
		(width 0.09525)
		(layer "F.Cu")
		(net "SAS2X28_A_HDD4_RX_-")
	)
	(segment
		(start 213.715346 -58.001916)
		(end 196.438774 -66.403474)
		(width 0.09525)
		(layer "F.Cu")
		(net "SAS2X28_A_HDD4_RX_-")
	)
	(segment
		(start 21.293074 -366.423448)
		(end 19.152362 -368.56416)
		(width 0.09525)
		(layer "F.Cu")
		(net "SAS2X28_A_HDD4_RX_-")
	)
	(segment
		(start 8.353044 -379.060964)
		(end 8.3439 -379.069854)
		(width 0.09525)
		(layer "F.Cu")
		(net "SAS2X28_A_HDD4_RX_-")
	)
	(segment
		(start 8.658098 -378.888244)
		(end 8.657844 -378.887736)
		(width 0.09525)
		(layer "F.Cu")
		(net "SAS2X28_A_HDD4_RX_-")
	)
	(segment
		(start 195.422012 -67.480942)
		(end 82.89798 -276.595586)
		(width 0.09525)
		(layer "F.Cu")
		(net "SAS2X28_A_HDD4_RX_-")
	)
	(segment
		(start 213.945216 -57.894728)
		(end 213.920832 -57.902348)
		(width 0.09525)
		(layer "F.Cu")
		(net "SAS2X28_A_HDD4_RX_-")
	)
	(segment
		(start 54.545738 -328.977498)
		(end 54.500526 -329.022964)
		(width 0.09525)
		(layer "F.Cu")
		(net "SAS2X28_A_HDD4_RX_-")
	)
	(segment
		(start 54.792372 -328.730864)
		(end 54.545738 -328.977498)
		(width 0.09525)
		(layer "F.Cu")
		(net "SAS2X28_A_HDD4_RX_-")
	)
	(segment
		(start 216.450418 -57.40654)
		(end 216.407746 -57.410096)
		(width 0.09525)
		(layer "F.Cu")
		(net "SAS2X28_A_HDD4_RX_-")
	)
	(segment
		(start 7.886192 -380.238254)
		(end 7.746746 -380.3777)
		(width 0.09525)
		(layer "F.Cu")
		(net "SAS2X28_A_HDD4_RX_-")
	)
	(segment
		(start 217.354912 -57.130696)
		(end 216.920572 -57.225438)
		(width 0.09525)
		(layer "F.Cu")
		(net "SAS2X28_A_HDD4_RX_-")
	)
	(segment
		(start 216.132664 -57.413906)
		(end 214.813896 -57.659778)
		(width 0.09525)
		(layer "F.Cu")
		(net "SAS2X28_A_HDD4_RX_-")
	)
	(segment
		(start 9.644634 -378.071888)
		(end 9.130284 -378.586238)
		(width 0.09525)
		(layer "F.Cu")
		(net "SAS2X28_A_HDD4_RX_-")
	)
	(segment
		(start 8.3439 -379.069854)
		(end 8.2804 -379.133354)
		(width 0.09525)
		(layer "F.Cu")
		(net "SAS2X28_A_HDD4_RX_-")
	)
	(segment
		(start 82.89798 -276.595586)
		(end 54.979824 -328.478642)
		(width 0.09525)
		(layer "F.Cu")
		(net "SAS2X28_A_HDD4_RX_-")
	)
	(segment
		(start 21.627846 -362.629196)
		(end 21.627846 -365.61522)
		(width 0.09525)
		(layer "F.Cu")
		(net "SAS2X28_A_HDD4_RX_-")
	)
	(segment
		(start 54.500526 -329.022964)
		(end 22.146514 -361.376976)
		(width 0.09525)
		(layer "F.Cu")
		(net "SAS2X28_A_HDD4_RX_-")
	)
	(segment
		(start 8.356346 -379.05817)
		(end 8.353044 -379.060964)
		(width 0.09525)
		(layer "F.Cu")
		(net "SAS2X28_A_HDD4_RX_-")
	)
	(segment
		(start 213.94547 -57.894982)
		(end 213.945216 -57.894728)
		(width 0.09525)
		(layer "F.Cu")
		(net "SAS2X28_A_HDD4_RX_-")
	)
	(segment
		(start 9.130284 -378.586492)
		(end 9.067038 -378.649992)
		(width 0.09525)
		(layer "F.Cu")
		(net "SAS2X28_A_HDD4_RX_-")
	)
	(segment
		(start 213.720426 -57.99963)
		(end 213.715346 -58.001916)
		(width 0.09525)
		(layer "F.Cu")
		(net "SAS2X28_A_HDD4_RX_-")
	)
	(via
		(at 7.746746 -380.3777)
		(size 0.5588)
		(drill 0.3048)
		(layers "F.Cu" "B.Cu")
		(net "SAS2X28_A_HDD4_RX_-")
	)
	(arc
		(start 21.627846 -365.61522)
		(mid 21.54084 -366.052627)
		(end 21.293074 -366.423448)
		(width 0.09525)
		(layer "F.Cu")
		(net "SAS2X28_A_HDD4_RX_-")
	)
	(arc
		(start 216.531444 -57.383172)
		(mid 216.492103 -57.398917)
		(end 216.450418 -57.40654)
		(width 0.09525)
		(layer "F.Cu")
		(net "SAS2X28_A_HDD4_RX_-")
	)
	(arc
		(start 8.657844 -378.887736)
		(mid 8.65759 -378.887863)
		(end 8.657336 -378.88799)
		(width 0.09525)
		(layer "F.Cu")
		(net "SAS2X28_A_HDD4_RX_-")
	)
	(arc
		(start 8.657336 -378.88799)
		(mid 8.49613 -378.954136)
		(end 8.356346 -379.05817)
		(width 0.09525)
		(layer "F.Cu")
		(net "SAS2X28_A_HDD4_RX_-")
	)
	(arc
		(start 214.750396 -57.672224)
		(mid 214.346411 -57.778104)
		(end 213.94547 -57.894982)
		(width 0.09525)
		(layer "F.Cu")
		(net "SAS2X28_A_HDD4_RX_-")
	)
	(arc
		(start 8.2804 -379.133354)
		(mid 8.101603 -379.401315)
		(end 8.038846 -379.7173)
		(width 0.09525)
		(layer "F.Cu")
		(net "SAS2X28_A_HDD4_RX_-")
	)
	(arc
		(start 8.038846 -379.8697)
		(mid 7.999171 -380.069158)
		(end 7.886192 -380.238254)
		(width 0.09525)
		(layer "F.Cu")
		(net "SAS2X28_A_HDD4_RX_-")
	)
	(arc
		(start 216.920572 -57.225438)
		(mid 216.77225 -57.268411)
		(end 216.631012 -57.330848)
		(width 0.09525)
		(layer "F.Cu")
		(net "SAS2X28_A_HDD4_RX_-")
	)
	(arc
		(start 196.438774 -66.403474)
		(mid 195.859213 -66.875036)
		(end 195.422012 -67.480942)
		(width 0.09525)
		(layer "F.Cu")
		(net "SAS2X28_A_HDD4_RX_-")
	)
	(arc
		(start 54.979824 -328.478642)
		(mid 54.895349 -328.611629)
		(end 54.792372 -328.730864)
		(width 0.09525)
		(layer "F.Cu")
		(net "SAS2X28_A_HDD4_RX_-")
	)
	(arc
		(start 22.146514 -361.376976)
		(mid 21.762654 -361.951513)
		(end 21.627846 -362.629196)
		(width 0.09525)
		(layer "F.Cu")
		(net "SAS2X28_A_HDD4_RX_-")
	)
	(arc
		(start 9.005062 -378.715016)
		(mid 8.840286 -378.819067)
		(end 8.658098 -378.888244)
		(width 0.09525)
		(layer "F.Cu")
		(net "SAS2X28_A_HDD4_RX_-")
	)
	(arc
		(start 216.175082 -57.410096)
		(mid 216.153786 -57.411028)
		(end 216.132664 -57.413906)
		(width 0.09525)
		(layer "F.Cu")
		(net "SAS2X28_A_HDD4_RX_-")
	)
	(arc
		(start 214.813896 -57.659778)
		(mid 214.781992 -57.665215)
		(end 214.750396 -57.672224)
		(width 0.09525)
		(layer "F.Cu")
		(net "SAS2X28_A_HDD4_RX_-")
	)
	(segment
		(start 6.808216 -376.59183)
		(end 6.528816 -376.31243)
		(width 0.09525)
		(layer "B.Cu")
		(net "SAS2X28_A_HDD4_RX_-")
	)
	(segment
		(start 6.121146 -376.1359)
		(end 5.583428 -376.1359)
		(width 0.09525)
		(layer "B.Cu")
		(net "SAS2X28_A_HDD4_RX_-")
	)
	(segment
		(start 5.460746 -376.1867)
		(end 5.327396 -376.32005)
		(width 0.09525)
		(layer "B.Cu")
		(net "SAS2X28_A_HDD4_RX_-")
	)
	(segment
		(start 4.890516 -376.498866)
		(end 2.811526 -376.498866)
		(width 0.09525)
		(layer "B.Cu")
		(net "SAS2X28_A_HDD4_RX_-")
	)
	(segment
		(start 4.89204 -376.50039)
		(end 4.890516 -376.498866)
		(width 0.09525)
		(layer "B.Cu")
		(net "SAS2X28_A_HDD4_RX_-")
	)
	(segment
		(start 7.283704 -377.501912)
		(end 7.115048 -377.333256)
		(width 0.09525)
		(layer "B.Cu")
		(net "SAS2X28_A_HDD4_RX_-")
	)
	(segment
		(start 6.528816 -376.31243)
		(end 6.515862 -376.299222)
		(width 0.09525)
		(layer "B.Cu")
		(net "SAS2X28_A_HDD4_RX_-")
	)
	(segment
		(start 8.000746 -379.764544)
		(end 8.000746 -378.4727)
		(width 0.09525)
		(layer "B.Cu")
		(net "SAS2X28_A_HDD4_RX_-")
	)
	(segment
		(start 7.821422 -378.039376)
		(end 7.283704 -377.501912)
		(width 0.09525)
		(layer "B.Cu")
		(net "SAS2X28_A_HDD4_RX_-")
	)
	(segment
		(start 6.897116 -376.80646)
		(end 6.897116 -376.806206)
		(width 0.09525)
		(layer "B.Cu")
		(net "SAS2X28_A_HDD4_RX_-")
	)
	(arc
		(start 5.583428 -376.1359)
		(mid 5.517039 -376.149106)
		(end 5.460746 -376.1867)
		(width 0.09525)
		(layer "B.Cu")
		(net "SAS2X28_A_HDD4_RX_-")
	)
	(arc
		(start 6.515862 -376.299222)
		(mid 6.33475 -376.1783)
		(end 6.121146 -376.1359)
		(width 0.09525)
		(layer "B.Cu")
		(net "SAS2X28_A_HDD4_RX_-")
	)
	(arc
		(start 7.746746 -380.3777)
		(mid 7.934717 -380.096382)
		(end 8.000746 -379.764544)
		(width 0.09525)
		(layer "B.Cu")
		(net "SAS2X28_A_HDD4_RX_-")
	)
	(arc
		(start 5.327396 -376.32005)
		(mid 5.127653 -376.453514)
		(end 4.89204 -376.50039)
		(width 0.09525)
		(layer "B.Cu")
		(net "SAS2X28_A_HDD4_RX_-")
	)
	(arc
		(start 6.897116 -376.806206)
		(mid 6.873963 -376.690187)
		(end 6.808216 -376.59183)
		(width 0.09525)
		(layer "B.Cu")
		(net "SAS2X28_A_HDD4_RX_-")
	)
	(arc
		(start 8.000746 -378.4727)
		(mid 7.954194 -378.238196)
		(end 7.821422 -378.039376)
		(width 0.09525)
		(layer "B.Cu")
		(net "SAS2X28_A_HDD4_RX_-")
	)
	(arc
		(start 7.115048 -377.333256)
		(mid 6.953689 -377.091531)
		(end 6.897116 -376.80646)
		(width 0.09525)
		(layer "B.Cu")
		(net "SAS2X28_A_HDD4_RX_-")
	)
	(segment
		(start 8.57758 -379.303534)
		(end 8.579358 -379.30201)
		(width 0.09525)
		(layer "F.Cu")
		(net "SAS2X28_A_HDD4_RX_+")
	)
	(segment
		(start 55.300118 -328.580496)
		(end 55.300626 -328.579988)
		(width 0.09525)
		(layer "F.Cu")
		(net "SAS2X28_A_HDD4_RX_+")
	)
	(segment
		(start 8.661146 -380.3777)
		(end 8.5217 -380.238254)
		(width 0.09525)
		(layer "F.Cu")
		(net "SAS2X28_A_HDD4_RX_+")
	)
	(segment
		(start 195.713604 -67.636898)
		(end 195.738242 -67.591178)
		(width 0.09525)
		(layer "F.Cu")
		(net "SAS2X28_A_HDD4_RX_+")
	)
	(segment
		(start 217.155522 -58.019696)
		(end 217.354912 -58.019696)
		(width 0.09525)
		(layer "F.Cu")
		(net "SAS2X28_A_HDD4_RX_+")
	)
	(segment
		(start 55.270654 -328.635106)
		(end 55.300118 -328.580496)
		(width 0.09525)
		(layer "F.Cu")
		(net "SAS2X28_A_HDD4_RX_+")
	)
	(segment
		(start 54.892194 -329.098402)
		(end 55.026052 -328.964544)
		(width 0.09525)
		(layer "F.Cu")
		(net "SAS2X28_A_HDD4_RX_+")
	)
	(segment
		(start 22.380194 -361.610402)
		(end 54.73446 -329.256136)
		(width 0.09525)
		(layer "F.Cu")
		(net "SAS2X28_A_HDD4_RX_+")
	)
	(segment
		(start 21.958046 -365.615474)
		(end 21.958046 -362.62945)
		(width 0.09525)
		(layer "F.Cu")
		(net "SAS2X28_A_HDD4_RX_+")
	)
	(segment
		(start 8.369046 -379.8697)
		(end 8.369046 -379.7173)
		(width 0.09525)
		(layer "F.Cu")
		(net "SAS2X28_A_HDD4_RX_+")
	)
	(segment
		(start 213.86038 -58.298842)
		(end 214.04199 -58.210704)
		(width 0.09525)
		(layer "F.Cu")
		(net "SAS2X28_A_HDD4_RX_+")
	)
	(segment
		(start 54.73446 -329.256136)
		(end 54.779672 -329.21067)
		(width 0.09525)
		(layer "F.Cu")
		(net "SAS2X28_A_HDD4_RX_+")
	)
	(segment
		(start 55.300626 -328.579988)
		(end 83.189064 -276.75205)
		(width 0.09525)
		(layer "F.Cu")
		(net "SAS2X28_A_HDD4_RX_+")
	)
	(segment
		(start 195.71335 -67.63766)
		(end 195.713604 -67.636898)
		(width 0.09525)
		(layer "F.Cu")
		(net "SAS2X28_A_HDD4_RX_+")
	)
	(segment
		(start 8.51408 -379.367034)
		(end 8.57758 -379.303534)
		(width 0.09525)
		(layer "F.Cu")
		(net "SAS2X28_A_HDD4_RX_+")
	)
	(segment
		(start 214.829898 -57.992772)
		(end 216.18448 -57.740296)
		(width 0.09525)
		(layer "F.Cu")
		(net "SAS2X28_A_HDD4_RX_+")
	)
	(segment
		(start 9.208262 -378.975366)
		(end 9.300464 -378.883418)
		(width 0.09525)
		(layer "F.Cu")
		(net "SAS2X28_A_HDD4_RX_+")
	)
	(segment
		(start 54.779672 -329.21067)
		(end 54.892194 -329.098402)
		(width 0.09525)
		(layer "F.Cu")
		(net "SAS2X28_A_HDD4_RX_+")
	)
	(segment
		(start 196.518022 -66.73215)
		(end 213.8553 -58.301128)
		(width 0.09525)
		(layer "F.Cu")
		(net "SAS2X28_A_HDD4_RX_+")
	)
	(segment
		(start 216.18448 -57.740296)
		(end 216.480898 -57.740296)
		(width 0.09525)
		(layer "F.Cu")
		(net "SAS2X28_A_HDD4_RX_+")
	)
	(segment
		(start 213.8553 -58.301128)
		(end 213.86038 -58.298842)
		(width 0.09525)
		(layer "F.Cu")
		(net "SAS2X28_A_HDD4_RX_+")
	)
	(segment
		(start 9.300464 -378.883418)
		(end 21.5265 -366.657128)
		(width 0.09525)
		(layer "F.Cu")
		(net "SAS2X28_A_HDD4_RX_+")
	)
	(segment
		(start 83.189064 -276.75205)
		(end 195.71335 -67.63766)
		(width 0.09525)
		(layer "F.Cu")
		(net "SAS2X28_A_HDD4_RX_+")
	)
	(via
		(at 8.661146 -380.3777)
		(size 0.5588)
		(drill 0.3048)
		(layers "F.Cu" "B.Cu")
		(net "SAS2X28_A_HDD4_RX_+")
	)
	(arc
		(start 8.369046 -379.7173)
		(mid 8.406748 -379.527757)
		(end 8.51408 -379.367034)
		(width 0.09525)
		(layer "F.Cu")
		(net "SAS2X28_A_HDD4_RX_+")
	)
	(arc
		(start 55.026052 -328.964544)
		(mid 55.160416 -328.808782)
		(end 55.270654 -328.635106)
		(width 0.09525)
		(layer "F.Cu")
		(net "SAS2X28_A_HDD4_RX_+")
	)
	(arc
		(start 8.743442 -379.207014)
		(mid 8.987498 -379.114558)
		(end 9.208262 -378.975366)
		(width 0.09525)
		(layer "F.Cu")
		(net "SAS2X28_A_HDD4_RX_+")
	)
	(arc
		(start 216.842086 -57.889902)
		(mid 216.985892 -57.98599)
		(end 217.155522 -58.019696)
		(width 0.09525)
		(layer "F.Cu")
		(net "SAS2X28_A_HDD4_RX_+")
	)
	(arc
		(start 8.579358 -379.30201)
		(mid 8.655163 -379.243739)
		(end 8.743442 -379.207014)
		(width 0.09525)
		(layer "F.Cu")
		(net "SAS2X28_A_HDD4_RX_+")
	)
	(arc
		(start 21.958046 -362.62945)
		(mid 22.067751 -362.077928)
		(end 22.380194 -361.610402)
		(width 0.09525)
		(layer "F.Cu")
		(net "SAS2X28_A_HDD4_RX_+")
	)
	(arc
		(start 214.04199 -58.210704)
		(mid 214.434453 -58.096348)
		(end 214.829898 -57.992772)
		(width 0.09525)
		(layer "F.Cu")
		(net "SAS2X28_A_HDD4_RX_+")
	)
	(arc
		(start 216.480898 -57.740296)
		(mid 216.67637 -57.779178)
		(end 216.842086 -57.889902)
		(width 0.09525)
		(layer "F.Cu")
		(net "SAS2X28_A_HDD4_RX_+")
	)
	(arc
		(start 195.738242 -67.591178)
		(mid 196.075724 -67.114089)
		(end 196.518022 -66.73215)
		(width 0.09525)
		(layer "F.Cu")
		(net "SAS2X28_A_HDD4_RX_+")
	)
	(arc
		(start 21.5265 -366.657128)
		(mid 21.845833 -366.179213)
		(end 21.958046 -365.615474)
		(width 0.09525)
		(layer "F.Cu")
		(net "SAS2X28_A_HDD4_RX_+")
	)
	(arc
		(start 8.5217 -380.238254)
		(mid 8.408715 -380.06916)
		(end 8.369046 -379.8697)
		(width 0.09525)
		(layer "F.Cu")
		(net "SAS2X28_A_HDD4_RX_+")
	)
	(segment
		(start 5.362194 -375.723912)
		(end 5.325364 -375.687082)
		(width 0.09525)
		(layer "B.Cu")
		(net "SAS2X28_A_HDD4_RX_+")
	)
	(segment
		(start 8.330946 -379.6157)
		(end 8.330946 -378.488448)
		(width 0.09525)
		(layer "B.Cu")
		(net "SAS2X28_A_HDD4_RX_+")
	)
	(segment
		(start 7.227062 -376.80646)
		(end 7.227062 -376.805698)
		(width 0.09525)
		(layer "B.Cu")
		(net "SAS2X28_A_HDD4_RX_+")
	)
	(segment
		(start 6.121146 -375.8057)
		(end 5.559298 -375.8057)
		(width 0.09525)
		(layer "B.Cu")
		(net "SAS2X28_A_HDD4_RX_+")
	)
	(segment
		(start 8.661146 -380.3777)
		(end 8.636254 -380.352808)
		(width 0.09525)
		(layer "B.Cu")
		(net "SAS2X28_A_HDD4_RX_+")
	)
	(segment
		(start 6.764528 -376.081036)
		(end 6.750812 -376.066812)
		(width 0.09525)
		(layer "B.Cu")
		(net "SAS2X28_A_HDD4_RX_+")
	)
	(segment
		(start 4.874768 -375.500392)
		(end 4.873244 -375.498868)
		(width 0.09525)
		(layer "B.Cu")
		(net "SAS2X28_A_HDD4_RX_+")
	)
	(segment
		(start 6.121146 -375.805954)
		(end 6.121146 -375.8057)
		(width 0.09525)
		(layer "B.Cu")
		(net "SAS2X28_A_HDD4_RX_+")
	)
	(segment
		(start 8.043418 -377.794266)
		(end 7.348728 -377.099576)
		(width 0.09525)
		(layer "B.Cu")
		(net "SAS2X28_A_HDD4_RX_+")
	)
	(segment
		(start 4.873244 -375.498868)
		(end 2.811526 -375.498868)
		(width 0.09525)
		(layer "B.Cu")
		(net "SAS2X28_A_HDD4_RX_+")
	)
	(segment
		(start 7.041642 -376.35815)
		(end 6.764528 -376.081036)
		(width 0.09525)
		(layer "B.Cu")
		(net "SAS2X28_A_HDD4_RX_+")
	)
	(arc
		(start 5.325364 -375.687082)
		(mid 5.118629 -375.548946)
		(end 4.874768 -375.500392)
		(width 0.09525)
		(layer "B.Cu")
		(net "SAS2X28_A_HDD4_RX_+")
	)
	(arc
		(start 5.494782 -375.79808)
		(mid 5.423356 -375.770173)
		(end 5.362194 -375.723912)
		(width 0.09525)
		(layer "B.Cu")
		(net "SAS2X28_A_HDD4_RX_+")
	)
	(arc
		(start 5.559298 -375.8057)
		(mid 5.526819 -375.803769)
		(end 5.494782 -375.79808)
		(width 0.09525)
		(layer "B.Cu")
		(net "SAS2X28_A_HDD4_RX_+")
	)
	(arc
		(start 8.636254 -380.352808)
		(mid 8.410284 -380.01462)
		(end 8.330946 -379.6157)
		(width 0.09525)
		(layer "B.Cu")
		(net "SAS2X28_A_HDD4_RX_+")
	)
	(arc
		(start 8.330946 -378.488448)
		(mid 8.256218 -378.112764)
		(end 8.043418 -377.794266)
		(width 0.09525)
		(layer "B.Cu")
		(net "SAS2X28_A_HDD4_RX_+")
	)
	(arc
		(start 7.348728 -377.099576)
		(mid 7.258787 -376.965108)
		(end 7.227062 -376.80646)
		(width 0.09525)
		(layer "B.Cu")
		(net "SAS2X28_A_HDD4_RX_+")
	)
	(arc
		(start 6.750812 -376.066812)
		(mid 6.462002 -375.873545)
		(end 6.121146 -375.805954)
		(width 0.09525)
		(layer "B.Cu")
		(net "SAS2X28_A_HDD4_RX_+")
	)
	(arc
		(start 7.227062 -376.805698)
		(mid 7.17888 -376.563472)
		(end 7.041642 -376.35815)
		(width 0.09525)
		(layer "B.Cu")
		(net "SAS2X28_A_HDD4_RX_+")
	)
	(segment
		(start 202.501246 -85.3567)
		(end 202.247246 -85.6107)
		(width 0.111252)
		(layer "F.Cu")
		(net "SAS2X28_A_HDD4_FLT")
	)
	(segment
		(start 200.786746 -85.6107)
		(end 200.659746 -85.4837)
		(width 0.111252)
		(layer "F.Cu")
		(net "SAS2X28_A_HDD4_FLT")
	)
	(segment
		(start 200.151746 -84.9757)
		(end 200.151746 -83.2612)
		(width 0.111252)
		(layer "F.Cu")
		(net "SAS2X28_A_HDD4_FLT")
	)
	(segment
		(start 200.659746 -85.4837)
		(end 200.151746 -84.9757)
		(width 0.111252)
		(layer "F.Cu")
		(net "SAS2X28_A_HDD4_FLT")
	)
	(segment
		(start 202.247246 -85.6107)
		(end 200.786746 -85.6107)
		(width 0.111252)
		(layer "F.Cu")
		(net "SAS2X28_A_HDD4_FLT")
	)
	(via
		(at 200.659746 -85.4837)
		(size 0.5588)
		(drill 0.3048)
		(layers "F.Cu" "B.Cu")
		(net "SAS2X28_A_HDD4_FLT")
	)
	(via
		(at 8.863584 -395.15542)
		(size 0.5588)
		(drill 0.3048)
		(layers "F.Cu" "B.Cu")
		(net "SAS2X28_A_HDD4_FLT")
	)
	(via
		(at 200.659746 -86.4235)
		(size 0.7112)
		(drill 0.3556)
		(layers "F.Cu" "B.Cu")
		(net "SAS2X28_A_HDD4_FLT")
	)
	(segment
		(start 8.863584 -395.15542)
		(end 7.93242 -395.15542)
		(width 0.111252)
		(layer "B.Cu")
		(net "SAS2X28_A_HDD4_FLT")
	)
	(segment
		(start 2.81305 -394.500354)
		(end 2.811526 -394.49883)
		(width 0.111252)
		(layer "B.Cu")
		(net "SAS2X28_A_HDD4_FLT")
	)
	(segment
		(start 200.659746 -85.4837)
		(end 200.659746 -86.4235)
		(width 0.111252)
		(layer "B.Cu")
		(net "SAS2X28_A_HDD4_FLT")
	)
	(segment
		(start 7.277354 -394.500354)
		(end 2.81305 -394.500354)
		(width 0.111252)
		(layer "B.Cu")
		(net "SAS2X28_A_HDD4_FLT")
	)
	(segment
		(start 7.93242 -395.15542)
		(end 7.277354 -394.500354)
		(width 0.111252)
		(layer "B.Cu")
		(net "SAS2X28_A_HDD4_FLT")
	)
	(segment
		(start 8.750808 -396.136114)
		(end 9.522206 -396.907512)
		(width 0.14605)
		(layer "In5.Cu")
		(net "SAS2X28_A_HDD4_FLT")
	)
	(segment
		(start 231.713278 -138.927078)
		(end 200.659746 -107.873546)
		(width 0.14605)
		(layer "In5.Cu")
		(net "SAS2X28_A_HDD4_FLT")
	)
	(segment
		(start 11.738102 -400.42846)
		(end 11.48334 -400.683222)
		(width 0.14605)
		(layer "In5.Cu")
		(net "SAS2X28_A_HDD4_FLT")
	)
	(segment
		(start 15.552674 -467.528148)
		(end 17.242028 -469.217502)
		(width 0.14605)
		(layer "In5.Cu")
		(net "SAS2X28_A_HDD4_FLT")
	)
	(segment
		(start 231.713278 -379.211586)
		(end 231.713278 -138.927078)
		(width 0.14605)
		(layer "In5.Cu")
		(net "SAS2X28_A_HDD4_FLT")
	)
	(segment
		(start 6.130798 -435.53507)
		(end 6.130798 -442.515244)
		(width 0.14605)
		(layer "In5.Cu")
		(net "SAS2X28_A_HDD4_FLT")
	)
	(segment
		(start 140.563854 -469.0745)
		(end 209.369152 -400.269202)
		(width 0.14605)
		(layer "In5.Cu")
		(net "SAS2X28_A_HDD4_FLT")
	)
	(segment
		(start 10.414254 -460.520034)
		(end 10.414254 -462.935066)
		(width 0.14605)
		(layer "In5.Cu")
		(net "SAS2X28_A_HDD4_FLT")
	)
	(segment
		(start 10.414254 -462.935066)
		(end 15.007336 -467.528148)
		(width 0.14605)
		(layer "In5.Cu")
		(net "SAS2X28_A_HDD4_FLT")
	)
	(segment
		(start 34.307018 -469.217502)
		(end 34.45002 -469.0745)
		(width 0.14605)
		(layer "In5.Cu")
		(net "SAS2X28_A_HDD4_FLT")
	)
	(segment
		(start 9.522206 -396.907512)
		(end 10.464292 -396.907512)
		(width 0.14605)
		(layer "In5.Cu")
		(net "SAS2X28_A_HDD4_FLT")
	)
	(segment
		(start 210.655916 -400.268948)
		(end 231.713278 -379.211586)
		(width 0.14605)
		(layer "In5.Cu")
		(net "SAS2X28_A_HDD4_FLT")
	)
	(segment
		(start 8.664448 -458.770228)
		(end 10.414254 -460.520034)
		(width 0.14605)
		(layer "In5.Cu")
		(net "SAS2X28_A_HDD4_FLT")
	)
	(segment
		(start 15.007336 -467.528148)
		(end 15.552674 -467.528148)
		(width 0.14605)
		(layer "In5.Cu")
		(net "SAS2X28_A_HDD4_FLT")
	)
	(segment
		(start 200.659746 -107.873546)
		(end 200.659746 -85.4837)
		(width 0.14605)
		(layer "In5.Cu")
		(net "SAS2X28_A_HDD4_FLT")
	)
	(segment
		(start 8.664448 -457.834238)
		(end 8.664448 -458.770228)
		(width 0.14605)
		(layer "In5.Cu")
		(net "SAS2X28_A_HDD4_FLT")
	)
	(segment
		(start 6.97865 -456.14844)
		(end 8.664448 -457.834238)
		(width 0.14605)
		(layer "In5.Cu")
		(net "SAS2X28_A_HDD4_FLT")
	)
	(segment
		(start 17.242028 -469.217502)
		(end 34.307018 -469.217502)
		(width 0.14605)
		(layer "In5.Cu")
		(net "SAS2X28_A_HDD4_FLT")
	)
	(segment
		(start 11.48334 -400.683222)
		(end 11.48334 -430.182528)
		(width 0.14605)
		(layer "In5.Cu")
		(net "SAS2X28_A_HDD4_FLT")
	)
	(segment
		(start 11.48334 -430.182528)
		(end 6.130798 -435.53507)
		(width 0.14605)
		(layer "In5.Cu")
		(net "SAS2X28_A_HDD4_FLT")
	)
	(segment
		(start 34.45002 -469.0745)
		(end 140.563854 -469.0745)
		(width 0.14605)
		(layer "In5.Cu")
		(net "SAS2X28_A_HDD4_FLT")
	)
	(segment
		(start 6.130798 -442.515244)
		(end 6.97865 -443.363096)
		(width 0.14605)
		(layer "In5.Cu")
		(net "SAS2X28_A_HDD4_FLT")
	)
	(segment
		(start 6.97865 -443.363096)
		(end 6.97865 -456.14844)
		(width 0.14605)
		(layer "In5.Cu")
		(net "SAS2X28_A_HDD4_FLT")
	)
	(segment
		(start 8.863584 -395.15542)
		(end 8.750808 -395.268196)
		(width 0.14605)
		(layer "In5.Cu")
		(net "SAS2X28_A_HDD4_FLT")
	)
	(segment
		(start 10.464292 -396.907512)
		(end 11.738102 -398.181322)
		(width 0.14605)
		(layer "In5.Cu")
		(net "SAS2X28_A_HDD4_FLT")
	)
	(segment
		(start 11.738102 -398.181322)
		(end 11.738102 -400.42846)
		(width 0.14605)
		(layer "In5.Cu")
		(net "SAS2X28_A_HDD4_FLT")
	)
	(segment
		(start 8.750808 -395.268196)
		(end 8.750808 -396.136114)
		(width 0.14605)
		(layer "In5.Cu")
		(net "SAS2X28_A_HDD4_FLT")
	)
	(segment
		(start 209.369152 -400.269202)
		(end 209.36966 -400.268948)
		(width 0.14605)
		(layer "In5.Cu")
		(net "SAS2X28_A_HDD4_FLT")
	)
	(segment
		(start 209.36966 -400.268948)
		(end 210.655916 -400.268948)
		(width 0.14605)
		(layer "In5.Cu")
		(net "SAS2X28_A_HDD4_FLT")
	)
	(segment
		(start 220.763338 -53.78958)
		(end 212.216746 -57.4167)
		(width 0.09525)
		(layer "F.Cu")
		(net "SAS2X28_A_HDD4_TX_+")
	)
	(segment
		(start 221.185486 -53.61051)
		(end 221.154244 -53.623718)
		(width 0.09525)
		(layer "F.Cu")
		(net "SAS2X28_A_HDD4_TX_+")
	)
	(segment
		(start 24.009604 -358.184196)
		(end 24.009604 -358.18445)
		(width 0.09525)
		(layer "F.Cu")
		(net "SAS2X28_A_HDD4_TX_+")
	)
	(segment
		(start 221.154244 -53.623718)
		(end 221.153228 -53.624226)
		(width 0.09525)
		(layer "F.Cu")
		(net "SAS2X28_A_HDD4_TX_+")
	)
	(segment
		(start 20.328636 -365.878364)
		(end 8.763 -377.444)
		(width 0.09525)
		(layer "F.Cu")
		(net "SAS2X28_A_HDD4_TX_+")
	)
	(segment
		(start 81.94294 -276.145752)
		(end 54.13756 -327.865994)
		(width 0.09525)
		(layer "F.Cu")
		(net "SAS2X28_A_HDD4_TX_+")
	)
	(segment
		(start 223.249998 -53.069998)
		(end 222.010986 -53.069998)
		(width 0.09525)
		(layer "F.Cu")
		(net "SAS2X28_A_HDD4_TX_+")
	)
	(segment
		(start 8.71982 -377.486926)
		(end 8.719566 -377.48718)
		(width 0.09525)
		(layer "F.Cu")
		(net "SAS2X28_A_HDD4_TX_+")
	)
	(segment
		(start 194.338956 -67.0814)
		(end 81.94294 -276.145752)
		(width 0.09525)
		(layer "F.Cu")
		(net "SAS2X28_A_HDD4_TX_+")
	)
	(segment
		(start 53.612034 -328.579988)
		(end 53.427884 -328.764138)
		(width 0.09525)
		(layer "F.Cu")
		(net "SAS2X28_A_HDD4_TX_+")
	)
	(segment
		(start 221.6658 -53.213)
		(end 221.639384 -53.239416)
		(width 0.09525)
		(layer "F.Cu")
		(net "SAS2X28_A_HDD4_TX_+")
	)
	(segment
		(start 20.688046 -362.269786)
		(end 20.688046 -365.0107)
		(width 0.09525)
		(layer "F.Cu")
		(net "SAS2X28_A_HDD4_TX_+")
	)
	(segment
		(start 221.153228 -53.624226)
		(end 220.763338 -53.78958)
		(width 0.09525)
		(layer "F.Cu")
		(net "SAS2X28_A_HDD4_TX_+")
	)
	(segment
		(start 54.13756 -327.865994)
		(end 54.09819 -327.9394)
		(width 0.09525)
		(layer "F.Cu")
		(net "SAS2X28_A_HDD4_TX_+")
	)
	(segment
		(start 7.874 -377.837446)
		(end 5.576316 -377.837446)
		(width 0.09525)
		(layer "F.Cu")
		(net "SAS2X28_A_HDD4_TX_+")
	)
	(segment
		(start 24.009604 -358.18445)
		(end 21.22805 -360.966004)
		(width 0.09525)
		(layer "F.Cu")
		(net "SAS2X28_A_HDD4_TX_+")
	)
	(segment
		(start 8.763 -377.444)
		(end 8.71982 -377.486926)
		(width 0.09525)
		(layer "F.Cu")
		(net "SAS2X28_A_HDD4_TX_+")
	)
	(segment
		(start 4.760976 -377.498864)
		(end 3.192526 -377.498864)
		(width 0.09525)
		(layer "F.Cu")
		(net "SAS2X28_A_HDD4_TX_+")
	)
	(segment
		(start 4.7625 -377.500388)
		(end 4.760976 -377.498864)
		(width 0.09525)
		(layer "F.Cu")
		(net "SAS2X28_A_HDD4_TX_+")
	)
	(segment
		(start 221.40672 -53.51653)
		(end 221.190058 -53.608478)
		(width 0.09525)
		(layer "F.Cu")
		(net "SAS2X28_A_HDD4_TX_+")
	)
	(segment
		(start 53.427884 -328.764138)
		(end 24.009604 -358.184196)
		(width 0.09525)
		(layer "F.Cu")
		(net "SAS2X28_A_HDD4_TX_+")
	)
	(segment
		(start 221.190058 -53.608478)
		(end 221.185486 -53.61051)
		(width 0.09525)
		(layer "F.Cu")
		(net "SAS2X28_A_HDD4_TX_+")
	)
	(arc
		(start 21.22805 -360.966004)
		(mid 20.828359 -361.564184)
		(end 20.688046 -362.269786)
		(width 0.09525)
		(layer "F.Cu")
		(net "SAS2X28_A_HDD4_TX_+")
	)
	(arc
		(start 221.596966 -53.341778)
		(mid 221.586009 -53.397334)
		(end 221.554548 -53.444394)
		(width 0.09525)
		(layer "F.Cu")
		(net "SAS2X28_A_HDD4_TX_+")
	)
	(arc
		(start 221.639384 -53.239416)
		(mid 221.607974 -53.286379)
		(end 221.596966 -53.341778)
		(width 0.09525)
		(layer "F.Cu")
		(net "SAS2X28_A_HDD4_TX_+")
	)
	(arc
		(start 212.216746 -57.4167)
		(mid 204.11196 -61.096596)
		(end 196.200014 -65.174622)
		(width 0.09525)
		(layer "F.Cu")
		(net "SAS2X28_A_HDD4_TX_+")
	)
	(arc
		(start 5.576316 -377.837446)
		(mid 5.426626 -377.807671)
		(end 5.29971 -377.722892)
		(width 0.09525)
		(layer "F.Cu")
		(net "SAS2X28_A_HDD4_TX_+")
	)
	(arc
		(start 196.200014 -65.174622)
		(mid 195.135144 -65.996891)
		(end 194.338956 -67.0814)
		(width 0.09525)
		(layer "F.Cu")
		(net "SAS2X28_A_HDD4_TX_+")
	)
	(arc
		(start 222.010986 -53.069998)
		(mid 221.824165 -53.107159)
		(end 221.6658 -53.213)
		(width 0.09525)
		(layer "F.Cu")
		(net "SAS2X28_A_HDD4_TX_+")
	)
	(arc
		(start 20.688046 -365.0107)
		(mid 20.594641 -365.480281)
		(end 20.328636 -365.878364)
		(width 0.09525)
		(layer "F.Cu")
		(net "SAS2X28_A_HDD4_TX_+")
	)
	(arc
		(start 5.29971 -377.722892)
		(mid 5.053236 -377.558203)
		(end 4.7625 -377.500388)
		(width 0.09525)
		(layer "F.Cu")
		(net "SAS2X28_A_HDD4_TX_+")
	)
	(arc
		(start 221.554548 -53.444394)
		(mid 221.481594 -53.48243)
		(end 221.40672 -53.51653)
		(width 0.09525)
		(layer "F.Cu")
		(net "SAS2X28_A_HDD4_TX_+")
	)
	(arc
		(start 8.719566 -377.48718)
		(mid 8.331617 -377.746399)
		(end 7.874 -377.837446)
		(width 0.09525)
		(layer "F.Cu")
		(net "SAS2X28_A_HDD4_TX_+")
	)
	(arc
		(start 54.09819 -327.9394)
		(mid 53.8803 -328.278811)
		(end 53.612034 -328.579988)
		(width 0.09525)
		(layer "F.Cu")
		(net "SAS2X28_A_HDD4_TX_+")
	)
	(segment
		(start 202.501246 -84.3407)
		(end 202.247246 -84.5947)
		(width 0.111252)
		(layer "F.Cu")
		(net "SAS2X28_B_HDD4_FLT")
	)
	(segment
		(start 201.040746 -84.5947)
		(end 200.801986 -84.35594)
		(width 0.111252)
		(layer "F.Cu")
		(net "SAS2X28_B_HDD4_FLT")
	)
	(segment
		(start 202.247246 -84.5947)
		(end 201.040746 -84.5947)
		(width 0.111252)
		(layer "F.Cu")
		(net "SAS2X28_B_HDD4_FLT")
	)
	(segment
		(start 200.801986 -84.35594)
		(end 200.801986 -83.2612)
		(width 0.111252)
		(layer "F.Cu")
		(net "SAS2X28_B_HDD4_FLT")
	)
	(via
		(at 201.980546 -84.5947)
		(size 0.7112)
		(drill 0.3556)
		(layers "F.Cu" "B.Cu")
		(net "SAS2X28_B_HDD4_FLT")
	)
	(via
		(at 201.040746 -84.5947)
		(size 0.5588)
		(drill 0.3048)
		(layers "F.Cu" "B.Cu")
		(net "SAS2X28_B_HDD4_FLT")
	)
	(via
		(at 94.487746 -139.5222)
		(size 0.5588)
		(drill 0.3048)
		(layers "F.Cu" "B.Cu")
		(net "SAS2X28_B_HDD4_FLT")
	)
	(via
		(at 10.888218 -139.3063)
		(size 0.5588)
		(drill 0.3048)
		(layers "F.Cu" "B.Cu")
		(net "SAS2X28_B_HDD4_FLT")
	)
	(segment
		(start 9.288018 -137.7061)
		(end 5.689346 -137.7061)
		(width 0.111252)
		(layer "B.Cu")
		(net "SAS2X28_B_HDD4_FLT")
	)
	(segment
		(start 5.689346 -137.7061)
		(end 5.483606 -137.50036)
		(width 0.111252)
		(layer "B.Cu")
		(net "SAS2X28_B_HDD4_FLT")
	)
	(segment
		(start 10.888218 -139.3063)
		(end 9.288018 -137.7061)
		(width 0.111252)
		(layer "B.Cu")
		(net "SAS2X28_B_HDD4_FLT")
	)
	(segment
		(start 5.483606 -137.50036)
		(end 2.81305 -137.50036)
		(width 0.111252)
		(layer "B.Cu")
		(net "SAS2X28_B_HDD4_FLT")
	)
	(segment
		(start 2.81305 -137.50036)
		(end 2.811526 -137.498836)
		(width 0.111252)
		(layer "B.Cu")
		(net "SAS2X28_B_HDD4_FLT")
	)
	(segment
		(start 201.040746 -84.5947)
		(end 201.980546 -84.5947)
		(width 0.111252)
		(layer "B.Cu")
		(net "SAS2X28_B_HDD4_FLT")
	)
	(segment
		(start 200.2409 -84.5947)
		(end 145.415 -139.4206)
		(width 0.14605)
		(layer "In2.Cu")
		(net "SAS2X28_B_HDD4_FLT")
	)
	(segment
		(start 201.040746 -84.5947)
		(end 200.2409 -84.5947)
		(width 0.14605)
		(layer "In2.Cu")
		(net "SAS2X28_B_HDD4_FLT")
	)
	(segment
		(start 145.415 -139.4206)
		(end 94.589346 -139.4206)
		(width 0.14605)
		(layer "In2.Cu")
		(net "SAS2X28_B_HDD4_FLT")
	)
	(segment
		(start 94.589346 -139.4206)
		(end 94.487746 -139.5222)
		(width 0.14605)
		(layer "In2.Cu")
		(net "SAS2X28_B_HDD4_FLT")
	)
	(segment
		(start 12.487402 -129.651252)
		(end 12.487402 -133.645148)
		(width 0.14605)
		(layer "In5.Cu")
		(net "SAS2X28_B_HDD4_FLT")
	)
	(segment
		(start 94.487746 -139.5222)
		(end 94.487746 -106.957876)
		(width 0.14605)
		(layer "In5.Cu")
		(net "SAS2X28_B_HDD4_FLT")
	)
	(segment
		(start 11.138154 -134.994396)
		(end 11.138154 -139.056364)
		(width 0.14605)
		(layer "In5.Cu")
		(net "SAS2X28_B_HDD4_FLT")
	)
	(segment
		(start 21.708364 -99.939348)
		(end 12.048998 -109.598714)
		(width 0.14605)
		(layer "In5.Cu")
		(net "SAS2X28_B_HDD4_FLT")
	)
	(segment
		(start 12.048998 -129.212848)
		(end 12.487402 -129.651252)
		(width 0.14605)
		(layer "In5.Cu")
		(net "SAS2X28_B_HDD4_FLT")
	)
	(segment
		(start 11.138154 -139.056364)
		(end 10.888218 -139.3063)
		(width 0.14605)
		(layer "In5.Cu")
		(net "SAS2X28_B_HDD4_FLT")
	)
	(segment
		(start 94.487746 -106.957876)
		(end 87.469218 -99.939348)
		(width 0.14605)
		(layer "In5.Cu")
		(net "SAS2X28_B_HDD4_FLT")
	)
	(segment
		(start 12.487402 -133.645148)
		(end 11.138154 -134.994396)
		(width 0.14605)
		(layer "In5.Cu")
		(net "SAS2X28_B_HDD4_FLT")
	)
	(segment
		(start 12.048998 -109.598714)
		(end 12.048998 -129.212848)
		(width 0.14605)
		(layer "In5.Cu")
		(net "SAS2X28_B_HDD4_FLT")
	)
	(segment
		(start 87.469218 -99.939348)
		(end 21.708364 -99.939348)
		(width 0.14605)
		(layer "In5.Cu")
		(net "SAS2X28_B_HDD4_FLT")
	)
	(segment
		(start 20.562316 -366.112044)
		(end 20.17268 -366.50168)
		(width 0.09525)
		(layer "F.Cu")
		(net "SAS2X28_A_HDD4_TX_-")
	)
	(segment
		(start 4.754372 -378.500386)
		(end 4.752848 -378.498862)
		(width 0.09525)
		(layer "F.Cu")
		(net "SAS2X28_A_HDD4_TX_-")
	)
	(segment
		(start 220.985588 -54.054248)
		(end 220.982032 -54.056026)
		(width 0.09525)
		(layer "F.Cu")
		(net "SAS2X28_A_HDD4_TX_-")
	)
	(segment
		(start 220.987366 -54.053486)
		(end 220.98635 -54.053994)
		(width 0.09525)
		(layer "F.Cu")
		(net "SAS2X28_A_HDD4_TX_-")
	)
	(segment
		(start 221.12859 -53.993542)
		(end 220.988128 -54.053232)
		(width 0.09525)
		(layer "F.Cu")
		(net "SAS2X28_A_HDD4_TX_-")
	)
	(segment
		(start 220.978222 -54.05755)
		(end 220.976698 -54.058312)
		(width 0.09525)
		(layer "F.Cu")
		(net "SAS2X28_A_HDD4_TX_-")
	)
	(segment
		(start 82.234024 -276.302216)
		(end 54.428644 -328.022458)
		(width 0.09525)
		(layer "F.Cu")
		(net "SAS2X28_A_HDD4_TX_-")
	)
	(segment
		(start 221.28353 -53.92801)
		(end 221.282514 -53.928518)
		(width 0.09525)
		(layer "F.Cu")
		(net "SAS2X28_A_HDD4_TX_-")
	)
	(segment
		(start 221.614746 -53.9877)
		(end 221.582234 -53.954934)
		(width 0.09525)
		(layer "F.Cu")
		(net "SAS2X28_A_HDD4_TX_-")
	)
	(segment
		(start 221.333568 -53.906674)
		(end 221.319344 -53.91277)
		(width 0.09525)
		(layer "F.Cu")
		(net "SAS2X28_A_HDD4_TX_-")
	)
	(segment
		(start 223.249998 -54.339998)
		(end 222.216218 -54.339998)
		(width 0.09525)
		(layer "F.Cu")
		(net "SAS2X28_A_HDD4_TX_-")
	)
	(segment
		(start 7.874254 -378.167646)
		(end 5.557774 -378.167646)
		(width 0.09525)
		(layer "F.Cu")
		(net "SAS2X28_A_HDD4_TX_-")
	)
	(segment
		(start 220.978984 -54.057296)
		(end 220.978222 -54.05755)
		(width 0.09525)
		(layer "F.Cu")
		(net "SAS2X28_A_HDD4_TX_-")
	)
	(segment
		(start 8.995918 -377.678188)
		(end 8.952992 -377.72086)
		(width 0.09525)
		(layer "F.Cu")
		(net "SAS2X28_A_HDD4_TX_-")
	)
	(segment
		(start 221.319344 -53.91277)
		(end 221.314772 -53.914802)
		(width 0.09525)
		(layer "F.Cu")
		(net "SAS2X28_A_HDD4_TX_-")
	)
	(segment
		(start 220.988128 -54.053232)
		(end 220.987366 -54.053486)
		(width 0.09525)
		(layer "F.Cu")
		(net "SAS2X28_A_HDD4_TX_-")
	)
	(segment
		(start 54.428898 -328.022458)
		(end 54.389528 -328.095356)
		(width 0.09525)
		(layer "F.Cu")
		(net "SAS2X28_A_HDD4_TX_-")
	)
	(segment
		(start 196.358764 -65.464182)
		(end 196.36105 -65.462912)
		(width 0.09525)
		(layer "F.Cu")
		(net "SAS2X28_A_HDD4_TX_-")
	)
	(segment
		(start 53.845714 -328.813668)
		(end 24.339804 -358.321102)
		(width 0.09525)
		(layer "F.Cu")
		(net "SAS2X28_A_HDD4_TX_-")
	)
	(segment
		(start 221.282514 -53.928518)
		(end 221.12859 -53.993542)
		(width 0.09525)
		(layer "F.Cu")
		(net "SAS2X28_A_HDD4_TX_-")
	)
	(segment
		(start 220.982032 -54.056026)
		(end 220.978984 -54.057296)
		(width 0.09525)
		(layer "F.Cu")
		(net "SAS2X28_A_HDD4_TX_-")
	)
	(segment
		(start 220.98635 -54.053994)
		(end 220.985588 -54.054248)
		(width 0.09525)
		(layer "F.Cu")
		(net "SAS2X28_A_HDD4_TX_-")
	)
	(segment
		(start 24.339804 -358.321102)
		(end 24.339804 -358.321356)
		(width 0.09525)
		(layer "F.Cu")
		(net "SAS2X28_A_HDD4_TX_-")
	)
	(segment
		(start 194.629786 -67.237864)
		(end 82.234024 -276.302216)
		(width 0.09525)
		(layer "F.Cu")
		(net "SAS2X28_A_HDD4_TX_-")
	)
	(segment
		(start 220.974666 -54.059074)
		(end 220.974666 -54.059328)
		(width 0.09525)
		(layer "F.Cu")
		(net "SAS2X28_A_HDD4_TX_-")
	)
	(segment
		(start 221.790768 -54.163976)
		(end 221.614746 -53.9877)
		(width 0.09525)
		(layer "F.Cu")
		(net "SAS2X28_A_HDD4_TX_-")
	)
	(segment
		(start 220.974666 -54.059328)
		(end 212.345778 -57.720738)
		(width 0.09525)
		(layer "F.Cu")
		(net "SAS2X28_A_HDD4_TX_-")
	)
	(segment
		(start 20.17268 -366.50168)
		(end 20.172426 -366.50168)
		(width 0.09525)
		(layer "F.Cu")
		(net "SAS2X28_A_HDD4_TX_-")
	)
	(segment
		(start 54.428644 -328.022458)
		(end 54.428898 -328.022458)
		(width 0.09525)
		(layer "F.Cu")
		(net "SAS2X28_A_HDD4_TX_-")
	)
	(segment
		(start 4.752848 -378.498862)
		(end 3.192526 -378.498862)
		(width 0.09525)
		(layer "F.Cu")
		(net "SAS2X28_A_HDD4_TX_-")
	)
	(segment
		(start 21.018246 -362.269786)
		(end 21.018246 -365.0107)
		(width 0.09525)
		(layer "F.Cu")
		(net "SAS2X28_A_HDD4_TX_-")
	)
	(segment
		(start 20.172426 -366.50168)
		(end 8.995918 -377.678188)
		(width 0.09525)
		(layer "F.Cu")
		(net "SAS2X28_A_HDD4_TX_-")
	)
	(segment
		(start 220.976698 -54.058312)
		(end 220.974666 -54.059074)
		(width 0.09525)
		(layer "F.Cu")
		(net "SAS2X28_A_HDD4_TX_-")
	)
	(segment
		(start 24.339804 -358.321356)
		(end 21.461476 -361.199684)
		(width 0.09525)
		(layer "F.Cu")
		(net "SAS2X28_A_HDD4_TX_-")
	)
	(segment
		(start 54.389528 -328.095356)
		(end 54.389274 -328.095356)
		(width 0.09525)
		(layer "F.Cu")
		(net "SAS2X28_A_HDD4_TX_-")
	)
	(segment
		(start 221.314772 -53.914802)
		(end 221.28353 -53.92801)
		(width 0.09525)
		(layer "F.Cu")
		(net "SAS2X28_A_HDD4_TX_-")
	)
	(arc
		(start 221.582234 -53.954934)
		(mid 221.559707 -53.935057)
		(end 221.534736 -53.918358)
		(width 0.09525)
		(layer "F.Cu")
		(net "SAS2X28_A_HDD4_TX_-")
	)
	(arc
		(start 53.852572 -328.807318)
		(mid 53.849204 -328.810559)
		(end 53.845714 -328.813668)
		(width 0.09525)
		(layer "F.Cu")
		(net "SAS2X28_A_HDD4_TX_-")
	)
	(arc
		(start 5.557774 -378.167646)
		(mid 5.433648 -378.192336)
		(end 5.328412 -378.262642)
		(width 0.09525)
		(layer "F.Cu")
		(net "SAS2X28_A_HDD4_TX_-")
	)
	(arc
		(start 54.389274 -328.095356)
		(mid 54.148424 -328.47207)
		(end 53.852572 -328.807318)
		(width 0.09525)
		(layer "F.Cu")
		(net "SAS2X28_A_HDD4_TX_-")
	)
	(arc
		(start 21.018246 -365.0107)
		(mid 20.899789 -365.606697)
		(end 20.562316 -366.112044)
		(width 0.09525)
		(layer "F.Cu")
		(net "SAS2X28_A_HDD4_TX_-")
	)
	(arc
		(start 222.216218 -54.339998)
		(mid 221.985991 -54.294297)
		(end 221.790768 -54.163976)
		(width 0.09525)
		(layer "F.Cu")
		(net "SAS2X28_A_HDD4_TX_-")
	)
	(arc
		(start 221.493842 -53.90007)
		(mid 221.457497 -53.89117)
		(end 221.420182 -53.888386)
		(width 0.09525)
		(layer "F.Cu")
		(net "SAS2X28_A_HDD4_TX_-")
	)
	(arc
		(start 221.49816 -53.901594)
		(mid 221.496005 -53.900821)
		(end 221.493842 -53.90007)
		(width 0.09525)
		(layer "F.Cu")
		(net "SAS2X28_A_HDD4_TX_-")
	)
	(arc
		(start 212.345778 -57.720738)
		(mid 204.256034 -61.393771)
		(end 196.358764 -65.464182)
		(width 0.09525)
		(layer "F.Cu")
		(net "SAS2X28_A_HDD4_TX_-")
	)
	(arc
		(start 196.36105 -65.462912)
		(mid 195.370515 -66.228553)
		(end 194.629786 -67.237864)
		(width 0.09525)
		(layer "F.Cu")
		(net "SAS2X28_A_HDD4_TX_-")
	)
	(arc
		(start 21.461476 -361.199684)
		(mid 21.133422 -361.690651)
		(end 21.018246 -362.269786)
		(width 0.09525)
		(layer "F.Cu")
		(net "SAS2X28_A_HDD4_TX_-")
	)
	(arc
		(start 221.420182 -53.888386)
		(mid 221.375972 -53.893253)
		(end 221.333568 -53.906674)
		(width 0.09525)
		(layer "F.Cu")
		(net "SAS2X28_A_HDD4_TX_-")
	)
	(arc
		(start 5.328412 -378.262642)
		(mid 5.06504 -378.438621)
		(end 4.754372 -378.500386)
		(width 0.09525)
		(layer "F.Cu")
		(net "SAS2X28_A_HDD4_TX_-")
	)
	(arc
		(start 221.534736 -53.918358)
		(mid 221.531072 -53.916291)
		(end 221.52737 -53.914294)
		(width 0.09525)
		(layer "F.Cu")
		(net "SAS2X28_A_HDD4_TX_-")
	)
	(arc
		(start 221.52737 -53.914294)
		(mid 221.51299 -53.907427)
		(end 221.49816 -53.901594)
		(width 0.09525)
		(layer "F.Cu")
		(net "SAS2X28_A_HDD4_TX_-")
	)
	(arc
		(start 8.952992 -377.72086)
		(mid 8.458049 -378.051537)
		(end 7.874254 -378.167646)
		(width 0.09525)
		(layer "F.Cu")
		(net "SAS2X28_A_HDD4_TX_-")
	)
	(segment
		(start 8.23976 -205.50124)
		(end 8.978646 -204.762354)
		(width 0.111252)
		(layer "F.Cu")
		(net "SAS_EXP_B_PWR1")
	)
	(segment
		(start 196.432424 -388.933944)
		(end 195.599558 -388.933944)
		(width 0.111252)
		(layer "F.Cu")
		(net "SAS_EXP_B_PWR1")
	)
	(segment
		(start 8.978646 -204.762354)
		(end 9.256522 -204.762354)
		(width 0.111252)
		(layer "F.Cu")
		(net "SAS_EXP_B_PWR1")
	)
	(segment
		(start 196.733668 -388.6327)
		(end 196.432424 -388.933944)
		(width 0.111252)
		(layer "F.Cu")
		(net "SAS_EXP_B_PWR1")
	)
	(segment
		(start 3.19024 -205.504542)
		(end 3.193542 -205.50124)
		(width 0.111252)
		(layer "F.Cu")
		(net "SAS_EXP_B_PWR1")
	)
	(segment
		(start 13.150342 -205.486)
		(end 13.399008 -205.734666)
		(width 0.111252)
		(layer "F.Cu")
		(net "SAS_EXP_B_PWR1")
	)
	(segment
		(start 9.256522 -204.762354)
		(end 9.261348 -204.757528)
		(width 0.111252)
		(layer "F.Cu")
		(net "SAS_EXP_B_PWR1")
	)
	(segment
		(start 11.620754 -204.762354)
		(end 12.3444 -205.486)
		(width 0.111252)
		(layer "F.Cu")
		(net "SAS_EXP_B_PWR1")
	)
	(segment
		(start 13.399008 -205.734666)
		(end 27.98953 -205.734666)
		(width 0.111252)
		(layer "F.Cu")
		(net "SAS_EXP_B_PWR1")
	)
	(segment
		(start 3.193542 -205.50124)
		(end 8.23976 -205.50124)
		(width 0.111252)
		(layer "F.Cu")
		(net "SAS_EXP_B_PWR1")
	)
	(segment
		(start 9.261348 -204.757528)
		(end 9.64438 -204.757528)
		(width 0.111252)
		(layer "F.Cu")
		(net "SAS_EXP_B_PWR1")
	)
	(segment
		(start 197.467474 -388.084822)
		(end 197.281546 -388.084822)
		(width 0.111252)
		(layer "F.Cu")
		(net "SAS_EXP_B_PWR1")
	)
	(segment
		(start 9.649206 -204.762354)
		(end 11.620754 -204.762354)
		(width 0.111252)
		(layer "F.Cu")
		(net "SAS_EXP_B_PWR1")
	)
	(segment
		(start 197.281546 -388.084822)
		(end 196.733668 -388.6327)
		(width 0.111252)
		(layer "F.Cu")
		(net "SAS_EXP_B_PWR1")
	)
	(segment
		(start 12.3444 -205.486)
		(end 13.150342 -205.486)
		(width 0.111252)
		(layer "F.Cu")
		(net "SAS_EXP_B_PWR1")
	)
	(segment
		(start 9.64438 -204.757528)
		(end 9.649206 -204.762354)
		(width 0.111252)
		(layer "F.Cu")
		(net "SAS_EXP_B_PWR1")
	)
	(via
		(at 27.98953 -205.734666)
		(size 0.5588)
		(drill 0.3048)
		(layers "F.Cu" "B.Cu")
		(net "SAS_EXP_B_PWR1")
	)
	(via
		(at 88.220296 -387.096)
		(size 0.5588)
		(drill 0.3048)
		(layers "F.Cu" "B.Cu")
		(net "SAS_EXP_B_PWR1")
	)
	(via
		(at 196.733668 -388.6327)
		(size 0.5588)
		(drill 0.3048)
		(layers "F.Cu" "B.Cu")
		(net "SAS_EXP_B_PWR1")
	)
	(via
		(at 196.733668 -387.6929)
		(size 0.7112)
		(drill 0.3556)
		(layers "F.Cu" "B.Cu")
		(net "SAS_EXP_B_PWR1")
	)
	(segment
		(start 196.733668 -388.6327)
		(end 196.733668 -387.6929)
		(width 0.111252)
		(layer "B.Cu")
		(net "SAS_EXP_B_PWR1")
	)
	(segment
		(start 189.611 -388.874)
		(end 196.492368 -388.874)
		(width 0.14605)
		(layer "In2.Cu")
		(net "SAS_EXP_B_PWR1")
	)
	(segment
		(start 187.9727 -387.2357)
		(end 189.611 -388.874)
		(width 0.14605)
		(layer "In2.Cu")
		(net "SAS_EXP_B_PWR1")
	)
	(segment
		(start 88.220296 -387.096)
		(end 88.359996 -387.2357)
		(width 0.14605)
		(layer "In2.Cu")
		(net "SAS_EXP_B_PWR1")
	)
	(segment
		(start 196.492368 -388.874)
		(end 196.733668 -388.6327)
		(width 0.14605)
		(layer "In2.Cu")
		(net "SAS_EXP_B_PWR1")
	)
	(segment
		(start 88.359996 -387.2357)
		(end 187.9727 -387.2357)
		(width 0.14605)
		(layer "In2.Cu")
		(net "SAS_EXP_B_PWR1")
	)
	(segment
		(start 27.935936 -200.231248)
		(end 27.868372 -200.231248)
		(width 0.14605)
		(layer "In5.Cu")
		(net "SAS_EXP_B_PWR1")
	)
	(segment
		(start 88.248998 -205.672944)
		(end 82.626454 -200.0504)
		(width 0.14605)
		(layer "In5.Cu")
		(net "SAS_EXP_B_PWR1")
	)
	(segment
		(start 82.626454 -200.0504)
		(end 28.116784 -200.0504)
		(width 0.14605)
		(layer "In5.Cu")
		(net "SAS_EXP_B_PWR1")
	)
	(segment
		(start 88.248998 -387.067298)
		(end 88.248998 -205.672944)
		(width 0.14605)
		(layer "In5.Cu")
		(net "SAS_EXP_B_PWR1")
	)
	(segment
		(start 28.116784 -200.0504)
		(end 27.935936 -200.231248)
		(width 0.14605)
		(layer "In5.Cu")
		(net "SAS_EXP_B_PWR1")
	)
	(segment
		(start 88.220296 -387.096)
		(end 88.248998 -387.067298)
		(width 0.14605)
		(layer "In5.Cu")
		(net "SAS_EXP_B_PWR1")
	)
	(segment
		(start 26.7589 -204.504036)
		(end 27.98953 -205.734666)
		(width 0.14605)
		(layer "In5.Cu")
		(net "SAS_EXP_B_PWR1")
	)
	(segment
		(start 27.868372 -200.231248)
		(end 27.587448 -200.512172)
		(width 0.14605)
		(layer "In5.Cu")
		(net "SAS_EXP_B_PWR1")
	)
	(segment
		(start 27.587448 -200.579736)
		(end 26.7589 -201.408284)
		(width 0.14605)
		(layer "In5.Cu")
		(net "SAS_EXP_B_PWR1")
	)
	(segment
		(start 26.7589 -201.408284)
		(end 26.7589 -204.504036)
		(width 0.14605)
		(layer "In5.Cu")
		(net "SAS_EXP_B_PWR1")
	)
	(segment
		(start 27.587448 -200.512172)
		(end 27.587448 -200.579736)
		(width 0.14605)
		(layer "In5.Cu")
		(net "SAS_EXP_B_PWR1")
	)
	(segment
		(start 216.941146 -166.955978)
		(end 216.071704 -166.955978)
		(width 0.09525)
		(layer "F.Cu")
		(net "SAS2X28_B_HDD3_RX_+")
	)
	(segment
		(start 215.65235 -166.782242)
		(end 215.334088 -166.46398)
		(width 0.09525)
		(layer "F.Cu")
		(net "SAS2X28_B_HDD3_RX_+")
	)
	(segment
		(start 217.410284 -167.229028)
		(end 217.275918 -167.094662)
		(width 0.09525)
		(layer "F.Cu")
		(net "SAS2X28_B_HDD3_RX_+")
	)
	(via
		(at 215.334088 -166.46398)
		(size 0.5588)
		(drill 0.3048)
		(layers "F.Cu" "B.Cu")
		(net "SAS2X28_B_HDD3_RX_+")
	)
	(arc
		(start 217.275918 -167.094662)
		(mid 217.122323 -166.992033)
		(end 216.941146 -166.955978)
		(width 0.09525)
		(layer "F.Cu")
		(net "SAS2X28_B_HDD3_RX_+")
	)
	(arc
		(start 216.071704 -166.955978)
		(mid 215.844738 -166.910832)
		(end 215.65235 -166.782242)
		(width 0.09525)
		(layer "F.Cu")
		(net "SAS2X28_B_HDD3_RX_+")
	)
	(segment
		(start 5.025898 -109.498892)
		(end 5.027422 -109.500416)
		(width 0.09525)
		(layer "B.Cu")
		(net "SAS2X28_B_HDD3_RX_+")
	)
	(segment
		(start 21.415502 -108.804202)
		(end 22.238716 -109.627416)
		(width 0.09525)
		(layer "B.Cu")
		(net "SAS2X28_B_HDD3_RX_+")
	)
	(segment
		(start 22.687788 -109.813344)
		(end 70.129146 -109.813344)
		(width 0.09525)
		(layer "B.Cu")
		(net "SAS2X28_B_HDD3_RX_+")
	)
	(segment
		(start 18.465292 -108.9279)
		(end 18.548096 -108.844842)
		(width 0.09525)
		(layer "B.Cu")
		(net "SAS2X28_B_HDD3_RX_+")
	)
	(segment
		(start 19.329146 -108.5215)
		(end 20.733004 -108.5215)
		(width 0.09525)
		(layer "B.Cu")
		(net "SAS2X28_B_HDD3_RX_+")
	)
	(segment
		(start 2.811526 -109.498892)
		(end 5.025898 -109.498892)
		(width 0.09525)
		(layer "B.Cu")
		(net "SAS2X28_B_HDD3_RX_+")
	)
	(segment
		(start 212.54847 -166.653718)
		(end 212.549486 -166.654226)
		(width 0.09525)
		(layer "B.Cu")
		(net "SAS2X28_B_HDD3_RX_+")
	)
	(segment
		(start 5.234178 -109.586014)
		(end 5.373878 -109.725714)
		(width 0.09525)
		(layer "B.Cu")
		(net "SAS2X28_B_HDD3_RX_+")
	)
	(segment
		(start 17.842992 -109.5502)
		(end 18.465292 -108.9279)
		(width 0.09525)
		(layer "B.Cu")
		(net "SAS2X28_B_HDD3_RX_+")
	)
	(segment
		(start 204.083158 -163.249864)
		(end 212.54847 -166.653718)
		(width 0.09525)
		(layer "B.Cu")
		(net "SAS2X28_B_HDD3_RX_+")
	)
	(segment
		(start 5.627116 -109.830616)
		(end 17.166082 -109.830616)
		(width 0.09525)
		(layer "B.Cu")
		(net "SAS2X28_B_HDD3_RX_+")
	)
	(segment
		(start 203.275946 -162.918902)
		(end 204.082904 -163.249864)
		(width 0.09525)
		(layer "B.Cu")
		(net "SAS2X28_B_HDD3_RX_+")
	)
	(segment
		(start 71.9074 -110.125002)
		(end 203.275946 -162.918902)
		(width 0.09525)
		(layer "B.Cu")
		(net "SAS2X28_B_HDD3_RX_+")
	)
	(segment
		(start 204.082904 -163.249864)
		(end 204.083158 -163.249864)
		(width 0.09525)
		(layer "B.Cu")
		(net "SAS2X28_B_HDD3_RX_+")
	)
	(segment
		(start 212.786468 -166.7002)
		(end 215.097868 -166.7002)
		(width 0.09525)
		(layer "B.Cu")
		(net "SAS2X28_B_HDD3_RX_+")
	)
	(arc
		(start 5.027422 -109.500416)
		(mid 5.139301 -109.52267)
		(end 5.234178 -109.586014)
		(width 0.09525)
		(layer "B.Cu")
		(net "SAS2X28_B_HDD3_RX_+")
	)
	(arc
		(start 71.218298 -109.92739)
		(mid 71.566362 -110.013945)
		(end 71.9074 -110.125002)
		(width 0.09525)
		(layer "B.Cu")
		(net "SAS2X28_B_HDD3_RX_+")
	)
	(arc
		(start 215.097868 -166.7002)
		(mid 215.264901 -166.631013)
		(end 215.334088 -166.46398)
		(width 0.09525)
		(layer "B.Cu")
		(net "SAS2X28_B_HDD3_RX_+")
	)
	(arc
		(start 17.166082 -109.830616)
		(mid 17.532435 -109.757744)
		(end 17.842992 -109.5502)
		(width 0.09525)
		(layer "B.Cu")
		(net "SAS2X28_B_HDD3_RX_+")
	)
	(arc
		(start 22.238716 -109.627416)
		(mid 22.444752 -109.765085)
		(end 22.687788 -109.813344)
		(width 0.09525)
		(layer "B.Cu")
		(net "SAS2X28_B_HDD3_RX_+")
	)
	(arc
		(start 20.733004 -108.5215)
		(mid 21.10237 -108.594971)
		(end 21.415502 -108.804202)
		(width 0.09525)
		(layer "B.Cu")
		(net "SAS2X28_B_HDD3_RX_+")
	)
	(arc
		(start 71.195184 -109.922564)
		(mid 71.206744 -109.924964)
		(end 71.218298 -109.92739)
		(width 0.09525)
		(layer "B.Cu")
		(net "SAS2X28_B_HDD3_RX_+")
	)
	(arc
		(start 70.129146 -109.813344)
		(mid 70.664954 -109.840731)
		(end 71.195184 -109.922564)
		(width 0.09525)
		(layer "B.Cu")
		(net "SAS2X28_B_HDD3_RX_+")
	)
	(arc
		(start 5.373878 -109.725714)
		(mid 5.490065 -109.803347)
		(end 5.627116 -109.830616)
		(width 0.09525)
		(layer "B.Cu")
		(net "SAS2X28_B_HDD3_RX_+")
	)
	(arc
		(start 18.548096 -108.844842)
		(mid 18.90646 -108.605484)
		(end 19.329146 -108.5215)
		(width 0.09525)
		(layer "B.Cu")
		(net "SAS2X28_B_HDD3_RX_+")
	)
	(arc
		(start 212.549486 -166.654226)
		(mid 212.665772 -166.688581)
		(end 212.786468 -166.7002)
		(width 0.09525)
		(layer "B.Cu")
		(net "SAS2X28_B_HDD3_RX_+")
	)
	(segment
		(start 13.126466 -203.0603)
		(end 12.574016 -203.0603)
		(width 0.111252)
		(layer "F.Cu")
		(net "SAS_EXP_B_PWR3")
	)
	(segment
		(start 13.136118 -203.069952)
		(end 13.126466 -203.0603)
		(width 0.111252)
		(layer "F.Cu")
		(net "SAS_EXP_B_PWR3")
	)
	(segment
		(start 21.470366 -203.069952)
		(end 13.136118 -203.069952)
		(width 0.111252)
		(layer "F.Cu")
		(net "SAS_EXP_B_PWR3")
	)
	(segment
		(start 21.480018 -203.0603)
		(end 21.470366 -203.069952)
		(width 0.111252)
		(layer "F.Cu")
		(net "SAS_EXP_B_PWR3")
	)
	(segment
		(start 196.659246 -183.9087)
		(end 196.180964 -183.9087)
		(width 0.111252)
		(layer "F.Cu")
		(net "SAS_EXP_B_PWR3")
	)
	(segment
		(start 10.285222 -201.496422)
		(end 8.84047 -201.496422)
		(width 0.111252)
		(layer "F.Cu")
		(net "SAS_EXP_B_PWR3")
	)
	(segment
		(start 195.344288 -184.104788)
		(end 194.804284 -184.104788)
		(width 0.111252)
		(layer "F.Cu")
		(net "SAS_EXP_B_PWR3")
	)
	(segment
		(start 28.2448 -203.0603)
		(end 21.480018 -203.0603)
		(width 0.111252)
		(layer "F.Cu")
		(net "SAS_EXP_B_PWR3")
	)
	(segment
		(start 196.180964 -183.9087)
		(end 195.86067 -183.588406)
		(width 0.111252)
		(layer "F.Cu")
		(net "SAS_EXP_B_PWR3")
	)
	(segment
		(start 8.832342 -201.50455)
		(end 3.19024 -201.50455)
		(width 0.111252)
		(layer "F.Cu")
		(net "SAS_EXP_B_PWR3")
	)
	(segment
		(start 12.574016 -203.0603)
		(end 11.594846 -202.08113)
		(width 0.111252)
		(layer "F.Cu")
		(net "SAS_EXP_B_PWR3")
	)
	(segment
		(start 8.84047 -201.496422)
		(end 8.832342 -201.50455)
		(width 0.111252)
		(layer "F.Cu")
		(net "SAS_EXP_B_PWR3")
	)
	(segment
		(start 11.58113 -202.08113)
		(end 11.4554 -201.9554)
		(width 0.111252)
		(layer "F.Cu")
		(net "SAS_EXP_B_PWR3")
	)
	(segment
		(start 195.86067 -183.588406)
		(end 195.344288 -184.104788)
		(width 0.111252)
		(layer "F.Cu")
		(net "SAS_EXP_B_PWR3")
	)
	(segment
		(start 11.4554 -201.9554)
		(end 10.7442 -201.9554)
		(width 0.111252)
		(layer "F.Cu")
		(net "SAS_EXP_B_PWR3")
	)
	(segment
		(start 10.7442 -201.9554)
		(end 10.285222 -201.496422)
		(width 0.111252)
		(layer "F.Cu")
		(net "SAS_EXP_B_PWR3")
	)
	(segment
		(start 11.594846 -202.08113)
		(end 11.58113 -202.08113)
		(width 0.111252)
		(layer "F.Cu")
		(net "SAS_EXP_B_PWR3")
	)
	(via
		(at 195.86067 -183.588406)
		(size 0.5588)
		(drill 0.3048)
		(layers "F.Cu" "B.Cu")
		(net "SAS_EXP_B_PWR3")
	)
	(via
		(at 195.833746 -184.5945)
		(size 0.7112)
		(drill 0.3556)
		(layers "F.Cu" "B.Cu")
		(net "SAS_EXP_B_PWR3")
	)
	(via
		(at 83.692746 -203.5937)
		(size 0.5588)
		(drill 0.3048)
		(layers "F.Cu" "B.Cu")
		(net "SAS_EXP_B_PWR3")
	)
	(via
		(at 28.2448 -203.0603)
		(size 0.5588)
		(drill 0.3048)
		(layers "F.Cu" "B.Cu")
		(net "SAS_EXP_B_PWR3")
	)
	(segment
		(start 195.86067 -183.588406)
		(end 195.833746 -183.6547)
		(width 0.111252)
		(layer "B.Cu")
		(net "SAS_EXP_B_PWR3")
	)
	(segment
		(start 195.833746 -183.6547)
		(end 195.833746 -184.5945)
		(width 0.111252)
		(layer "B.Cu")
		(net "SAS_EXP_B_PWR3")
	)
	(segment
		(start 195.86067 -183.588406)
		(end 103.69804 -183.588406)
		(width 0.14605)
		(layer "In2.Cu")
		(net "SAS_EXP_B_PWR3")
	)
	(segment
		(start 103.69804 -183.588406)
		(end 83.692746 -203.5937)
		(width 0.14605)
		(layer "In2.Cu")
		(net "SAS_EXP_B_PWR3")
	)
	(segment
		(start 77.83322 -201.40295)
		(end 77.650594 -201.585576)
		(width 0.14605)
		(layer "In5.Cu")
		(net "SAS_EXP_B_PWR3")
	)
	(segment
		(start 49.81702 -201.40295)
		(end 49.507394 -201.712576)
		(width 0.14605)
		(layer "In5.Cu")
		(net "SAS_EXP_B_PWR3")
	)
	(segment
		(start 77.976222 -202.371452)
		(end 78.43647 -202.371452)
		(width 0.14605)
		(layer "In5.Cu")
		(net "SAS_EXP_B_PWR3")
	)
	(segment
		(start 72.545194 -201.661776)
		(end 72.545194 -202.122024)
		(width 0.14605)
		(layer "In5.Cu")
		(net "SAS_EXP_B_PWR3")
	)
	(segment
		(start 78.579472 -201.40295)
		(end 81.501996 -201.40295)
		(width 0.14605)
		(layer "In5.Cu")
		(net "SAS_EXP_B_PWR3")
	)
	(segment
		(start 57.93867 -202.498452)
		(end 58.264298 -202.172824)
		(width 0.14605)
		(layer "In5.Cu")
		(net "SAS_EXP_B_PWR3")
	)
	(segment
		(start 62.207394 -202.172824)
		(end 62.533022 -202.498452)
		(width 0.14605)
		(layer "In5.Cu")
		(net "SAS_EXP_B_PWR3")
	)
	(segment
		(start 58.264298 -202.172824)
		(end 58.264298 -201.712576)
		(width 0.14605)
		(layer "In5.Cu")
		(net "SAS_EXP_B_PWR3")
	)
	(segment
		(start 62.99327 -202.498452)
		(end 63.318898 -202.172824)
		(width 0.14605)
		(layer "In5.Cu")
		(net "SAS_EXP_B_PWR3")
	)
	(segment
		(start 57.152794 -201.712576)
		(end 57.152794 -202.172824)
		(width 0.14605)
		(layer "In5.Cu")
		(net "SAS_EXP_B_PWR3")
	)
	(segment
		(start 50.618898 -201.712576)
		(end 50.309272 -201.40295)
		(width 0.14605)
		(layer "In5.Cu")
		(net "SAS_EXP_B_PWR3")
	)
	(segment
		(start 29.90215 -201.40295)
		(end 49.81702 -201.40295)
		(width 0.14605)
		(layer "In5.Cu")
		(net "SAS_EXP_B_PWR3")
	)
	(segment
		(start 62.533022 -202.498452)
		(end 62.99327 -202.498452)
		(width 0.14605)
		(layer "In5.Cu")
		(net "SAS_EXP_B_PWR3")
	)
	(segment
		(start 78.762098 -201.585576)
		(end 78.579472 -201.40295)
		(width 0.14605)
		(layer "In5.Cu")
		(net "SAS_EXP_B_PWR3")
	)
	(segment
		(start 77.650594 -202.045824)
		(end 77.976222 -202.371452)
		(width 0.14605)
		(layer "In5.Cu")
		(net "SAS_EXP_B_PWR3")
	)
	(segment
		(start 63.318898 -202.172824)
		(end 63.318898 -201.712576)
		(width 0.14605)
		(layer "In5.Cu")
		(net "SAS_EXP_B_PWR3")
	)
	(segment
		(start 62.51702 -201.40295)
		(end 62.207394 -201.712576)
		(width 0.14605)
		(layer "In5.Cu")
		(net "SAS_EXP_B_PWR3")
	)
	(segment
		(start 57.46242 -201.40295)
		(end 57.152794 -201.712576)
		(width 0.14605)
		(layer "In5.Cu")
		(net "SAS_EXP_B_PWR3")
	)
	(segment
		(start 63.318898 -201.712576)
		(end 63.009272 -201.40295)
		(width 0.14605)
		(layer "In5.Cu")
		(net "SAS_EXP_B_PWR3")
	)
	(segment
		(start 73.33107 -202.447652)
		(end 73.656698 -202.122024)
		(width 0.14605)
		(layer "In5.Cu")
		(net "SAS_EXP_B_PWR3")
	)
	(segment
		(start 73.656698 -202.122024)
		(end 73.656698 -201.661776)
		(width 0.14605)
		(layer "In5.Cu")
		(net "SAS_EXP_B_PWR3")
	)
	(segment
		(start 72.545194 -202.122024)
		(end 72.870822 -202.447652)
		(width 0.14605)
		(layer "In5.Cu")
		(net "SAS_EXP_B_PWR3")
	)
	(segment
		(start 49.833022 -202.498452)
		(end 50.29327 -202.498452)
		(width 0.14605)
		(layer "In5.Cu")
		(net "SAS_EXP_B_PWR3")
	)
	(segment
		(start 49.507394 -201.712576)
		(end 49.507394 -202.172824)
		(width 0.14605)
		(layer "In5.Cu")
		(net "SAS_EXP_B_PWR3")
	)
	(segment
		(start 57.152794 -202.172824)
		(end 57.478422 -202.498452)
		(width 0.14605)
		(layer "In5.Cu")
		(net "SAS_EXP_B_PWR3")
	)
	(segment
		(start 63.009272 -201.40295)
		(end 72.80402 -201.40295)
		(width 0.14605)
		(layer "In5.Cu")
		(net "SAS_EXP_B_PWR3")
	)
	(segment
		(start 73.656698 -201.661776)
		(end 73.397872 -201.40295)
		(width 0.14605)
		(layer "In5.Cu")
		(net "SAS_EXP_B_PWR3")
	)
	(segment
		(start 73.397872 -201.40295)
		(end 77.83322 -201.40295)
		(width 0.14605)
		(layer "In5.Cu")
		(net "SAS_EXP_B_PWR3")
	)
	(segment
		(start 81.501996 -201.40295)
		(end 83.692746 -203.5937)
		(width 0.14605)
		(layer "In5.Cu")
		(net "SAS_EXP_B_PWR3")
	)
	(segment
		(start 50.309272 -201.40295)
		(end 57.46242 -201.40295)
		(width 0.14605)
		(layer "In5.Cu")
		(net "SAS_EXP_B_PWR3")
	)
	(segment
		(start 78.762098 -202.045824)
		(end 78.762098 -201.585576)
		(width 0.14605)
		(layer "In5.Cu")
		(net "SAS_EXP_B_PWR3")
	)
	(segment
		(start 57.478422 -202.498452)
		(end 57.93867 -202.498452)
		(width 0.14605)
		(layer "In5.Cu")
		(net "SAS_EXP_B_PWR3")
	)
	(segment
		(start 62.207394 -201.712576)
		(end 62.207394 -202.172824)
		(width 0.14605)
		(layer "In5.Cu")
		(net "SAS_EXP_B_PWR3")
	)
	(segment
		(start 72.80402 -201.40295)
		(end 72.545194 -201.661776)
		(width 0.14605)
		(layer "In5.Cu")
		(net "SAS_EXP_B_PWR3")
	)
	(segment
		(start 49.507394 -202.172824)
		(end 49.833022 -202.498452)
		(width 0.14605)
		(layer "In5.Cu")
		(net "SAS_EXP_B_PWR3")
	)
	(segment
		(start 57.954672 -201.40295)
		(end 62.51702 -201.40295)
		(width 0.14605)
		(layer "In5.Cu")
		(net "SAS_EXP_B_PWR3")
	)
	(segment
		(start 50.618898 -202.172824)
		(end 50.618898 -201.712576)
		(width 0.14605)
		(layer "In5.Cu")
		(net "SAS_EXP_B_PWR3")
	)
	(segment
		(start 78.43647 -202.371452)
		(end 78.762098 -202.045824)
		(width 0.14605)
		(layer "In5.Cu")
		(net "SAS_EXP_B_PWR3")
	)
	(segment
		(start 58.264298 -201.712576)
		(end 57.954672 -201.40295)
		(width 0.14605)
		(layer "In5.Cu")
		(net "SAS_EXP_B_PWR3")
	)
	(segment
		(start 50.29327 -202.498452)
		(end 50.618898 -202.172824)
		(width 0.14605)
		(layer "In5.Cu")
		(net "SAS_EXP_B_PWR3")
	)
	(segment
		(start 77.650594 -201.585576)
		(end 77.650594 -202.045824)
		(width 0.14605)
		(layer "In5.Cu")
		(net "SAS_EXP_B_PWR3")
	)
	(segment
		(start 72.870822 -202.447652)
		(end 73.33107 -202.447652)
		(width 0.14605)
		(layer "In5.Cu")
		(net "SAS_EXP_B_PWR3")
	)
	(segment
		(start 28.2448 -203.0603)
		(end 29.90215 -201.40295)
		(width 0.14605)
		(layer "In5.Cu")
		(net "SAS_EXP_B_PWR3")
	)
	(segment
		(start 223.391984 -164.705792)
		(end 223.163384 -164.934392)
		(width 0.09525)
		(layer "F.Cu")
		(net "SAS2X28_B_HDD3_TX_-")
	)
	(segment
		(start 4.836922 -112.50041)
		(end 4.835398 -112.498886)
		(width 0.09525)
		(layer "F.Cu")
		(net "SAS2X28_B_HDD3_TX_-")
	)
	(segment
		(start 4.835398 -112.498886)
		(end 3.192526 -112.498886)
		(width 0.09525)
		(layer "F.Cu")
		(net "SAS2X28_B_HDD3_TX_-")
	)
	(segment
		(start 6.349746 -112.160812)
		(end 5.656834 -112.160812)
		(width 0.09525)
		(layer "F.Cu")
		(net "SAS2X28_B_HDD3_TX_-")
	)
	(segment
		(start 224.489264 -164.789866)
		(end 224.485962 -164.786564)
		(width 0.09525)
		(layer "F.Cu")
		(net "SAS2X28_B_HDD3_TX_-")
	)
	(segment
		(start 5.656834 -112.160812)
		(end 5.65658 -112.160558)
		(width 0.09525)
		(layer "F.Cu")
		(net "SAS2X28_B_HDD3_TX_-")
	)
	(segment
		(start 224.04705 -164.6047)
		(end 223.636078 -164.6047)
		(width 0.09525)
		(layer "F.Cu")
		(net "SAS2X28_B_HDD3_TX_-")
	)
	(segment
		(start 225.399854 -164.789866)
		(end 224.489264 -164.789866)
		(width 0.09525)
		(layer "F.Cu")
		(net "SAS2X28_B_HDD3_TX_-")
	)
	(via
		(at 6.756146 -112.458246)
		(size 0.5588)
		(drill 0.3048)
		(layers "F.Cu" "B.Cu")
		(net "SAS2X28_B_HDD3_TX_-")
	)
	(via
		(at 223.163384 -164.934392)
		(size 0.5588)
		(drill 0.3048)
		(layers "F.Cu" "B.Cu")
		(net "SAS2X28_B_HDD3_TX_-")
	)
	(arc
		(start 5.43941 -112.20958)
		(mid 5.365724 -112.253056)
		(end 5.300472 -112.308386)
		(width 0.09525)
		(layer "F.Cu")
		(net "SAS2X28_B_HDD3_TX_-")
	)
	(arc
		(start 5.500878 -112.18545)
		(mid 5.480008 -112.192612)
		(end 5.459476 -112.20069)
		(width 0.09525)
		(layer "F.Cu")
		(net "SAS2X28_B_HDD3_TX_-")
	)
	(arc
		(start 5.459476 -112.20069)
		(mid 5.449394 -112.205024)
		(end 5.43941 -112.20958)
		(width 0.09525)
		(layer "F.Cu")
		(net "SAS2X28_B_HDD3_TX_-")
	)
	(arc
		(start 224.485962 -164.786564)
		(mid 224.347936 -164.759109)
		(end 224.230946 -164.6809)
		(width 0.09525)
		(layer "F.Cu")
		(net "SAS2X28_B_HDD3_TX_-")
	)
	(arc
		(start 6.756146 -112.458246)
		(mid 6.601532 -112.243164)
		(end 6.349746 -112.160812)
		(width 0.09525)
		(layer "F.Cu")
		(net "SAS2X28_B_HDD3_TX_-")
	)
	(arc
		(start 5.65658 -112.160558)
		(mid 5.650611 -112.160524)
		(end 5.644642 -112.160558)
		(width 0.09525)
		(layer "F.Cu")
		(net "SAS2X28_B_HDD3_TX_-")
	)
	(arc
		(start 5.644642 -112.160558)
		(mid 5.586639 -112.165349)
		(end 5.52958 -112.176814)
		(width 0.09525)
		(layer "F.Cu")
		(net "SAS2X28_B_HDD3_TX_-")
	)
	(arc
		(start 5.52958 -112.176814)
		(mid 5.515164 -112.180917)
		(end 5.500878 -112.18545)
		(width 0.09525)
		(layer "F.Cu")
		(net "SAS2X28_B_HDD3_TX_-")
	)
	(arc
		(start 223.636078 -164.6047)
		(mid 223.625787 -164.6048)
		(end 223.615504 -164.605208)
		(width 0.09525)
		(layer "F.Cu")
		(net "SAS2X28_B_HDD3_TX_-")
	)
	(arc
		(start 223.615504 -164.605208)
		(mid 223.494491 -164.634958)
		(end 223.391984 -164.705792)
		(width 0.09525)
		(layer "F.Cu")
		(net "SAS2X28_B_HDD3_TX_-")
	)
	(arc
		(start 224.230946 -164.6809)
		(mid 224.146574 -164.624524)
		(end 224.04705 -164.6047)
		(width 0.09525)
		(layer "F.Cu")
		(net "SAS2X28_B_HDD3_TX_-")
	)
	(arc
		(start 5.300472 -112.308386)
		(mid 5.087793 -112.450493)
		(end 4.836922 -112.50041)
		(width 0.09525)
		(layer "F.Cu")
		(net "SAS2X28_B_HDD3_TX_-")
	)
	(segment
		(start 7.398004 -112.144048)
		(end 41.215564 -112.144048)
		(width 0.09525)
		(layer "B.Cu")
		(net "SAS2X28_B_HDD3_TX_-")
	)
	(segment
		(start 45.897546 -115.788948)
		(end 46.085506 -115.863878)
		(width 0.09525)
		(layer "B.Cu")
		(net "SAS2X28_B_HDD3_TX_-")
	)
	(segment
		(start 46.215046 -115.904518)
		(end 211.854796 -167.90035)
		(width 0.09525)
		(layer "B.Cu")
		(net "SAS2X28_B_HDD3_TX_-")
	)
	(segment
		(start 46.188122 -115.904518)
		(end 46.215046 -115.904518)
		(width 0.09525)
		(layer "B.Cu")
		(net "SAS2X28_B_HDD3_TX_-")
	)
	(segment
		(start 41.61663 -112.286542)
		(end 45.686726 -115.662202)
		(width 0.09525)
		(layer "B.Cu")
		(net "SAS2X28_B_HDD3_TX_-")
	)
	(segment
		(start 222.922592 -164.6936)
		(end 223.163384 -164.934392)
		(width 0.09525)
		(layer "B.Cu")
		(net "SAS2X28_B_HDD3_TX_-")
	)
	(segment
		(start 46.085506 -115.863878)
		(end 46.188122 -115.904518)
		(width 0.09525)
		(layer "B.Cu")
		(net "SAS2X28_B_HDD3_TX_-")
	)
	(segment
		(start 212.311234 -167.9702)
		(end 215.799162 -167.9702)
		(width 0.09525)
		(layer "B.Cu")
		(net "SAS2X28_B_HDD3_TX_-")
	)
	(segment
		(start 45.686726 -115.662202)
		(end 45.897546 -115.788948)
		(width 0.09525)
		(layer "B.Cu")
		(net "SAS2X28_B_HDD3_TX_-")
	)
	(segment
		(start 220.126306 -164.574982)
		(end 222.636334 -164.574982)
		(width 0.09525)
		(layer "B.Cu")
		(net "SAS2X28_B_HDD3_TX_-")
	)
	(segment
		(start 216.87663 -167.523922)
		(end 219.612972 -164.78758)
		(width 0.09525)
		(layer "B.Cu")
		(net "SAS2X28_B_HDD3_TX_-")
	)
	(arc
		(start 41.215564 -112.144048)
		(mid 41.428394 -112.180686)
		(end 41.61663 -112.286542)
		(width 0.09525)
		(layer "B.Cu")
		(net "SAS2X28_B_HDD3_TX_-")
	)
	(arc
		(start 215.799162 -167.9702)
		(mid 216.382274 -167.854212)
		(end 216.87663 -167.523922)
		(width 0.09525)
		(layer "B.Cu")
		(net "SAS2X28_B_HDD3_TX_-")
	)
	(arc
		(start 222.636334 -164.574982)
		(mid 222.791273 -164.605801)
		(end 222.922592 -164.6936)
		(width 0.09525)
		(layer "B.Cu")
		(net "SAS2X28_B_HDD3_TX_-")
	)
	(arc
		(start 211.854796 -167.90035)
		(mid 212.080353 -167.952675)
		(end 212.311234 -167.9702)
		(width 0.09525)
		(layer "B.Cu")
		(net "SAS2X28_B_HDD3_TX_-")
	)
	(arc
		(start 6.756146 -112.458246)
		(mid 7.042493 -112.230483)
		(end 7.398004 -112.144048)
		(width 0.09525)
		(layer "B.Cu")
		(net "SAS2X28_B_HDD3_TX_-")
	)
	(arc
		(start 219.612972 -164.78758)
		(mid 219.848492 -164.630211)
		(end 220.126306 -164.574982)
		(width 0.09525)
		(layer "B.Cu")
		(net "SAS2X28_B_HDD3_TX_-")
	)
	(segment
		(start 224.029016 -164.2745)
		(end 223.5835 -164.2745)
		(width 0.09525)
		(layer "F.Cu")
		(net "SAS2X28_B_HDD3_TX_+")
	)
	(segment
		(start 4.830572 -111.498888)
		(end 3.192526 -111.498888)
		(width 0.09525)
		(layer "F.Cu")
		(net "SAS2X28_B_HDD3_TX_+")
	)
	(segment
		(start 225.399854 -163.99002)
		(end 224.619312 -163.99002)
		(width 0.09525)
		(layer "F.Cu")
		(net "SAS2X28_B_HDD3_TX_+")
	)
	(segment
		(start 4.832096 -111.500412)
		(end 4.830572 -111.498888)
		(width 0.09525)
		(layer "F.Cu")
		(net "SAS2X28_B_HDD3_TX_+")
	)
	(segment
		(start 224.319846 -164.1094)
		(end 224.243646 -164.1856)
		(width 0.09525)
		(layer "F.Cu")
		(net "SAS2X28_B_HDD3_TX_+")
	)
	(segment
		(start 223.376744 -164.188902)
		(end 223.163384 -163.975542)
		(width 0.09525)
		(layer "F.Cu")
		(net "SAS2X28_B_HDD3_TX_+")
	)
	(segment
		(start 224.619312 -163.99002)
		(end 224.61601 -163.986718)
		(width 0.09525)
		(layer "F.Cu")
		(net "SAS2X28_B_HDD3_TX_+")
	)
	(segment
		(start 6.349746 -111.830612)
		(end 5.636514 -111.830612)
		(width 0.09525)
		(layer "F.Cu")
		(net "SAS2X28_B_HDD3_TX_+")
	)
	(via
		(at 6.728968 -111.5949)
		(size 0.5588)
		(drill 0.3048)
		(layers "F.Cu" "B.Cu")
		(net "SAS2X28_B_HDD3_TX_+")
	)
	(via
		(at 223.163384 -163.975542)
		(size 0.5588)
		(drill 0.3048)
		(layers "F.Cu" "B.Cu")
		(net "SAS2X28_B_HDD3_TX_+")
	)
	(arc
		(start 224.61601 -163.986718)
		(mid 224.455725 -164.018601)
		(end 224.319846 -164.1094)
		(width 0.09525)
		(layer "F.Cu")
		(net "SAS2X28_B_HDD3_TX_+")
	)
	(arc
		(start 223.5835 -164.2745)
		(mid 223.471621 -164.252246)
		(end 223.376744 -164.188902)
		(width 0.09525)
		(layer "F.Cu")
		(net "SAS2X28_B_HDD3_TX_+")
	)
	(arc
		(start 6.728968 -111.5949)
		(mid 6.573 -111.766882)
		(end 6.349746 -111.830612)
		(width 0.09525)
		(layer "F.Cu")
		(net "SAS2X28_B_HDD3_TX_+")
	)
	(arc
		(start 5.194808 -111.653066)
		(mid 5.126614 -111.566146)
		(end 5.023358 -111.526828)
		(width 0.09525)
		(layer "F.Cu")
		(net "SAS2X28_B_HDD3_TX_+")
	)
	(arc
		(start 5.434838 -111.816134)
		(mid 5.289725 -111.771522)
		(end 5.194808 -111.653066)
		(width 0.09525)
		(layer "F.Cu")
		(net "SAS2X28_B_HDD3_TX_+")
	)
	(arc
		(start 224.243646 -164.1856)
		(mid 224.145173 -164.251398)
		(end 224.029016 -164.2745)
		(width 0.09525)
		(layer "F.Cu")
		(net "SAS2X28_B_HDD3_TX_+")
	)
	(arc
		(start 5.636514 -111.830612)
		(mid 5.535416 -111.827002)
		(end 5.434838 -111.816134)
		(width 0.09525)
		(layer "F.Cu")
		(net "SAS2X28_B_HDD3_TX_+")
	)
	(arc
		(start 5.023358 -111.526828)
		(mid 4.92863 -111.507085)
		(end 4.832096 -111.500412)
		(width 0.09525)
		(layer "F.Cu")
		(net "SAS2X28_B_HDD3_TX_+")
	)
	(segment
		(start 46.196758 -115.552728)
		(end 46.197774 -115.552728)
		(width 0.09525)
		(layer "B.Cu")
		(net "SAS2X28_B_HDD3_TX_+")
	)
	(segment
		(start 222.976186 -164.16274)
		(end 223.163384 -163.975542)
		(width 0.09525)
		(layer "B.Cu")
		(net "SAS2X28_B_HDD3_TX_+")
	)
	(segment
		(start 41.826434 -112.031526)
		(end 41.82745 -112.032288)
		(width 0.09525)
		(layer "B.Cu")
		(net "SAS2X28_B_HDD3_TX_+")
	)
	(segment
		(start 45.88002 -115.392708)
		(end 46.044866 -115.492022)
		(width 0.09525)
		(layer "B.Cu")
		(net "SAS2X28_B_HDD3_TX_+")
	)
	(segment
		(start 46.197774 -115.552728)
		(end 211.953602 -167.585136)
		(width 0.09525)
		(layer "B.Cu")
		(net "SAS2X28_B_HDD3_TX_+")
	)
	(segment
		(start 212.311234 -167.64)
		(end 215.799162 -167.64)
		(width 0.09525)
		(layer "B.Cu")
		(net "SAS2X28_B_HDD3_TX_+")
	)
	(segment
		(start 41.82491 -112.03051)
		(end 41.82491 -112.030256)
		(width 0.09525)
		(layer "B.Cu")
		(net "SAS2X28_B_HDD3_TX_+")
	)
	(segment
		(start 220.125544 -164.244782)
		(end 222.778066 -164.244782)
		(width 0.09525)
		(layer "B.Cu")
		(net "SAS2X28_B_HDD3_TX_+")
	)
	(segment
		(start 46.044866 -115.492022)
		(end 46.196758 -115.552728)
		(width 0.09525)
		(layer "B.Cu")
		(net "SAS2X28_B_HDD3_TX_+")
	)
	(segment
		(start 45.540168 -115.111276)
		(end 45.88002 -115.392708)
		(width 0.09525)
		(layer "B.Cu")
		(net "SAS2X28_B_HDD3_TX_+")
	)
	(segment
		(start 41.82745 -112.032288)
		(end 45.540168 -115.111276)
		(width 0.09525)
		(layer "B.Cu")
		(net "SAS2X28_B_HDD3_TX_+")
	)
	(segment
		(start 216.64295 -167.290242)
		(end 219.379292 -164.5539)
		(width 0.09525)
		(layer "B.Cu")
		(net "SAS2X28_B_HDD3_TX_+")
	)
	(segment
		(start 7.391146 -111.813848)
		(end 41.215564 -111.813848)
		(width 0.09525)
		(layer "B.Cu")
		(net "SAS2X28_B_HDD3_TX_+")
	)
	(arc
		(start 215.799162 -167.64)
		(mid 216.255859 -167.549064)
		(end 216.64295 -167.290242)
		(width 0.09525)
		(layer "B.Cu")
		(net "SAS2X28_B_HDD3_TX_+")
	)
	(arc
		(start 219.379292 -164.5539)
		(mid 219.721675 -164.325127)
		(end 220.125544 -164.244782)
		(width 0.09525)
		(layer "B.Cu")
		(net "SAS2X28_B_HDD3_TX_+")
	)
	(arc
		(start 211.953602 -167.585136)
		(mid 212.130329 -167.626178)
		(end 212.311234 -167.64)
		(width 0.09525)
		(layer "B.Cu")
		(net "SAS2X28_B_HDD3_TX_+")
	)
	(arc
		(start 41.82491 -112.030256)
		(mid 41.825672 -112.030891)
		(end 41.826434 -112.031526)
		(width 0.09525)
		(layer "B.Cu")
		(net "SAS2X28_B_HDD3_TX_+")
	)
	(arc
		(start 222.778066 -164.244782)
		(mid 222.885279 -164.223456)
		(end 222.976186 -164.16274)
		(width 0.09525)
		(layer "B.Cu")
		(net "SAS2X28_B_HDD3_TX_+")
	)
	(arc
		(start 6.728968 -111.5949)
		(mid 7.042426 -111.757701)
		(end 7.391146 -111.813848)
		(width 0.09525)
		(layer "B.Cu")
		(net "SAS2X28_B_HDD3_TX_+")
	)
	(arc
		(start 41.215564 -111.813848)
		(mid 41.538923 -111.869625)
		(end 41.82491 -112.03051)
		(width 0.09525)
		(layer "B.Cu")
		(net "SAS2X28_B_HDD3_TX_+")
	)
	(segment
		(start 216.966546 -166.625778)
		(end 216.55024 -166.625778)
		(width 0.09525)
		(layer "F.Cu")
		(net "SAS2X28_B_HDD3_RX_-")
	)
	(segment
		(start 217.410284 -166.340028)
		(end 217.236294 -166.514018)
		(width 0.09525)
		(layer "F.Cu")
		(net "SAS2X28_B_HDD3_RX_-")
	)
	(via
		(at 216.197688 -166.479728)
		(size 0.5588)
		(drill 0.3048)
		(layers "F.Cu" "B.Cu")
		(net "SAS2X28_B_HDD3_RX_-")
	)
	(arc
		(start 217.236294 -166.514018)
		(mid 217.112533 -166.596713)
		(end 216.966546 -166.625778)
		(width 0.09525)
		(layer "F.Cu")
		(net "SAS2X28_B_HDD3_RX_-")
	)
	(arc
		(start 216.55024 -166.625778)
		(mid 216.359433 -166.587824)
		(end 216.197688 -166.479728)
		(width 0.09525)
		(layer "F.Cu")
		(net "SAS2X28_B_HDD3_RX_-")
	)
	(segment
		(start 21.181822 -109.037628)
		(end 22.005036 -109.860842)
		(width 0.09525)
		(layer "B.Cu")
		(net "SAS2X28_B_HDD3_RX_-")
	)
	(segment
		(start 4.93014 -110.49889)
		(end 4.931664 -110.500414)
		(width 0.09525)
		(layer "B.Cu")
		(net "SAS2X28_B_HDD3_RX_-")
	)
	(segment
		(start 22.687534 -110.143544)
		(end 70.129146 -110.143544)
		(width 0.09525)
		(layer "B.Cu")
		(net "SAS2X28_B_HDD3_RX_-")
	)
	(segment
		(start 5.285994 -110.353602)
		(end 5.349494 -110.290102)
		(width 0.09525)
		(layer "B.Cu")
		(net "SAS2X28_B_HDD3_RX_-")
	)
	(segment
		(start 202.848972 -163.103306)
		(end 203.95819 -163.55568)
		(width 0.09525)
		(layer "B.Cu")
		(net "SAS2X28_B_HDD3_RX_-")
	)
	(segment
		(start 215.893904 -166.783512)
		(end 216.197688 -166.479728)
		(width 0.09525)
		(layer "B.Cu")
		(net "SAS2X28_B_HDD3_RX_-")
	)
	(segment
		(start 212.785198 -167.0304)
		(end 215.297766 -167.0304)
		(width 0.09525)
		(layer "B.Cu")
		(net "SAS2X28_B_HDD3_RX_-")
	)
	(segment
		(start 5.66166 -110.160816)
		(end 17.144746 -110.160816)
		(width 0.09525)
		(layer "B.Cu")
		(net "SAS2X28_B_HDD3_RX_-")
	)
	(segment
		(start 203.959968 -163.556442)
		(end 203.960222 -163.556442)
		(width 0.09525)
		(layer "B.Cu")
		(net "SAS2X28_B_HDD3_RX_-")
	)
	(segment
		(start 19.329146 -108.8517)
		(end 20.73275 -108.8517)
		(width 0.09525)
		(layer "B.Cu")
		(net "SAS2X28_B_HDD3_RX_-")
	)
	(segment
		(start 71.817738 -110.445042)
		(end 202.848972 -163.103306)
		(width 0.09525)
		(layer "B.Cu")
		(net "SAS2X28_B_HDD3_RX_-")
	)
	(segment
		(start 18.091912 -109.76864)
		(end 18.127472 -109.732826)
		(width 0.09525)
		(layer "B.Cu")
		(net "SAS2X28_B_HDD3_RX_-")
	)
	(segment
		(start 203.95819 -163.55568)
		(end 203.959968 -163.556442)
		(width 0.09525)
		(layer "B.Cu")
		(net "SAS2X28_B_HDD3_RX_-")
	)
	(segment
		(start 18.127472 -109.732826)
		(end 18.775172 -109.085126)
		(width 0.09525)
		(layer "B.Cu")
		(net "SAS2X28_B_HDD3_RX_-")
	)
	(segment
		(start 18.775172 -109.085126)
		(end 18.781776 -109.078268)
		(width 0.09525)
		(layer "B.Cu")
		(net "SAS2X28_B_HDD3_RX_-")
	)
	(segment
		(start 2.811526 -110.49889)
		(end 4.93014 -110.49889)
		(width 0.09525)
		(layer "B.Cu")
		(net "SAS2X28_B_HDD3_RX_-")
	)
	(segment
		(start 203.960222 -163.556442)
		(end 212.425026 -166.960804)
		(width 0.09525)
		(layer "B.Cu")
		(net "SAS2X28_B_HDD3_RX_-")
	)
	(arc
		(start 22.005036 -109.860842)
		(mid 22.318169 -110.070071)
		(end 22.687534 -110.143544)
		(width 0.09525)
		(layer "B.Cu")
		(net "SAS2X28_B_HDD3_RX_-")
	)
	(arc
		(start 18.781776 -109.078268)
		(mid 19.032927 -108.910548)
		(end 19.329146 -108.8517)
		(width 0.09525)
		(layer "B.Cu")
		(net "SAS2X28_B_HDD3_RX_-")
	)
	(arc
		(start 17.144746 -110.160816)
		(mid 17.657344 -110.058948)
		(end 18.091912 -109.76864)
		(width 0.09525)
		(layer "B.Cu")
		(net "SAS2X28_B_HDD3_RX_-")
	)
	(arc
		(start 4.931664 -110.500414)
		(mid 5.123443 -110.462267)
		(end 5.285994 -110.353602)
		(width 0.09525)
		(layer "B.Cu")
		(net "SAS2X28_B_HDD3_RX_-")
	)
	(arc
		(start 215.297766 -167.0304)
		(mid 215.620378 -166.966228)
		(end 215.893904 -166.783512)
		(width 0.09525)
		(layer "B.Cu")
		(net "SAS2X28_B_HDD3_RX_-")
	)
	(arc
		(start 20.73275 -108.8517)
		(mid 20.975754 -108.900036)
		(end 21.181822 -109.037628)
		(width 0.09525)
		(layer "B.Cu")
		(net "SAS2X28_B_HDD3_RX_-")
	)
	(arc
		(start 5.349494 -110.290102)
		(mid 5.492717 -110.194403)
		(end 5.66166 -110.160816)
		(width 0.09525)
		(layer "B.Cu")
		(net "SAS2X28_B_HDD3_RX_-")
	)
	(arc
		(start 71.15048 -110.248192)
		(mid 71.48818 -110.33282)
		(end 71.817738 -110.445042)
		(width 0.09525)
		(layer "B.Cu")
		(net "SAS2X28_B_HDD3_RX_-")
	)
	(arc
		(start 70.129146 -110.143544)
		(mid 70.642488 -110.169759)
		(end 71.15048 -110.248192)
		(width 0.09525)
		(layer "B.Cu")
		(net "SAS2X28_B_HDD3_RX_-")
	)
	(arc
		(start 212.425026 -166.960804)
		(mid 212.601774 -167.012879)
		(end 212.785198 -167.0304)
		(width 0.09525)
		(layer "B.Cu")
		(net "SAS2X28_B_HDD3_RX_-")
	)
	(segment
		(start 23.024846 -363.206792)
		(end 23.024846 -368.3127)
		(width 0.09525)
		(layer "F.Cu")
		(net "SAS2X28_A_HDD3_TX_-")
	)
	(segment
		(start 9.339072 -382.16078)
		(end 5.499862 -382.16078)
		(width 0.09525)
		(layer "F.Cu")
		(net "SAS2X28_A_HDD3_TX_-")
	)
	(segment
		(start 223.249998 -157.340046)
		(end 221.980252 -157.340046)
		(width 0.09525)
		(layer "F.Cu")
		(net "SAS2X28_A_HDD3_TX_-")
	)
	(segment
		(start 22.452076 -369.695476)
		(end 10.44448 -381.703072)
		(width 0.09525)
		(layer "F.Cu")
		(net "SAS2X28_A_HDD3_TX_-")
	)
	(segment
		(start 4.67868 -382.498854)
		(end 3.192526 -382.498854)
		(width 0.09525)
		(layer "F.Cu")
		(net "SAS2X28_A_HDD3_TX_-")
	)
	(segment
		(start 4.680204 -382.500378)
		(end 4.67868 -382.498854)
		(width 0.09525)
		(layer "F.Cu")
		(net "SAS2X28_A_HDD3_TX_-")
	)
	(segment
		(start 196.885814 -156.866844)
		(end 196.87159 -156.868876)
		(width 0.09525)
		(layer "F.Cu")
		(net "SAS2X28_A_HDD3_TX_-")
	)
	(segment
		(start 221.741746 -157.15107)
		(end 221.741746 -157.101794)
		(width 0.09525)
		(layer "F.Cu")
		(net "SAS2X28_A_HDD3_TX_-")
	)
	(segment
		(start 104.386888 -270.685006)
		(end 66.455036 -317.669926)
		(width 0.09525)
		(layer "F.Cu")
		(net "SAS2X28_A_HDD3_TX_-")
	)
	(segment
		(start 61.041534 -324.375272)
		(end 23.601172 -361.81538)
		(width 0.09525)
		(layer "F.Cu")
		(net "SAS2X28_A_HDD3_TX_-")
	)
	(segment
		(start 221.506796 -156.866844)
		(end 196.885814 -156.866844)
		(width 0.09525)
		(layer "F.Cu")
		(net "SAS2X28_A_HDD3_TX_-")
	)
	(segment
		(start 196.018658 -157.184344)
		(end 104.386888 -270.685006)
		(width 0.09525)
		(layer "F.Cu")
		(net "SAS2X28_A_HDD3_TX_-")
	)
	(segment
		(start 221.811596 -157.270196)
		(end 221.776544 -157.235144)
		(width 0.09525)
		(layer "F.Cu")
		(net "SAS2X28_A_HDD3_TX_-")
	)
	(segment
		(start 196.87159 -156.868876)
		(end 196.795644 -156.868876)
		(width 0.09525)
		(layer "F.Cu")
		(net "SAS2X28_A_HDD3_TX_-")
	)
	(segment
		(start 66.455036 -317.669926)
		(end 61.041534 -324.375272)
		(width 0.09525)
		(layer "F.Cu")
		(net "SAS2X28_A_HDD3_TX_-")
	)
	(arc
		(start 23.024846 -368.3127)
		(mid 22.875989 -369.061055)
		(end 22.452076 -369.695476)
		(width 0.09525)
		(layer "F.Cu")
		(net "SAS2X28_A_HDD3_TX_-")
	)
	(arc
		(start 221.776544 -157.235144)
		(mid 221.75077 -157.196571)
		(end 221.741746 -157.15107)
		(width 0.09525)
		(layer "F.Cu")
		(net "SAS2X28_A_HDD3_TX_-")
	)
	(arc
		(start 5.499862 -382.16078)
		(mid 5.372139 -382.186186)
		(end 5.263896 -382.25857)
		(width 0.09525)
		(layer "F.Cu")
		(net "SAS2X28_A_HDD3_TX_-")
	)
	(arc
		(start 221.509336 -156.866844)
		(mid 221.508066 -156.866841)
		(end 221.506796 -156.866844)
		(width 0.09525)
		(layer "F.Cu")
		(net "SAS2X28_A_HDD3_TX_-")
	)
	(arc
		(start 196.795644 -156.868876)
		(mid 196.376377 -156.950804)
		(end 196.018658 -157.184344)
		(width 0.09525)
		(layer "F.Cu")
		(net "SAS2X28_A_HDD3_TX_-")
	)
	(arc
		(start 23.601172 -361.81538)
		(mid 23.174568 -362.453738)
		(end 23.024846 -363.206792)
		(width 0.09525)
		(layer "F.Cu")
		(net "SAS2X28_A_HDD3_TX_-")
	)
	(arc
		(start 10.44448 -381.703072)
		(mid 9.937314 -382.04192)
		(end 9.339072 -382.16078)
		(width 0.09525)
		(layer "F.Cu")
		(net "SAS2X28_A_HDD3_TX_-")
	)
	(arc
		(start 221.980252 -157.340046)
		(mid 221.88898 -157.321891)
		(end 221.811596 -157.270196)
		(width 0.09525)
		(layer "F.Cu")
		(net "SAS2X28_A_HDD3_TX_-")
	)
	(arc
		(start 221.741746 -157.101794)
		(mid 221.673826 -156.93656)
		(end 221.509336 -156.866844)
		(width 0.09525)
		(layer "F.Cu")
		(net "SAS2X28_A_HDD3_TX_-")
	)
	(arc
		(start 5.263896 -382.25857)
		(mid 4.996096 -382.437508)
		(end 4.680204 -382.500378)
		(width 0.09525)
		(layer "F.Cu")
		(net "SAS2X28_A_HDD3_TX_-")
	)
	(segment
		(start 60.795408 -324.154038)
		(end 23.444962 -361.504484)
		(width 0.09525)
		(layer "F.Cu")
		(net "SAS2X28_A_HDD3_TX_+")
	)
	(segment
		(start 221.769178 -156.22905)
		(end 221.769178 -156.322776)
		(width 0.09525)
		(layer "F.Cu")
		(net "SAS2X28_A_HDD3_TX_+")
	)
	(segment
		(start 10.2108 -381.469138)
		(end 10.2108 -381.469646)
		(width 0.09525)
		(layer "F.Cu")
		(net "SAS2X28_A_HDD3_TX_+")
	)
	(segment
		(start 195.773294 -156.962094)
		(end 104.129586 -270.477234)
		(width 0.09525)
		(layer "F.Cu")
		(net "SAS2X28_A_HDD3_TX_+")
	)
	(segment
		(start 10.324846 -381.355346)
		(end 10.324592 -381.355346)
		(width 0.09525)
		(layer "F.Cu")
		(net "SAS2X28_A_HDD3_TX_+")
	)
	(segment
		(start 221.910656 -156.078428)
		(end 221.868746 -156.09189)
		(width 0.09525)
		(layer "F.Cu")
		(net "SAS2X28_A_HDD3_TX_+")
	)
	(segment
		(start 10.324592 -381.355346)
		(end 10.2108 -381.469138)
		(width 0.09525)
		(layer "F.Cu")
		(net "SAS2X28_A_HDD3_TX_+")
	)
	(segment
		(start 9.339072 -381.83058)
		(end 5.489702 -381.83058)
		(width 0.09525)
		(layer "F.Cu")
		(net "SAS2X28_A_HDD3_TX_+")
	)
	(segment
		(start 223.249998 -156.070046)
		(end 221.963234 -156.070046)
		(width 0.09525)
		(layer "F.Cu")
		(net "SAS2X28_A_HDD3_TX_+")
	)
	(segment
		(start 221.555056 -156.536644)
		(end 196.851524 -156.536644)
		(width 0.09525)
		(layer "F.Cu")
		(net "SAS2X28_A_HDD3_TX_+")
	)
	(segment
		(start 23.367492 -361.581446)
		(end 23.367492 -361.5817)
		(width 0.09525)
		(layer "F.Cu")
		(net "SAS2X28_A_HDD3_TX_+")
	)
	(segment
		(start 104.129586 -270.477234)
		(end 60.795408 -324.154038)
		(width 0.09525)
		(layer "F.Cu")
		(net "SAS2X28_A_HDD3_TX_+")
	)
	(segment
		(start 4.692396 -381.50038)
		(end 4.690872 -381.498856)
		(width 0.09525)
		(layer "F.Cu")
		(net "SAS2X28_A_HDD3_TX_+")
	)
	(segment
		(start 196.851524 -156.536644)
		(end 196.849746 -156.538422)
		(width 0.09525)
		(layer "F.Cu")
		(net "SAS2X28_A_HDD3_TX_+")
	)
	(segment
		(start 196.849746 -156.538422)
		(end 196.847968 -156.538676)
		(width 0.09525)
		(layer "F.Cu")
		(net "SAS2X28_A_HDD3_TX_+")
	)
	(segment
		(start 4.690872 -381.498856)
		(end 3.192526 -381.498856)
		(width 0.09525)
		(layer "F.Cu")
		(net "SAS2X28_A_HDD3_TX_+")
	)
	(segment
		(start 196.847968 -156.538676)
		(end 196.79539 -156.538676)
		(width 0.09525)
		(layer "F.Cu")
		(net "SAS2X28_A_HDD3_TX_+")
	)
	(segment
		(start 22.218396 -369.461796)
		(end 10.324846 -381.355346)
		(width 0.09525)
		(layer "F.Cu")
		(net "SAS2X28_A_HDD3_TX_+")
	)
	(segment
		(start 22.694646 -363.206792)
		(end 22.694646 -368.312446)
		(width 0.09525)
		(layer "F.Cu")
		(net "SAS2X28_A_HDD3_TX_+")
	)
	(segment
		(start 23.444962 -361.504484)
		(end 23.367492 -361.581446)
		(width 0.09525)
		(layer "F.Cu")
		(net "SAS2X28_A_HDD3_TX_+")
	)
	(arc
		(start 196.79539 -156.538676)
		(mid 196.242216 -156.648709)
		(end 195.773294 -156.962094)
		(width 0.09525)
		(layer "F.Cu")
		(net "SAS2X28_A_HDD3_TX_+")
	)
	(arc
		(start 221.70644 -156.473906)
		(mid 221.636984 -156.520315)
		(end 221.555056 -156.536644)
		(width 0.09525)
		(layer "F.Cu")
		(net "SAS2X28_A_HDD3_TX_+")
	)
	(arc
		(start 10.2108 -381.469646)
		(mid 9.810833 -381.736803)
		(end 9.339072 -381.83058)
		(width 0.09525)
		(layer "F.Cu")
		(net "SAS2X28_A_HDD3_TX_+")
	)
	(arc
		(start 22.694646 -368.312446)
		(mid 22.57089 -368.934522)
		(end 22.218396 -369.461796)
		(width 0.09525)
		(layer "F.Cu")
		(net "SAS2X28_A_HDD3_TX_+")
	)
	(arc
		(start 5.489702 -381.83058)
		(mid 5.371213 -381.807011)
		(end 5.270754 -381.739902)
		(width 0.09525)
		(layer "F.Cu")
		(net "SAS2X28_A_HDD3_TX_+")
	)
	(arc
		(start 23.367492 -361.5817)
		(mid 22.869387 -362.327301)
		(end 22.694646 -363.206792)
		(width 0.09525)
		(layer "F.Cu")
		(net "SAS2X28_A_HDD3_TX_+")
	)
	(arc
		(start 221.769178 -156.322776)
		(mid 221.752883 -156.404606)
		(end 221.70644 -156.473906)
		(width 0.09525)
		(layer "F.Cu")
		(net "SAS2X28_A_HDD3_TX_+")
	)
	(arc
		(start 221.963234 -156.070046)
		(mid 221.936613 -156.072165)
		(end 221.910656 -156.078428)
		(width 0.09525)
		(layer "F.Cu")
		(net "SAS2X28_A_HDD3_TX_+")
	)
	(arc
		(start 221.868746 -156.09189)
		(mid 221.796702 -156.144308)
		(end 221.769178 -156.22905)
		(width 0.09525)
		(layer "F.Cu")
		(net "SAS2X28_A_HDD3_TX_+")
	)
	(arc
		(start 5.270754 -381.739902)
		(mid 5.005401 -381.562599)
		(end 4.692396 -381.50038)
		(width 0.09525)
		(layer "F.Cu")
		(net "SAS2X28_A_HDD3_TX_+")
	)
	(segment
		(start 201.167746 -186.1947)
		(end 200.674986 -185.70194)
		(width 0.111252)
		(layer "F.Cu")
		(net "SAS2X28_B_HDD3_FLT")
	)
	(segment
		(start 202.120246 -185.9407)
		(end 201.739246 -186.3217)
		(width 0.111252)
		(layer "F.Cu")
		(net "SAS2X28_B_HDD3_FLT")
	)
	(segment
		(start 201.294746 -186.3217)
		(end 201.167746 -186.1947)
		(width 0.111252)
		(layer "F.Cu")
		(net "SAS2X28_B_HDD3_FLT")
	)
	(segment
		(start 201.739246 -186.3217)
		(end 201.294746 -186.3217)
		(width 0.111252)
		(layer "F.Cu")
		(net "SAS2X28_B_HDD3_FLT")
	)
	(segment
		(start 200.674986 -185.70194)
		(end 200.674986 -185.1152)
		(width 0.111252)
		(layer "F.Cu")
		(net "SAS2X28_B_HDD3_FLT")
	)
	(via
		(at 9.961118 -140.9065)
		(size 0.5588)
		(drill 0.3048)
		(layers "F.Cu" "B.Cu")
		(net "SAS2X28_B_HDD3_FLT")
	)
	(via
		(at 8.584946 -140.4747)
		(size 0.7112)
		(drill 0.3556)
		(layers "F.Cu" "B.Cu")
		(net "SAS2X28_B_HDD3_FLT")
	)
	(via
		(at 95.503746 -177.4317)
		(size 0.5588)
		(drill 0.3048)
		(layers "F.Cu" "B.Cu")
		(net "SAS2X28_B_HDD3_FLT")
	)
	(via
		(at 201.167746 -186.1947)
		(size 0.5588)
		(drill 0.3048)
		(layers "F.Cu" "B.Cu")
		(net "SAS2X28_B_HDD3_FLT")
	)
	(via
		(at 201.167746 -185.2549)
		(size 0.7112)
		(drill 0.3556)
		(layers "F.Cu" "B.Cu")
		(net "SAS2X28_B_HDD3_FLT")
	)
	(segment
		(start 2.811526 -140.49883)
		(end 2.81305 -140.500354)
		(width 0.111252)
		(layer "B.Cu")
		(net "SAS2X28_B_HDD3_FLT")
	)
	(segment
		(start 2.81305 -140.500354)
		(end 8.559292 -140.500354)
		(width 0.111252)
		(layer "B.Cu")
		(net "SAS2X28_B_HDD3_FLT")
	)
	(segment
		(start 9.961118 -140.9065)
		(end 9.529318 -140.4747)
		(width 0.111252)
		(layer "B.Cu")
		(net "SAS2X28_B_HDD3_FLT")
	)
	(segment
		(start 9.529318 -140.4747)
		(end 8.584946 -140.4747)
		(width 0.111252)
		(layer "B.Cu")
		(net "SAS2X28_B_HDD3_FLT")
	)
	(segment
		(start 201.167746 -186.1947)
		(end 201.167746 -185.2549)
		(width 0.111252)
		(layer "B.Cu")
		(net "SAS2X28_B_HDD3_FLT")
	)
	(segment
		(start 8.559292 -140.500354)
		(end 8.584946 -140.4747)
		(width 0.111252)
		(layer "B.Cu")
		(net "SAS2X28_B_HDD3_FLT")
	)
	(segment
		(start 191.6684 -177.1142)
		(end 190.1698 -177.1142)
		(width 0.14605)
		(layer "In2.Cu")
		(net "SAS2X28_B_HDD3_FLT")
	)
	(segment
		(start 190.1698 -177.1142)
		(end 189.8523 -177.4317)
		(width 0.14605)
		(layer "In2.Cu")
		(net "SAS2X28_B_HDD3_FLT")
	)
	(segment
		(start 197.7898 -183.2356)
		(end 191.6684 -177.1142)
		(width 0.14605)
		(layer "In2.Cu")
		(net "SAS2X28_B_HDD3_FLT")
	)
	(segment
		(start 201.167746 -185.978546)
		(end 198.4248 -183.2356)
		(width 0.14605)
		(layer "In2.Cu")
		(net "SAS2X28_B_HDD3_FLT")
	)
	(segment
		(start 189.8523 -177.4317)
		(end 95.503746 -177.4317)
		(width 0.14605)
		(layer "In2.Cu")
		(net "SAS2X28_B_HDD3_FLT")
	)
	(segment
		(start 201.167746 -186.1947)
		(end 201.167746 -185.978546)
		(width 0.14605)
		(layer "In2.Cu")
		(net "SAS2X28_B_HDD3_FLT")
	)
	(segment
		(start 198.4248 -183.2356)
		(end 197.7898 -183.2356)
		(width 0.14605)
		(layer "In2.Cu")
		(net "SAS2X28_B_HDD3_FLT")
	)
	(segment
		(start 9.961118 -140.9065)
		(end 9.961118 -139.695174)
		(width 0.14605)
		(layer "In5.Cu")
		(net "SAS2X28_B_HDD3_FLT")
	)
	(segment
		(start 10.207244 -138.6713)
		(end 10.236454 -138.641836)
		(width 0.14605)
		(layer "In5.Cu")
		(net "SAS2X28_B_HDD3_FLT")
	)
	(segment
		(start 9.957816 -138.920728)
		(end 10.207244 -138.6713)
		(width 0.14605)
		(layer "In5.Cu")
		(net "SAS2X28_B_HDD3_FLT")
	)
	(segment
		(start 11.147298 -109.224826)
		(end 21.334476 -99.037648)
		(width 0.14605)
		(layer "In5.Cu")
		(net "SAS2X28_B_HDD3_FLT")
	)
	(segment
		(start 10.236454 -134.620508)
		(end 11.585702 -133.27126)
		(width 0.14605)
		(layer "In5.Cu")
		(net "SAS2X28_B_HDD3_FLT")
	)
	(segment
		(start 95.503746 -106.698288)
		(end 95.503746 -177.4317)
		(width 0.14605)
		(layer "In5.Cu")
		(net "SAS2X28_B_HDD3_FLT")
	)
	(segment
		(start 11.585702 -133.27126)
		(end 11.585702 -130.02514)
		(width 0.14605)
		(layer "In5.Cu")
		(net "SAS2X28_B_HDD3_FLT")
	)
	(segment
		(start 11.585702 -130.02514)
		(end 11.147298 -129.586736)
		(width 0.14605)
		(layer "In5.Cu")
		(net "SAS2X28_B_HDD3_FLT")
	)
	(segment
		(start 10.236454 -138.641836)
		(end 10.236454 -134.620508)
		(width 0.14605)
		(layer "In5.Cu")
		(net "SAS2X28_B_HDD3_FLT")
	)
	(segment
		(start 87.843106 -99.037648)
		(end 95.503746 -106.698288)
		(width 0.14605)
		(layer "In5.Cu")
		(net "SAS2X28_B_HDD3_FLT")
	)
	(segment
		(start 21.334476 -99.037648)
		(end 87.843106 -99.037648)
		(width 0.14605)
		(layer "In5.Cu")
		(net "SAS2X28_B_HDD3_FLT")
	)
	(segment
		(start 11.147298 -129.586736)
		(end 11.147298 -109.224826)
		(width 0.14605)
		(layer "In5.Cu")
		(net "SAS2X28_B_HDD3_FLT")
	)
	(segment
		(start 9.957816 -139.691872)
		(end 9.957816 -138.920728)
		(width 0.14605)
		(layer "In5.Cu")
		(net "SAS2X28_B_HDD3_FLT")
	)
	(segment
		(start 9.961118 -139.695174)
		(end 9.957816 -139.691872)
		(width 0.14605)
		(layer "In5.Cu")
		(net "SAS2X28_B_HDD3_FLT")
	)
	(segment
		(start 200.024746 -186.5757)
		(end 200.024746 -185.1152)
		(width 0.111252)
		(layer "F.Cu")
		(net "SAS2X28_A_HDD3_FLT")
	)
	(segment
		(start 200.405746 -186.9567)
		(end 200.024746 -186.5757)
		(width 0.111252)
		(layer "F.Cu")
		(net "SAS2X28_A_HDD3_FLT")
	)
	(segment
		(start 202.120246 -186.9567)
		(end 200.405746 -186.9567)
		(width 0.111252)
		(layer "F.Cu")
		(net "SAS2X28_A_HDD3_FLT")
	)
	(via
		(at 9.23036 -395.937486)
		(size 0.5588)
		(drill 0.3048)
		(layers "F.Cu" "B.Cu")
		(net "SAS2X28_A_HDD3_FLT")
	)
	(via
		(at 200.405746 -186.9567)
		(size 0.5588)
		(drill 0.3048)
		(layers "F.Cu" "B.Cu")
		(net "SAS2X28_A_HDD3_FLT")
	)
	(via
		(at 199.599804 -187.440316)
		(size 0.7112)
		(drill 0.3556)
		(layers "F.Cu" "B.Cu")
		(net "SAS2X28_A_HDD3_FLT")
	)
	(segment
		(start 2.81305 -395.500352)
		(end 2.811526 -395.498828)
		(width 0.111252)
		(layer "B.Cu")
		(net "SAS2X28_A_HDD3_FLT")
	)
	(segment
		(start 200.405746 -186.9567)
		(end 199.92213 -187.440316)
		(width 0.111252)
		(layer "B.Cu")
		(net "SAS2X28_A_HDD3_FLT")
	)
	(segment
		(start 199.92213 -187.440316)
		(end 199.599804 -187.440316)
		(width 0.111252)
		(layer "B.Cu")
		(net "SAS2X28_A_HDD3_FLT")
	)
	(segment
		(start 7.837932 -395.937486)
		(end 7.400798 -395.500352)
		(width 0.111252)
		(layer "B.Cu")
		(net "SAS2X28_A_HDD3_FLT")
	)
	(segment
		(start 9.23036 -395.937486)
		(end 7.837932 -395.937486)
		(width 0.111252)
		(layer "B.Cu")
		(net "SAS2X28_A_HDD3_FLT")
	)
	(segment
		(start 7.400798 -395.500352)
		(end 2.81305 -395.500352)
		(width 0.111252)
		(layer "B.Cu")
		(net "SAS2X28_A_HDD3_FLT")
	)
	(segment
		(start 229.909878 -376.458734)
		(end 220.557344 -385.811268)
		(width 0.14605)
		(layer "In5.Cu")
		(net "SAS2X28_A_HDD3_FLT")
	)
	(segment
		(start 200.405746 -200.037192)
		(end 229.909878 -229.541324)
		(width 0.14605)
		(layer "In5.Cu")
		(net "SAS2X28_A_HDD3_FLT")
	)
	(segment
		(start 7.4295 -450.570854)
		(end 7.4295 -443.176152)
		(width 0.14605)
		(layer "In5.Cu")
		(net "SAS2X28_A_HDD3_FLT")
	)
	(segment
		(start 6.581648 -435.722014)
		(end 11.93419 -430.369472)
		(width 0.14605)
		(layer "In5.Cu")
		(net "SAS2X28_A_HDD3_FLT")
	)
	(segment
		(start 229.909878 -229.541324)
		(end 229.909878 -376.458734)
		(width 0.14605)
		(layer "In5.Cu")
		(net "SAS2X28_A_HDD3_FLT")
	)
	(segment
		(start 220.557344 -385.903978)
		(end 139.861036 -466.600286)
		(width 0.14605)
		(layer "In5.Cu")
		(net "SAS2X28_A_HDD3_FLT")
	)
	(segment
		(start 10.210546 -455.40168)
		(end 10.210546 -453.3519)
		(width 0.14605)
		(layer "In5.Cu")
		(net "SAS2X28_A_HDD3_FLT")
	)
	(segment
		(start 6.581648 -442.3283)
		(end 6.581648 -435.722014)
		(width 0.14605)
		(layer "In5.Cu")
		(net "SAS2X28_A_HDD3_FLT")
	)
	(segment
		(start 10.48004 -455.658728)
		(end 10.467594 -455.658728)
		(width 0.14605)
		(layer "In5.Cu")
		(net "SAS2X28_A_HDD3_FLT")
	)
	(segment
		(start 12.217654 -462.18729)
		(end 12.217654 -458.724)
		(width 0.14605)
		(layer "In5.Cu")
		(net "SAS2X28_A_HDD3_FLT")
	)
	(segment
		(start 10.921746 -456.100434)
		(end 10.48004 -455.658728)
		(width 0.14605)
		(layer "In5.Cu")
		(net "SAS2X28_A_HDD3_FLT")
	)
	(segment
		(start 220.557344 -385.811268)
		(end 220.557344 -385.903978)
		(width 0.14605)
		(layer "In5.Cu")
		(net "SAS2X28_A_HDD3_FLT")
	)
	(segment
		(start 17.989804 -467.414102)
		(end 15.282164 -464.706462)
		(width 0.14605)
		(layer "In5.Cu")
		(net "SAS2X28_A_HDD3_FLT")
	)
	(segment
		(start 11.93419 -400.870166)
		(end 12.188952 -400.615404)
		(width 0.14605)
		(layer "In5.Cu")
		(net "SAS2X28_A_HDD3_FLT")
	)
	(segment
		(start 12.217654 -458.724)
		(end 10.921746 -457.428092)
		(width 0.14605)
		(layer "In5.Cu")
		(net "SAS2X28_A_HDD3_FLT")
	)
	(segment
		(start 10.651236 -396.456662)
		(end 9.749536 -396.456662)
		(width 0.14605)
		(layer "In5.Cu")
		(net "SAS2X28_A_HDD3_FLT")
	)
	(segment
		(start 20.959318 -467.414102)
		(end 17.989804 -467.414102)
		(width 0.14605)
		(layer "In5.Cu")
		(net "SAS2X28_A_HDD3_FLT")
	)
	(segment
		(start 10.467594 -455.658728)
		(end 10.210546 -455.40168)
		(width 0.14605)
		(layer "In5.Cu")
		(net "SAS2X28_A_HDD3_FLT")
	)
	(segment
		(start 10.921746 -457.428092)
		(end 10.921746 -456.100434)
		(width 0.14605)
		(layer "In5.Cu")
		(net "SAS2X28_A_HDD3_FLT")
	)
	(segment
		(start 12.188952 -397.994378)
		(end 10.651236 -396.456662)
		(width 0.14605)
		(layer "In5.Cu")
		(net "SAS2X28_A_HDD3_FLT")
	)
	(segment
		(start 139.861036 -466.600286)
		(end 21.773134 -466.600286)
		(width 0.14605)
		(layer "In5.Cu")
		(net "SAS2X28_A_HDD3_FLT")
	)
	(segment
		(start 12.188952 -400.615404)
		(end 12.188952 -397.994378)
		(width 0.14605)
		(layer "In5.Cu")
		(net "SAS2X28_A_HDD3_FLT")
	)
	(segment
		(start 10.210546 -453.3519)
		(end 7.4295 -450.570854)
		(width 0.14605)
		(layer "In5.Cu")
		(net "SAS2X28_A_HDD3_FLT")
	)
	(segment
		(start 15.282164 -464.706462)
		(end 14.736826 -464.706462)
		(width 0.14605)
		(layer "In5.Cu")
		(net "SAS2X28_A_HDD3_FLT")
	)
	(segment
		(start 200.405746 -186.9567)
		(end 200.405746 -200.037192)
		(width 0.14605)
		(layer "In5.Cu")
		(net "SAS2X28_A_HDD3_FLT")
	)
	(segment
		(start 9.749536 -396.456662)
		(end 9.23036 -395.937486)
		(width 0.14605)
		(layer "In5.Cu")
		(net "SAS2X28_A_HDD3_FLT")
	)
	(segment
		(start 11.93419 -430.369472)
		(end 11.93419 -400.870166)
		(width 0.14605)
		(layer "In5.Cu")
		(net "SAS2X28_A_HDD3_FLT")
	)
	(segment
		(start 7.4295 -443.176152)
		(end 6.581648 -442.3283)
		(width 0.14605)
		(layer "In5.Cu")
		(net "SAS2X28_A_HDD3_FLT")
	)
	(segment
		(start 21.773134 -466.600286)
		(end 20.959318 -467.414102)
		(width 0.14605)
		(layer "In5.Cu")
		(net "SAS2X28_A_HDD3_FLT")
	)
	(segment
		(start 14.736826 -464.706462)
		(end 12.217654 -462.18729)
		(width 0.14605)
		(layer "In5.Cu")
		(net "SAS2X28_A_HDD3_FLT")
	)
	(segment
		(start 232.295446 -143.9926)
		(end 232.879646 -143.9926)
		(width 0.111252)
		(layer "F.Cu")
		(net "DRIVE_ACT_3")
	)
	(segment
		(start 230.808784 -143.988028)
		(end 232.290874 -143.988028)
		(width 0.111252)
		(layer "F.Cu")
		(net "DRIVE_ACT_3")
	)
	(segment
		(start 232.879646 -143.9926)
		(end 233.044746 -144.1577)
		(width 0.111252)
		(layer "F.Cu")
		(net "DRIVE_ACT_3")
	)
	(segment
		(start 233.044746 -144.1577)
		(end 235.457746 -144.1577)
		(width 0.111252)
		(layer "F.Cu")
		(net "DRIVE_ACT_3")
	)
	(segment
		(start 232.290874 -143.988028)
		(end 232.295446 -143.9926)
		(width 0.111252)
		(layer "F.Cu")
		(net "DRIVE_ACT_3")
	)
	(segment
		(start 235.457746 -144.1577)
		(end 235.711746 -144.4117)
		(width 0.111252)
		(layer "F.Cu")
		(net "DRIVE_ACT_3")
	)
	(segment
		(start 230.808784 -145.004028)
		(end 230.808784 -143.988028)
		(width 0.111252)
		(layer "F.Cu")
		(net "DRIVE_ACT_3")
	)
	(via
		(at 235.711746 -144.4117)
		(size 0.7112)
		(drill 0.3556)
		(layers "F.Cu" "B.Cu")
		(net "DRIVE_ACT_3")
	)
	(segment
		(start 196.468746 -491.5027)
		(end 196.087746 -491.8837)
		(width 0.111252)
		(layer "F.Cu")
		(net "SAS_EXP_B_PWR0")
	)
	(segment
		(start 196.786246 -491.5027)
		(end 196.468746 -491.5027)
		(width 0.111252)
		(layer "F.Cu")
		(net "SAS_EXP_B_PWR0")
	)
	(segment
		(start 8.405114 -206.544926)
		(end 8.243062 -206.382874)
		(width 0.111252)
		(layer "F.Cu")
		(net "SAS_EXP_B_PWR0")
	)
	(segment
		(start 7.738364 -206.50454)
		(end 3.19024 -206.50454)
		(width 0.111252)
		(layer "F.Cu")
		(net "SAS_EXP_B_PWR0")
	)
	(segment
		(start 13.180314 -206.090774)
		(end 10.164826 -206.090774)
		(width 0.111252)
		(layer "F.Cu")
		(net "SAS_EXP_B_PWR0")
	)
	(segment
		(start 195.960746 -491.8837)
		(end 195.807584 -492.036862)
		(width 0.111252)
		(layer "F.Cu")
		(net "SAS_EXP_B_PWR0")
	)
	(segment
		(start 9.710674 -206.544926)
		(end 8.405114 -206.544926)
		(width 0.111252)
		(layer "F.Cu")
		(net "SAS_EXP_B_PWR0")
	)
	(segment
		(start 7.86003 -206.382874)
		(end 7.738364 -206.50454)
		(width 0.111252)
		(layer "F.Cu")
		(net "SAS_EXP_B_PWR0")
	)
	(segment
		(start 13.687806 -206.598266)
		(end 13.180314 -206.090774)
		(width 0.111252)
		(layer "F.Cu")
		(net "SAS_EXP_B_PWR0")
	)
	(segment
		(start 8.243062 -206.382874)
		(end 7.86003 -206.382874)
		(width 0.111252)
		(layer "F.Cu")
		(net "SAS_EXP_B_PWR0")
	)
	(segment
		(start 196.087746 -491.8837)
		(end 195.960746 -491.8837)
		(width 0.111252)
		(layer "F.Cu")
		(net "SAS_EXP_B_PWR0")
	)
	(segment
		(start 10.164826 -206.090774)
		(end 9.710674 -206.544926)
		(width 0.111252)
		(layer "F.Cu")
		(net "SAS_EXP_B_PWR0")
	)
	(segment
		(start 27.991308 -206.598266)
		(end 13.687806 -206.598266)
		(width 0.111252)
		(layer "F.Cu")
		(net "SAS_EXP_B_PWR0")
	)
	(segment
		(start 195.807584 -492.036862)
		(end 194.707256 -492.036862)
		(width 0.111252)
		(layer "F.Cu")
		(net "SAS_EXP_B_PWR0")
	)
	(via
		(at 89.788746 -434.4543)
		(size 0.5588)
		(drill 0.3048)
		(layers "F.Cu" "B.Cu")
		(net "SAS_EXP_B_PWR0")
	)
	(via
		(at 27.991308 -206.598266)
		(size 0.5588)
		(drill 0.3048)
		(layers "F.Cu" "B.Cu")
		(net "SAS_EXP_B_PWR0")
	)
	(via
		(at 195.960746 -491.8837)
		(size 0.5588)
		(drill 0.3048)
		(layers "F.Cu" "B.Cu")
		(net "SAS_EXP_B_PWR0")
	)
	(via
		(at 192.023746 -491.5027)
		(size 0.7112)
		(drill 0.3556)
		(layers "F.Cu" "B.Cu")
		(net "SAS_EXP_B_PWR0")
	)
	(segment
		(start 195.579746 -491.5027)
		(end 192.023746 -491.5027)
		(width 0.111252)
		(layer "B.Cu")
		(net "SAS_EXP_B_PWR0")
	)
	(segment
		(start 188.213746 -491.5027)
		(end 192.023746 -491.5027)
		(width 0.111252)
		(layer "B.Cu")
		(net "SAS_EXP_B_PWR0")
	)
	(segment
		(start 89.788746 -434.4797)
		(end 92.328746 -437.0197)
		(width 0.111252)
		(layer "B.Cu")
		(net "SAS_EXP_B_PWR0")
	)
	(segment
		(start 195.960746 -491.8837)
		(end 195.579746 -491.5027)
		(width 0.111252)
		(layer "B.Cu")
		(net "SAS_EXP_B_PWR0")
	)
	(segment
		(start 133.730746 -437.0197)
		(end 188.213746 -491.5027)
		(width 0.111252)
		(layer "B.Cu")
		(net "SAS_EXP_B_PWR0")
	)
	(segment
		(start 89.788746 -434.4543)
		(end 89.788746 -434.4797)
		(width 0.111252)
		(layer "B.Cu")
		(net "SAS_EXP_B_PWR0")
	)
	(segment
		(start 92.328746 -437.0197)
		(end 133.730746 -437.0197)
		(width 0.111252)
		(layer "B.Cu")
		(net "SAS_EXP_B_PWR0")
	)
	(segment
		(start 88.699848 -205.486)
		(end 88.699848 -387.294628)
		(width 0.14605)
		(layer "In5.Cu")
		(net "SAS_EXP_B_PWR0")
	)
	(segment
		(start 88.699848 -387.294628)
		(end 88.115394 -387.879082)
		(width 0.14605)
		(layer "In5.Cu")
		(net "SAS_EXP_B_PWR0")
	)
	(segment
		(start 27.991308 -206.598266)
		(end 26.30805 -204.915008)
		(width 0.14605)
		(layer "In5.Cu")
		(net "SAS_EXP_B_PWR0")
	)
	(segment
		(start 88.115394 -387.879082)
		(end 88.115394 -432.780948)
		(width 0.14605)
		(layer "In5.Cu")
		(net "SAS_EXP_B_PWR0")
	)
	(segment
		(start 26.30805 -201.153776)
		(end 27.862276 -199.59955)
		(width 0.14605)
		(layer "In5.Cu")
		(net "SAS_EXP_B_PWR0")
	)
	(segment
		(start 82.813398 -199.59955)
		(end 88.699848 -205.486)
		(width 0.14605)
		(layer "In5.Cu")
		(net "SAS_EXP_B_PWR0")
	)
	(segment
		(start 27.862276 -199.59955)
		(end 82.813398 -199.59955)
		(width 0.14605)
		(layer "In5.Cu")
		(net "SAS_EXP_B_PWR0")
	)
	(segment
		(start 26.30805 -204.915008)
		(end 26.30805 -201.153776)
		(width 0.14605)
		(layer "In5.Cu")
		(net "SAS_EXP_B_PWR0")
	)
	(segment
		(start 88.115394 -432.780948)
		(end 89.788746 -434.4543)
		(width 0.14605)
		(layer "In5.Cu")
		(net "SAS_EXP_B_PWR0")
	)
	(via
		(at 64.389 -402.971)
		(size 0.7112)
		(drill 0.3556)
		(layers "F.Cu" "B.Cu")
		(net "P12V_HDD6")
	)
	(via
		(at 66.167 -391.414)
		(size 0.7112)
		(drill 0.3556)
		(layers "F.Cu" "B.Cu")
		(net "P12V_HDD6")
	)
	(segment
		(start 65.786 -388.6454)
		(end 65.786 -389.636)
		(width 0.508)
		(layer "F.Cu")
		(net "P5V_HDD6")
	)
	(via
		(at 65.786 -389.636)
		(size 0.7112)
		(drill 0.3556)
		(layers "F.Cu" "B.Cu")
		(net "P5V_HDD6")
	)
	(via
		(at 55.245 -386.715)
		(size 0.7112)
		(drill 0.3556)
		(layers "F.Cu" "B.Cu")
		(net "P5V_HDD6")
	)
	(segment
		(start 16.766794 -52.430426)
		(end 15.59052 -52.430426)
		(width 0.111252)
		(layer "F.Cu")
		(net "DRV_ACT_NET14")
	)
	(segment
		(start 16.769842 -52.433474)
		(end 16.766794 -52.430426)
		(width 0.111252)
		(layer "F.Cu")
		(net "DRV_ACT_NET14")
	)
	(segment
		(start 15.080996 -52.68595)
		(end 15.049246 -52.7177)
		(width 0.111252)
		(layer "F.Cu")
		(net "DRV_ACT_NET14")
	)
	(segment
		(start 15.049246 -52.9082)
		(end 15.620746 -53.4797)
		(width 0.111252)
		(layer "F.Cu")
		(net "DRV_ACT_NET14")
	)
	(segment
		(start 15.049246 -52.7177)
		(end 15.049246 -52.9082)
		(width 0.111252)
		(layer "F.Cu")
		(net "DRV_ACT_NET14")
	)
	(segment
		(start 15.620746 -53.4797)
		(end 15.620746 -54.903878)
		(width 0.111252)
		(layer "F.Cu")
		(net "DRV_ACT_NET14")
	)
	(segment
		(start 15.620746 -54.903878)
		(end 15.686278 -54.96941)
		(width 0.111252)
		(layer "F.Cu")
		(net "DRV_ACT_NET14")
	)
	(segment
		(start 15.334996 -52.68595)
		(end 15.080996 -52.68595)
		(width 0.111252)
		(layer "F.Cu")
		(net "DRV_ACT_NET14")
	)
	(segment
		(start 15.59052 -52.430426)
		(end 15.334996 -52.68595)
		(width 0.111252)
		(layer "F.Cu")
		(net "DRV_ACT_NET14")
	)
	(via
		(at 15.686278 -54.96941)
		(size 0.7112)
		(drill 0.3556)
		(layers "F.Cu" "B.Cu")
		(net "DRV_ACT_NET14")
	)
	(segment
		(start 15.875 -156.691838)
		(end 15.875 -160.8582)
		(width 0.111252)
		(layer "F.Cu")
		(net "DRV_ACT_NET13")
	)
	(segment
		(start 15.875 -161.925)
		(end 15.875 -160.8582)
		(width 0.111252)
		(layer "F.Cu")
		(net "DRV_ACT_NET13")
	)
	(segment
		(start 16.549878 -155.433522)
		(end 15.879826 -156.103574)
		(width 0.111252)
		(layer "F.Cu")
		(net "DRV_ACT_NET13")
	)
	(segment
		(start 14.477746 -165.731698)
		(end 14.093698 -165.731698)
		(width 0.111252)
		(layer "F.Cu")
		(net "DRV_ACT_NET13")
	)
	(segment
		(start 15.879826 -156.687012)
		(end 15.875 -156.691838)
		(width 0.111252)
		(layer "F.Cu")
		(net "DRV_ACT_NET13")
	)
	(segment
		(start 13.589 -164.211)
		(end 15.875 -161.925)
		(width 0.111252)
		(layer "F.Cu")
		(net "DRV_ACT_NET13")
	)
	(segment
		(start 13.589 -165.227)
		(end 13.589 -164.211)
		(width 0.111252)
		(layer "F.Cu")
		(net "DRV_ACT_NET13")
	)
	(segment
		(start 15.879826 -156.103574)
		(end 15.879826 -156.687012)
		(width 0.111252)
		(layer "F.Cu")
		(net "DRV_ACT_NET13")
	)
	(segment
		(start 16.769842 -155.433522)
		(end 16.549878 -155.433522)
		(width 0.111252)
		(layer "F.Cu")
		(net "DRV_ACT_NET13")
	)
	(segment
		(start 14.093698 -165.731698)
		(end 13.589 -165.227)
		(width 0.111252)
		(layer "F.Cu")
		(net "DRV_ACT_NET13")
	)
	(via
		(at 15.875 -160.8582)
		(size 0.7112)
		(drill 0.3556)
		(layers "F.Cu" "B.Cu")
		(net "DRV_ACT_NET13")
	)
	(segment
		(start 16.001746 -258.8387)
		(end 16.406876 -258.43357)
		(width 0.111252)
		(layer "F.Cu")
		(net "DRV_ACT_NET12")
	)
	(segment
		(start 15.747746 -260.1087)
		(end 16.052038 -260.1087)
		(width 0.111252)
		(layer "F.Cu")
		(net "DRV_ACT_NET12")
	)
	(segment
		(start 16.052038 -260.1087)
		(end 16.071342 -260.089396)
		(width 0.111252)
		(layer "F.Cu")
		(net "DRV_ACT_NET12")
	)
	(segment
		(start 15.160244 -259.521198)
		(end 15.747746 -260.1087)
		(width 0.111252)
		(layer "F.Cu")
		(net "DRV_ACT_NET12")
	)
	(segment
		(start 15.160244 -259.3467)
		(end 15.160244 -259.521198)
		(width 0.111252)
		(layer "F.Cu")
		(net "DRV_ACT_NET12")
	)
	(segment
		(start 16.406876 -258.43357)
		(end 16.769842 -258.43357)
		(width 0.111252)
		(layer "F.Cu")
		(net "DRV_ACT_NET12")
	)
	(segment
		(start 16.071342 -260.089396)
		(end 16.071342 -260.051042)
		(width 0.111252)
		(layer "F.Cu")
		(net "DRV_ACT_NET12")
	)
	(segment
		(start 16.071342 -260.051042)
		(end 16.001746 -259.981446)
		(width 0.111252)
		(layer "F.Cu")
		(net "DRV_ACT_NET12")
	)
	(segment
		(start 16.001746 -259.981446)
		(end 16.001746 -258.8387)
		(width 0.111252)
		(layer "F.Cu")
		(net "DRV_ACT_NET12")
	)
	(via
		(at 16.764 -259.1689)
		(size 0.7112)
		(drill 0.3556)
		(layers "F.Cu" "B.Cu")
		(net "DRV_ACT_NET12")
	)
	(via
		(at 16.071342 -260.089396)
		(size 0.5588)
		(drill 0.3048)
		(layers "F.Cu" "B.Cu")
		(net "DRV_ACT_NET12")
	)
	(segment
		(start 16.071342 -259.861558)
		(end 16.764 -259.1689)
		(width 0.111252)
		(layer "B.Cu")
		(net "DRV_ACT_NET12")
	)
	(segment
		(start 16.071342 -260.089396)
		(end 16.071342 -259.861558)
		(width 0.111252)
		(layer "B.Cu")
		(net "DRV_ACT_NET12")
	)
	(segment
		(start 30.416246 -343.4207)
		(end 29.6164 -344.220546)
		(width 0.111252)
		(layer "F.Cu")
		(net "DRV_ACT_NET11")
	)
	(segment
		(start 27.6606 -351.822258)
		(end 27.6606 -348.957392)
		(width 0.111252)
		(layer "F.Cu")
		(net "DRV_ACT_NET11")
	)
	(segment
		(start 29.336746 -347.281246)
		(end 29.336746 -346.5957)
		(width 0.111252)
		(layer "F.Cu")
		(net "DRV_ACT_NET11")
	)
	(segment
		(start 16.769842 -361.433618)
		(end 16.769588 -361.433364)
		(width 0.111252)
		(layer "F.Cu")
		(net "DRV_ACT_NET11")
	)
	(segment
		(start 16.769588 -361.285536)
		(end 17.7165 -360.338624)
		(width 0.111252)
		(layer "F.Cu")
		(net "DRV_ACT_NET11")
	)
	(segment
		(start 27.6606 -348.957392)
		(end 29.336746 -347.281246)
		(width 0.111252)
		(layer "F.Cu")
		(net "DRV_ACT_NET11")
	)
	(segment
		(start 16.769588 -361.433364)
		(end 16.769588 -361.285536)
		(width 0.111252)
		(layer "F.Cu")
		(net "DRV_ACT_NET11")
	)
	(segment
		(start 17.7165 -360.338624)
		(end 19.144234 -360.338624)
		(width 0.111252)
		(layer "F.Cu")
		(net "DRV_ACT_NET11")
	)
	(segment
		(start 29.6164 -344.220546)
		(end 29.6164 -346.316046)
		(width 0.111252)
		(layer "F.Cu")
		(net "DRV_ACT_NET11")
	)
	(segment
		(start 29.6164 -346.316046)
		(end 29.336746 -346.5957)
		(width 0.111252)
		(layer "F.Cu")
		(net "DRV_ACT_NET11")
	)
	(segment
		(start 19.144234 -360.338624)
		(end 27.6606 -351.822258)
		(width 0.111252)
		(layer "F.Cu")
		(net "DRV_ACT_NET11")
	)
	(via
		(at 29.336746 -346.5957)
		(size 0.7112)
		(drill 0.3556)
		(layers "F.Cu" "B.Cu")
		(net "DRV_ACT_NET11")
	)
	(via
		(at 58.927746 -486.1687)
		(size 0.5588)
		(drill 0.3048)
		(layers "F.Cu" "B.Cu")
		(net "P5V_HDD5")
	)
	(via
		(at 58.927746 -487.1847)
		(size 0.7112)
		(drill 0.3556)
		(layers "F.Cu" "B.Cu")
		(net "P5V_HDD5")
	)
	(via
		(at 63.372746 -489.7247)
		(size 0.5588)
		(drill 0.3048)
		(layers "F.Cu" "B.Cu")
		(net "P5V_HDD5")
	)
	(via
		(at 63.372746 -488.7849)
		(size 0.7112)
		(drill 0.3556)
		(layers "F.Cu" "B.Cu")
		(net "P5V_HDD5")
	)
	(segment
		(start 58.927746 -486.1687)
		(end 58.927746 -487.1847)
		(width 0.508)
		(layer "B.Cu")
		(net "P5V_HDD5")
	)
	(segment
		(start 63.372746 -489.7247)
		(end 63.372746 -488.7849)
		(width 0.508)
		(layer "B.Cu")
		(net "P5V_HDD5")
	)
	(segment
		(start 18.230342 -52.433474)
		(end 17.809972 -52.433474)
		(width 0.111252)
		(layer "F.Cu")
		(net "DRV_ACT_14")
	)
	(segment
		(start 18.23339 -52.430426)
		(end 18.230342 -52.433474)
		(width 0.111252)
		(layer "F.Cu")
		(net "DRV_ACT_14")
	)
	(segment
		(start 17.5006 -52.742846)
		(end 17.5006 -55.019194)
		(width 0.111252)
		(layer "F.Cu")
		(net "DRV_ACT_14")
	)
	(segment
		(start 17.809972 -52.433474)
		(end 17.5006 -52.742846)
		(width 0.111252)
		(layer "F.Cu")
		(net "DRV_ACT_14")
	)
	(segment
		(start 19.27352 -52.430426)
		(end 18.23339 -52.430426)
		(width 0.111252)
		(layer "F.Cu")
		(net "DRV_ACT_14")
	)
	(segment
		(start 17.5006 -55.019194)
		(end 17.65554 -55.174134)
		(width 0.111252)
		(layer "F.Cu")
		(net "DRV_ACT_14")
	)
	(segment
		(start 19.748246 -51.9557)
		(end 19.27352 -52.430426)
		(width 0.111252)
		(layer "F.Cu")
		(net "DRV_ACT_14")
	)
	(via
		(at 17.65554 -55.174134)
		(size 0.7112)
		(drill 0.3556)
		(layers "F.Cu" "B.Cu")
		(net "DRV_ACT_14")
	)
	(segment
		(start 19.910044 -468.376)
		(end 19.684746 -468.150702)
		(width 0.111252)
		(layer "F.Cu")
		(net "DRV_ACT_NET10")
	)
	(segment
		(start 19.684746 -468.2617)
		(end 19.684746 -468.150702)
		(width 0.111252)
		(layer "F.Cu")
		(net "DRV_ACT_NET10")
	)
	(segment
		(start 22.507448 -468.376)
		(end 19.910044 -468.376)
		(width 0.111252)
		(layer "F.Cu")
		(net "DRV_ACT_NET10")
	)
	(segment
		(start 16.5862 -466.118956)
		(end 16.5862 -467.3092)
		(width 0.111252)
		(layer "F.Cu")
		(net "DRV_ACT_NET10")
	)
	(segment
		(start 16.769842 -464.433666)
		(end 16.14678 -464.433666)
		(width 0.111252)
		(layer "F.Cu")
		(net "DRV_ACT_NET10")
	)
	(segment
		(start 19.31162 -468.634826)
		(end 19.684746 -468.2617)
		(width 0.111252)
		(layer "F.Cu")
		(net "DRV_ACT_NET10")
	)
	(segment
		(start 22.732746 -468.150702)
		(end 22.507448 -468.376)
		(width 0.111252)
		(layer "F.Cu")
		(net "DRV_ACT_NET10")
	)
	(segment
		(start 16.4338 -467.4616)
		(end 16.4338 -468.482172)
		(width 0.111252)
		(layer "F.Cu")
		(net "DRV_ACT_NET10")
	)
	(segment
		(start 16.586454 -468.634826)
		(end 19.31162 -468.634826)
		(width 0.111252)
		(layer "F.Cu")
		(net "DRV_ACT_NET10")
	)
	(segment
		(start 16.14678 -464.433666)
		(end 15.774416 -464.80603)
		(width 0.111252)
		(layer "F.Cu")
		(net "DRV_ACT_NET10")
	)
	(segment
		(start 16.4338 -468.482172)
		(end 16.586454 -468.634826)
		(width 0.111252)
		(layer "F.Cu")
		(net "DRV_ACT_NET10")
	)
	(segment
		(start 16.5862 -467.3092)
		(end 16.4338 -467.4616)
		(width 0.111252)
		(layer "F.Cu")
		(net "DRV_ACT_NET10")
	)
	(segment
		(start 15.774416 -465.307172)
		(end 16.5862 -466.118956)
		(width 0.111252)
		(layer "F.Cu")
		(net "DRV_ACT_NET10")
	)
	(segment
		(start 15.774416 -464.80603)
		(end 15.774416 -465.307172)
		(width 0.111252)
		(layer "F.Cu")
		(net "DRV_ACT_NET10")
	)
	(via
		(at 22.732746 -468.150702)
		(size 0.7112)
		(drill 0.3556)
		(layers "F.Cu" "B.Cu")
		(net "DRV_ACT_NET10")
	)
	(via
		(at 67.182746 -499.8847)
		(size 0.7112)
		(drill 0.3556)
		(layers "F.Cu" "B.Cu")
		(net "P12V_HDD5")
	)
	(via
		(at 54.137052 -495.986562)
		(size 0.5588)
		(drill 0.3048)
		(layers "F.Cu" "B.Cu")
		(net "P12V_HDD5")
	)
	(via
		(at 54.863746 -496.5827)
		(size 0.7112)
		(drill 0.3556)
		(layers "F.Cu" "B.Cu")
		(net "P12V_HDD5")
	)
	(via
		(at 67.182746 -498.8687)
		(size 0.5588)
		(drill 0.3048)
		(layers "F.Cu" "B.Cu")
		(net "P12V_HDD5")
	)
	(segment
		(start 67.182746 -498.8687)
		(end 67.182746 -499.8847)
		(width 0.508)
		(layer "B.Cu")
		(net "P12V_HDD5")
	)
	(segment
		(start 54.137052 -495.986562)
		(end 54.73319 -496.5827)
		(width 0.508)
		(layer "B.Cu")
		(net "P12V_HDD5")
	)
	(segment
		(start 54.73319 -496.5827)
		(end 54.863746 -496.5827)
		(width 0.508)
		(layer "B.Cu")
		(net "P12V_HDD5")
	)
	(segment
		(start 16.130016 -155.05938)
		(end 16.130016 -155.05303)
		(width 0.111252)
		(layer "F.Cu")
		(net "DRV_ACT_13")
	)
	(segment
		(start 15.3416 -155.829)
		(end 15.630398 -155.540456)
		(width 0.111252)
		(layer "F.Cu")
		(net "DRV_ACT_13")
	)
	(segment
		(start 16.281654 -154.907742)
		(end 17.620742 -154.907742)
		(width 0.111252)
		(layer "F.Cu")
		(net "DRV_ACT_13")
	)
	(segment
		(start 18.146522 -155.433522)
		(end 18.230342 -155.433522)
		(width 0.111252)
		(layer "F.Cu")
		(net "DRV_ACT_13")
	)
	(segment
		(start 19.748754 -155.3083)
		(end 19.623532 -155.433522)
		(width 0.111252)
		(layer "F.Cu")
		(net "DRV_ACT_13")
	)
	(segment
		(start 16.130016 -155.05303)
		(end 16.23695 -154.946096)
		(width 0.111252)
		(layer "F.Cu")
		(net "DRV_ACT_13")
	)
	(segment
		(start 17.620742 -154.907742)
		(end 18.146522 -155.433522)
		(width 0.111252)
		(layer "F.Cu")
		(net "DRV_ACT_13")
	)
	(segment
		(start 16.23695 -154.946096)
		(end 16.2433 -154.946096)
		(width 0.111252)
		(layer "F.Cu")
		(net "DRV_ACT_13")
	)
	(segment
		(start 15.3416 -156.464)
		(end 15.3416 -155.829)
		(width 0.111252)
		(layer "F.Cu")
		(net "DRV_ACT_13")
	)
	(segment
		(start 19.623532 -155.433522)
		(end 18.230342 -155.433522)
		(width 0.111252)
		(layer "F.Cu")
		(net "DRV_ACT_13")
	)
	(segment
		(start 15.630398 -155.540456)
		(end 15.686024 -155.503372)
		(width 0.111252)
		(layer "F.Cu")
		(net "DRV_ACT_13")
	)
	(segment
		(start 16.2433 -154.946096)
		(end 16.281654 -154.907742)
		(width 0.111252)
		(layer "F.Cu")
		(net "DRV_ACT_13")
	)
	(segment
		(start 15.686024 -155.503372)
		(end 16.130016 -155.05938)
		(width 0.111252)
		(layer "F.Cu")
		(net "DRV_ACT_13")
	)
	(via
		(at 15.3416 -156.464)
		(size 0.7112)
		(drill 0.3556)
		(layers "F.Cu" "B.Cu")
		(net "DRV_ACT_13")
	)
	(segment
		(start 50.061114 -40.2717)
		(end 49.808638 -40.524176)
		(width 0.111252)
		(layer "F.Cu")
		(net "DRV_ACT_NET9")
	)
	(segment
		(start 45.338746 -40.2717)
		(end 44.894246 -40.7162)
		(width 0.111252)
		(layer "F.Cu")
		(net "DRV_ACT_NET9")
	)
	(segment
		(start 49.80178 -40.524176)
		(end 49.721008 -40.604948)
		(width 0.111252)
		(layer "F.Cu")
		(net "DRV_ACT_NET9")
	)
	(segment
		(start 51.053746 -40.3987)
		(end 50.926746 -40.2717)
		(width 0.111252)
		(layer "F.Cu")
		(net "DRV_ACT_NET9")
	)
	(segment
		(start 48.601884 -40.604948)
		(end 48.521112 -40.524176)
		(width 0.111252)
		(layer "F.Cu")
		(net "DRV_ACT_NET9")
	)
	(segment
		(start 44.326048 -40.9067)
		(end 44.894246 -40.9067)
		(width 0.111252)
		(layer "F.Cu")
		(net "DRV_ACT_NET9")
	)
	(segment
		(start 44.07281 -41.156636)
		(end 44.076112 -41.156636)
		(width 0.111252)
		(layer "F.Cu")
		(net "DRV_ACT_NET9")
	)
	(segment
		(start 44.076112 -41.156636)
		(end 44.326048 -40.9067)
		(width 0.111252)
		(layer "F.Cu")
		(net "DRV_ACT_NET9")
	)
	(segment
		(start 48.514254 -40.524176)
		(end 48.261778 -40.2717)
		(width 0.111252)
		(layer "F.Cu")
		(net "DRV_ACT_NET9")
	)
	(segment
		(start 48.261778 -40.2717)
		(end 45.338746 -40.2717)
		(width 0.111252)
		(layer "F.Cu")
		(net "DRV_ACT_NET9")
	)
	(segment
		(start 50.926746 -40.2717)
		(end 50.061114 -40.2717)
		(width 0.111252)
		(layer "F.Cu")
		(net "DRV_ACT_NET9")
	)
	(segment
		(start 43.663108 -41.566338)
		(end 44.07281 -41.156636)
		(width 0.111252)
		(layer "F.Cu")
		(net "DRV_ACT_NET9")
	)
	(segment
		(start 49.721008 -40.604948)
		(end 48.601884 -40.604948)
		(width 0.111252)
		(layer "F.Cu")
		(net "DRV_ACT_NET9")
	)
	(segment
		(start 48.521112 -40.524176)
		(end 48.514254 -40.524176)
		(width 0.111252)
		(layer "F.Cu")
		(net "DRV_ACT_NET9")
	)
	(segment
		(start 43.230292 -41.566338)
		(end 43.663108 -41.566338)
		(width 0.111252)
		(layer "F.Cu")
		(net "DRV_ACT_NET9")
	)
	(segment
		(start 49.808638 -40.524176)
		(end 49.80178 -40.524176)
		(width 0.111252)
		(layer "F.Cu")
		(net "DRV_ACT_NET9")
	)
	(segment
		(start 44.894246 -40.7162)
		(end 44.894246 -40.9067)
		(width 0.111252)
		(layer "F.Cu")
		(net "DRV_ACT_NET9")
	)
	(via
		(at 51.053746 -40.3987)
		(size 0.7112)
		(drill 0.3556)
		(layers "F.Cu" "B.Cu")
		(net "DRV_ACT_NET9")
	)
	(segment
		(start 19.177 -256.159)
		(end 18.288 -257.048)
		(width 0.111252)
		(layer "F.Cu")
		(net "DRV_ACT_12")
	)
	(segment
		(start 18.230342 -257.461258)
		(end 18.230342 -258.43357)
		(width 0.111252)
		(layer "F.Cu")
		(net "DRV_ACT_12")
	)
	(segment
		(start 18.288 -257.4036)
		(end 18.230342 -257.461258)
		(width 0.111252)
		(layer "F.Cu")
		(net "DRV_ACT_12")
	)
	(segment
		(start 18.288 -257.048)
		(end 18.288 -257.4036)
		(width 0.111252)
		(layer "F.Cu")
		(net "DRV_ACT_12")
	)
	(segment
		(start 20.6375 -256.159)
		(end 19.177 -256.159)
		(width 0.111252)
		(layer "F.Cu")
		(net "DRV_ACT_12")
	)
	(via
		(at 18.288 -257.4036)
		(size 0.5588)
		(drill 0.3048)
		(layers "F.Cu" "B.Cu")
		(net "DRV_ACT_12")
	)
	(via
		(at 18.3642 -258.572)
		(size 0.7112)
		(drill 0.3556)
		(layers "F.Cu" "B.Cu")
		(net "DRV_ACT_12")
	)
	(segment
		(start 18.288 -258.4958)
		(end 18.3642 -258.572)
		(width 0.111252)
		(layer "B.Cu")
		(net "DRV_ACT_12")
	)
	(segment
		(start 18.288 -257.4036)
		(end 18.288 -258.4958)
		(width 0.111252)
		(layer "B.Cu")
		(net "DRV_ACT_12")
	)
	(segment
		(start 50.545746 -144.0307)
		(end 51.053746 -143.5227)
		(width 0.111252)
		(layer "F.Cu")
		(net "DRV_ACT_NET8")
	)
	(segment
		(start 45.211746 -143.7767)
		(end 48.132746 -143.7767)
		(width 0.111252)
		(layer "F.Cu")
		(net "DRV_ACT_NET8")
	)
	(segment
		(start 48.386746 -144.0307)
		(end 50.545746 -144.0307)
		(width 0.111252)
		(layer "F.Cu")
		(net "DRV_ACT_NET8")
	)
	(segment
		(start 44.615862 -144.563084)
		(end 44.894246 -144.2847)
		(width 0.111252)
		(layer "F.Cu")
		(net "DRV_ACT_NET8")
	)
	(segment
		(start 43.230292 -144.566386)
		(end 43.233594 -144.563084)
		(width 0.111252)
		(layer "F.Cu")
		(net "DRV_ACT_NET8")
	)
	(segment
		(start 44.894246 -144.2847)
		(end 44.894246 -144.0942)
		(width 0.111252)
		(layer "F.Cu")
		(net "DRV_ACT_NET8")
	)
	(segment
		(start 43.233594 -144.563084)
		(end 44.615862 -144.563084)
		(width 0.111252)
		(layer "F.Cu")
		(net "DRV_ACT_NET8")
	)
	(segment
		(start 48.132746 -143.7767)
		(end 48.386746 -144.0307)
		(width 0.111252)
		(layer "F.Cu")
		(net "DRV_ACT_NET8")
	)
	(segment
		(start 44.894246 -144.0942)
		(end 45.211746 -143.7767)
		(width 0.111252)
		(layer "F.Cu")
		(net "DRV_ACT_NET8")
	)
	(via
		(at 51.053746 -143.5227)
		(size 0.7112)
		(drill 0.3556)
		(layers "F.Cu" "B.Cu")
		(net "DRV_ACT_NET8")
	)
	(segment
		(start 28.955746 -350.6597)
		(end 28.955746 -349.47352)
		(width 0.111252)
		(layer "F.Cu")
		(net "DRV_ACT_11")
	)
	(segment
		(start 31.150052 -346.686632)
		(end 32.142684 -345.694)
		(width 0.111252)
		(layer "F.Cu")
		(net "DRV_ACT_11")
	)
	(segment
		(start 28.955746 -351.704148)
		(end 28.955746 -350.6597)
		(width 0.111252)
		(layer "F.Cu")
		(net "DRV_ACT_11")
	)
	(segment
		(start 32.142684 -345.694)
		(end 32.5755 -345.694)
		(width 0.111252)
		(layer "F.Cu")
		(net "DRV_ACT_11")
	)
	(segment
		(start 19.226276 -361.433618)
		(end 28.955746 -351.704148)
		(width 0.111252)
		(layer "F.Cu")
		(net "DRV_ACT_11")
	)
	(segment
		(start 18.230342 -361.433618)
		(end 19.226276 -361.433618)
		(width 0.111252)
		(layer "F.Cu")
		(net "DRV_ACT_11")
	)
	(segment
		(start 31.150052 -347.279214)
		(end 31.150052 -346.686632)
		(width 0.111252)
		(layer "F.Cu")
		(net "DRV_ACT_11")
	)
	(segment
		(start 28.955746 -349.47352)
		(end 31.150052 -347.279214)
		(width 0.111252)
		(layer "F.Cu")
		(net "DRV_ACT_11")
	)
	(via
		(at 28.955746 -350.6597)
		(size 0.7112)
		(drill 0.3556)
		(layers "F.Cu" "B.Cu")
		(net "DRV_ACT_11")
	)
	(segment
		(start 47.878746 -246.0117)
		(end 48.513746 -246.6467)
		(width 0.111252)
		(layer "F.Cu")
		(net "DRV_ACT_NET7")
	)
	(segment
		(start 44.830746 -246.7737)
		(end 45.338746 -246.2657)
		(width 0.111252)
		(layer "F.Cu")
		(net "DRV_ACT_NET7")
	)
	(segment
		(start 43.230292 -247.566434)
		(end 44.292012 -247.566434)
		(width 0.111252)
		(layer "F.Cu")
		(net "DRV_ACT_NET7")
	)
	(segment
		(start 48.513746 -246.6467)
		(end 50.799746 -246.6467)
		(width 0.111252)
		(layer "F.Cu")
		(net "DRV_ACT_NET7")
	)
	(segment
		(start 46.608746 -246.0117)
		(end 47.878746 -246.0117)
		(width 0.111252)
		(layer "F.Cu")
		(net "DRV_ACT_NET7")
	)
	(segment
		(start 45.338746 -246.2657)
		(end 46.354746 -246.2657)
		(width 0.111252)
		(layer "F.Cu")
		(net "DRV_ACT_NET7")
	)
	(segment
		(start 44.830746 -247.0277)
		(end 44.830746 -246.7737)
		(width 0.111252)
		(layer "F.Cu")
		(net "DRV_ACT_NET7")
	)
	(segment
		(start 46.354746 -246.2657)
		(end 46.608746 -246.0117)
		(width 0.111252)
		(layer "F.Cu")
		(net "DRV_ACT_NET7")
	)
	(segment
		(start 44.292012 -247.566434)
		(end 44.830746 -247.0277)
		(width 0.111252)
		(layer "F.Cu")
		(net "DRV_ACT_NET7")
	)
	(via
		(at 50.799746 -246.6467)
		(size 0.7112)
		(drill 0.3556)
		(layers "F.Cu" "B.Cu")
		(net "DRV_ACT_NET7")
	)
	(segment
		(start 18.233644 -464.430364)
		(end 19.528282 -464.430364)
		(width 0.111252)
		(layer "F.Cu")
		(net "DRV_ACT_10")
	)
	(segment
		(start 20.954746 -464.467702)
		(end 20.608544 -464.1215)
		(width 0.111252)
		(layer "F.Cu")
		(net "DRV_ACT_10")
	)
	(segment
		(start 20.608544 -464.1215)
		(end 19.837146 -464.1215)
		(width 0.111252)
		(layer "F.Cu")
		(net "DRV_ACT_10")
	)
	(segment
		(start 18.230342 -464.433666)
		(end 18.233644 -464.430364)
		(width 0.111252)
		(layer "F.Cu")
		(net "DRV_ACT_10")
	)
	(segment
		(start 19.528282 -464.430364)
		(end 19.837146 -464.1215)
		(width 0.111252)
		(layer "F.Cu")
		(net "DRV_ACT_10")
	)
	(via
		(at 19.837146 -464.1215)
		(size 0.7112)
		(drill 0.3556)
		(layers "F.Cu" "B.Cu")
		(net "DRV_ACT_10")
	)
	(segment
		(start 43.230292 -350.566482)
		(end 43.233594 -350.56318)
		(width 0.111252)
		(layer "F.Cu")
		(net "DRV_ACT_NET6")
	)
	(segment
		(start 47.977298 -350.370648)
		(end 47.977298 -350.616266)
		(width 0.111252)
		(layer "F.Cu")
		(net "DRV_ACT_NET6")
	)
	(segment
		(start 43.928792 -350.56318)
		(end 44.495212 -351.1296)
		(width 0.111252)
		(layer "F.Cu")
		(net "DRV_ACT_NET6")
	)
	(segment
		(start 48.577246 -349.7707)
		(end 47.977298 -350.370648)
		(width 0.111252)
		(layer "F.Cu")
		(net "DRV_ACT_NET6")
	)
	(segment
		(start 47.977298 -350.616266)
		(end 47.463964 -351.1296)
		(width 0.111252)
		(layer "F.Cu")
		(net "DRV_ACT_NET6")
	)
	(segment
		(start 44.495212 -351.1296)
		(end 47.244 -351.1296)
		(width 0.111252)
		(layer "F.Cu")
		(net "DRV_ACT_NET6")
	)
	(segment
		(start 47.463964 -351.1296)
		(end 47.244 -351.1296)
		(width 0.111252)
		(layer "F.Cu")
		(net "DRV_ACT_NET6")
	)
	(segment
		(start 43.233594 -350.56318)
		(end 43.928792 -350.56318)
		(width 0.111252)
		(layer "F.Cu")
		(net "DRV_ACT_NET6")
	)
	(via
		(at 47.244 -351.1296)
		(size 0.7112)
		(drill 0.3556)
		(layers "F.Cu" "B.Cu")
		(net "DRV_ACT_NET6")
	)
	(segment
		(start 40.551608 -41.566338)
		(end 41.769792 -41.566338)
		(width 0.111252)
		(layer "F.Cu")
		(net "DRV_ACT_9")
	)
	(segment
		(start 42.544746 -39.6367)
		(end 42.417746 -39.5097)
		(width 0.111252)
		(layer "F.Cu")
		(net "DRV_ACT_9")
	)
	(segment
		(start 41.769792 -41.566338)
		(end 42.266108 -41.566338)
		(width 0.111252)
		(layer "F.Cu")
		(net "DRV_ACT_9")
	)
	(segment
		(start 40.195246 -41.9227)
		(end 40.551608 -41.566338)
		(width 0.111252)
		(layer "F.Cu")
		(net "DRV_ACT_9")
	)
	(segment
		(start 42.544746 -41.2877)
		(end 42.544746 -39.6367)
		(width 0.111252)
		(layer "F.Cu")
		(net "DRV_ACT_9")
	)
	(segment
		(start 42.266108 -41.566338)
		(end 42.544746 -41.2877)
		(width 0.111252)
		(layer "F.Cu")
		(net "DRV_ACT_9")
	)
	(via
		(at 42.417746 -39.5097)
		(size 0.7112)
		(drill 0.3556)
		(layers "F.Cu" "B.Cu")
		(net "DRV_ACT_9")
	)
	(segment
		(start 44.449746 -452.1327)
		(end 45.037756 -452.72071)
		(width 0.111252)
		(layer "F.Cu")
		(net "DRV_ACT_NET5")
	)
	(segment
		(start 45.037756 -452.783702)
		(end 44.258484 -453.562974)
		(width 0.111252)
		(layer "F.Cu")
		(net "DRV_ACT_NET5")
	)
	(segment
		(start 44.449746 -451.3707)
		(end 44.449746 -452.1327)
		(width 0.111252)
		(layer "F.Cu")
		(net "DRV_ACT_NET5")
	)
	(segment
		(start 43.941746 -450.8627)
		(end 44.449746 -451.3707)
		(width 0.111252)
		(layer "F.Cu")
		(net "DRV_ACT_NET5")
	)
	(segment
		(start 43.233594 -453.562974)
		(end 43.230292 -453.566276)
		(width 0.111252)
		(layer "F.Cu")
		(net "DRV_ACT_NET5")
	)
	(segment
		(start 44.258484 -453.562974)
		(end 43.233594 -453.562974)
		(width 0.111252)
		(layer "F.Cu")
		(net "DRV_ACT_NET5")
	)
	(segment
		(start 45.037756 -452.72071)
		(end 45.037756 -452.783702)
		(width 0.111252)
		(layer "F.Cu")
		(net "DRV_ACT_NET5")
	)
	(via
		(at 43.941746 -450.8627)
		(size 0.7112)
		(drill 0.3556)
		(layers "F.Cu" "B.Cu")
		(net "DRV_ACT_NET5")
	)
	(segment
		(start 41.995852 -144.566386)
		(end 42.4688 -144.093438)
		(width 0.111252)
		(layer "F.Cu")
		(net "DRV_ACT_8")
	)
	(segment
		(start 40.385746 -144.7927)
		(end 40.615362 -144.563084)
		(width 0.111252)
		(layer "F.Cu")
		(net "DRV_ACT_8")
	)
	(segment
		(start 41.769792 -144.566386)
		(end 41.995852 -144.566386)
		(width 0.111252)
		(layer "F.Cu")
		(net "DRV_ACT_8")
	)
	(segment
		(start 40.615362 -144.563084)
		(end 41.76649 -144.563084)
		(width 0.111252)
		(layer "F.Cu")
		(net "DRV_ACT_8")
	)
	(segment
		(start 41.76649 -144.563084)
		(end 41.769792 -144.566386)
		(width 0.111252)
		(layer "F.Cu")
		(net "DRV_ACT_8")
	)
	(segment
		(start 40.068246 -144.7927)
		(end 40.385746 -144.7927)
		(width 0.111252)
		(layer "F.Cu")
		(net "DRV_ACT_8")
	)
	(segment
		(start 42.4688 -144.093438)
		(end 42.4688 -142.494)
		(width 0.111252)
		(layer "F.Cu")
		(net "DRV_ACT_8")
	)
	(via
		(at 42.4688 -142.494)
		(size 0.7112)
		(drill 0.3556)
		(layers "F.Cu" "B.Cu")
		(net "DRV_ACT_8")
	)
	(segment
		(start 232.377742 -42.779696)
		(end 232.917746 -42.779696)
		(width 0.111252)
		(layer "F.Cu")
		(net "DRV_ACT_NET4")
	)
	(segment
		(start 231.161082 -41.563036)
		(end 232.377742 -42.779696)
		(width 0.111252)
		(layer "F.Cu")
		(net "DRV_ACT_NET4")
	)
	(segment
		(start 232.917746 -42.779696)
		(end 234.309412 -42.779696)
		(width 0.111252)
		(layer "F.Cu")
		(net "DRV_ACT_NET4")
	)
	(segment
		(start 228.233478 -41.563036)
		(end 231.161082 -41.563036)
		(width 0.111252)
		(layer "F.Cu")
		(net "DRV_ACT_NET4")
	)
	(segment
		(start 228.230176 -41.566338)
		(end 228.233478 -41.563036)
		(width 0.111252)
		(layer "F.Cu")
		(net "DRV_ACT_NET4")
	)
	(via
		(at 232.917746 -42.779696)
		(size 0.7112)
		(drill 0.3556)
		(layers "F.Cu" "B.Cu")
		(net "DRV_ACT_NET4")
	)
	(zone
		(layer "F.Cu")
		(hatch none 0.5)
		(connect_pads
			(clearance 0)
		)
		(min_thickness 0.25)
		(keepout
			(tracks allowed)
			(vias allowed)
			(pads allowed)
			(copperpour allowed)
			(footprints allowed)
		)
		(placement
			(enabled no)
			(sheetname "")
		)
		(fill
			(thermal_gap 0.5)
			(thermal_bridge_width 0.5)
			(island_removal_mode 0)
		)
		(polygon
			(pts
				(xy 40.258746 -268.7447) (xy 41.401746 -268.7447) (xy 41.528746 -268.6177) (xy 41.528746 -267.6017)
				(xy 41.401746 -267.4747) (xy 40.385746 -267.4747) (xy 40.004746 -267.8557) (xy 40.004746 -268.4907)
			)
		)
	)
	(zone
		(layer "F.Cu")
		(hatch none 0.5)
		(connect_pads
			(clearance 0)
		)
		(min_thickness 0.25)
		(keepout
			(tracks allowed)
			(vias allowed)
			(pads allowed)
			(copperpour allowed)
			(footprints not_allowed)
		)
		(placement
			(enabled no)
			(sheetname "")
		)
		(fill
			(thermal_gap 0.5)
			(thermal_bridge_width 0.5)
			(island_removal_mode 0)
		)
		(polygon
			(pts
				(arc
					(start 69.000116 -476.000064)
					(mid 73.000108 -480.000056)
					(end 69.000116 -484.000048)
				)
				(arc
					(start 69.000116 -484.000048)
					(mid 65.000124 -480.000056)
					(end 69.000116 -476.000064)
				)
			)
		)
	)
	(zone
		(net "P12V_HDD9")
		(layer "F.Cu")
		(hatch none 0.5)
		(connect_pads
			(clearance 0.5)
		)
		(min_thickness 0.25)
		(fill yes
			(thermal_gap 0.5)
			(thermal_bridge_width 0.5)
			(island_removal_mode 0)
		)
		(polygon
			(pts
				(xy 65.548002 -81.2927) (xy 64.515746 -82.324956) (xy 57.657492 -82.324956) (xy 57.276492 -82.705956)
				(xy 57.276492 -85.118956) (xy 56.895492 -85.499956) (xy 46.354492 -85.499956) (xy 42.671492 -81.816956)
				(xy 37.083492 -81.816956) (xy 36.829492 -82.070956) (xy 36.829492 -84.991956) (xy 37.083492 -85.245956)
				(xy 40.893492 -85.245956) (xy 43.814492 -88.166956) (xy 61.468 -88.166956) (xy 61.6966 -88.395556)
				(xy 61.6966 -88.7476) (xy 61.6966 -91.808554) (xy 64.261746 -94.3737) (xy 71.373746 -94.3737) (xy 72.389746 -93.3577)
				(xy 72.389746 -89.1667) (xy 71.843646 -88.6206) (xy 69.697346 -88.6206) (xy 69.468746 -88.392) (xy 69.468746 -81.6737)
				(xy 69.087746 -81.2927)
			)
		)
		(polygon
			(pts
				(xy 54.812692 -87.150956) (xy 54.558692 -87.150956) (xy 54.558692 -87.404956) (xy 54.812692 -87.404956)
			)
		)
		(polygon
			(pts
				(xy 53.949092 -87.150956) (xy 53.695092 -87.150956) (xy 53.695092 -87.404956) (xy 53.949092 -87.404956)
			)
		)
		(polygon
			(pts
				(xy 61.086492 -84.991956) (xy 60.832492 -84.991956) (xy 60.832492 -85.245956) (xy 61.086492 -85.245956)
			)
		)
		(polygon
			(pts
				(xy 59.943492 -84.991956) (xy 59.689492 -84.991956) (xy 59.689492 -85.245956) (xy 59.943492 -85.245956)
			)
		)
	)
	(zone
		(net "P5VA")
		(layer "F.Cu")
		(hatch none 0.5)
		(connect_pads
			(clearance 0.5)
		)
		(min_thickness 0.25)
		(fill yes
			(thermal_gap 0.5)
			(thermal_bridge_width 0.5)
			(island_removal_mode 0)
		)
		(polygon
			(pts
				(xy 201.61123 -381.056388) (xy 201.23023 -381.437388) (xy 201.23023 -386.390388) (xy 201.48423 -386.644388)
				(xy 205.67523 -386.644388) (xy 206.05623 -386.263388) (xy 206.05623 -381.310388) (xy 205.80223 -381.056388)
			)
		)
	)
	(zone
		(net "P3V3")
		(layer "F.Cu")
		(hatch none 0.5)
		(connect_pads
			(clearance 0.5)
		)
		(min_thickness 0.25)
		(fill yes
			(thermal_gap 0.5)
			(thermal_bridge_width 0.5)
			(island_removal_mode 0)
		)
		(polygon
			(pts
				(xy 191.388746 -38.6207) (xy 191.007746 -39.0017) (xy 191.007746 -40.5257) (xy 191.261746 -40.7797)
				(xy 212.851746 -40.7797) (xy 213.359746 -40.2717) (xy 213.359746 -39.0017) (xy 212.978746 -38.6207)
			)
		)
		(polygon
			(pts
				(xy 211.607146 -40.0685) (xy 211.353146 -40.0685) (xy 211.353146 -40.3225) (xy 211.607146 -40.3225)
			)
		)
		(polygon
			(pts
				(xy 211.048346 -40.0685) (xy 210.794346 -40.0685) (xy 210.794346 -40.3225) (xy 211.048346 -40.3225)
			)
		)
		(polygon
			(pts
				(xy 209.702146 -40.0685) (xy 209.448146 -40.0685) (xy 209.448146 -40.3225) (xy 209.702146 -40.3225)
			)
		)
		(polygon
			(pts
				(xy 209.143346 -40.0685) (xy 208.889346 -40.0685) (xy 208.889346 -40.3225) (xy 209.143346 -40.3225)
			)
		)
		(polygon
			(pts
				(xy 207.797146 -40.0685) (xy 207.543146 -40.0685) (xy 207.543146 -40.3225) (xy 207.797146 -40.3225)
			)
		)
		(polygon
			(pts
				(xy 207.238346 -40.0685) (xy 206.984346 -40.0685) (xy 206.984346 -40.3225) (xy 207.238346 -40.3225)
			)
		)
	)
	(zone
		(layer "F.Cu")
		(hatch none 0.5)
		(connect_pads
			(clearance 0)
		)
		(min_thickness 0.25)
		(keepout
			(tracks not_allowed)
			(vias allowed)
			(pads allowed)
			(copperpour not_allowed)
			(footprints allowed)
		)
		(placement
			(enabled no)
			(sheetname "")
		)
		(fill
			(thermal_gap 0.5)
			(thermal_bridge_width 0.5)
			(island_removal_mode 0)
		)
		(polygon
			(pts
				(arc
					(start 6.489446 -162.32378)
					(mid 6.332595 -162.255228)
					(end 6.164072 -162.225228)
				)
				(arc
					(start 6.164072 -162.459416)
					(mid 6.748272 -163.043616)
					(end 7.332472 -162.459416)
				)
				(arc
					(start 7.332472 -161.531554)
					(mid 6.748399 -160.9471)
					(end 6.164072 -161.5313)
				)
				(arc
					(start 6.164072 -161.765488)
					(mid 6.332582 -161.735445)
					(end 6.489446 -161.666936)
				)
				(arc
					(start 6.489446 -161.666936)
					(mid 6.970891 -161.342015)
					(end 6.572758 -161.76498)
				)
				(arc
					(start 6.572758 -161.76498)
					(mid 6.376538 -161.854839)
					(end 6.164072 -161.892742)
				)
				(arc
					(start 6.164072 -162.097974)
					(mid 6.376545 -162.135853)
					(end 6.572758 -162.225736)
				)
				(arc
					(start 6.572758 -162.225736)
					(mid 6.970921 -162.648727)
					(end 6.489446 -162.32378)
				)
			)
		)
	)
	(zone
		(layer "F.Cu")
		(hatch none 0.5)
		(connect_pads
			(clearance 0)
		)
		(min_thickness 0.25)
		(keepout
			(tracks not_allowed)
			(vias allowed)
			(pads allowed)
			(copperpour not_allowed)
			(footprints allowed)
		)
		(placement
			(enabled no)
			(sheetname "")
		)
		(fill
			(thermal_gap 0.5)
			(thermal_bridge_width 0.5)
			(island_removal_mode 0)
		)
		(polygon
			(pts
				(arc
					(start 35.638486 -472.820492)
					(mid 35.051873 -472.233498)
					(end 34.465006 -472.820238)
				)
				(arc
					(start 34.465006 -473.748354)
					(mid 35.051746 -474.335094)
					(end 35.638486 -473.748354)
				)
				(arc
					(start 35.638486 -473.593414)
					(mid 35.532195 -473.570576)
					(end 35.42792 -473.53982)
				)
				(arc
					(start 35.42792 -473.53982)
					(mid 35.373723 -473.537324)
					(end 35.32632 -473.563696)
				)
				(arc
					(start 35.29838 -473.591636)
					(mid 34.84512 -473.95498)
					(end 35.208464 -473.50172)
				)
				(xy 35.254946 -473.455238)
				(arc
					(start 35.257486 -473.455238)
					(mid 35.358524 -473.4108)
					(end 35.46856 -473.419424)
				)
				(arc
					(start 35.46856 -473.419424)
					(mid 35.55278 -473.444601)
					(end 35.638486 -473.464128)
				)
				(arc
					(start 35.638486 -473.256356)
					(mid 35.41791 -473.180487)
					(end 35.217862 -473.060522)
				)
				(arc
					(start 35.217862 -473.060522)
					(mid 34.837157 -472.62204)
					(end 35.304476 -472.966796)
				)
				(arc
					(start 35.304476 -472.966796)
					(mid 35.464014 -473.06188)
					(end 35.638486 -473.125546)
				)
			)
		)
	)
	(zone
		(layer "F.Cu")
		(hatch none 0.5)
		(connect_pads
			(clearance 0)
		)
		(min_thickness 0.25)
		(keepout
			(tracks not_allowed)
			(vias allowed)
			(pads allowed)
			(copperpour not_allowed)
			(footprints allowed)
		)
		(placement
			(enabled no)
			(sheetname "")
		)
		(fill
			(thermal_gap 0.5)
			(thermal_bridge_width 0.5)
			(island_removal_mode 0)
		)
		(polygon
			(pts
				(arc
					(start 29.41574 -341.503254)
					(mid 28.829127 -340.91626)
					(end 28.24226 -341.503)
				)
				(xy 28.24226 -341.691976) (xy 28.288742 -341.6935)
				(arc
					(start 28.321 -341.6935)
					(mid 28.448134 -341.678655)
					(end 28.568396 -341.634826)
				)
				(arc
					(start 28.568396 -341.634826)
					(mid 29.054452 -341.317125)
					(end 28.650946 -341.734648)
				)
				(arc
					(start 28.650946 -341.734648)
					(mid 28.504468 -341.795191)
					(end 28.347924 -341.819992)
				)
				(xy 28.347416 -341.8205) (xy 28.262326 -341.8205) (xy 28.262072 -341.819992) (xy 28.24226 -341.81923)
				(arc
					(start 28.24226 -342.07831)
					(mid 28.281583 -342.075433)
					(end 28.321 -342.0745)
				)
				(arc
					(start 28.321 -342.0745)
					(mid 28.502968 -342.103683)
					(end 28.666694 -342.188292)
				)
				(arc
					(start 28.666694 -342.188292)
					(mid 29.040668 -342.63237)
					(end 28.578302 -342.281256)
				)
				(arc
					(start 28.578302 -342.281256)
					(mid 28.45569 -342.221895)
					(end 28.321 -342.2015)
				)
				(arc
					(start 28.321 -342.2015)
					(mid 28.281563 -342.202628)
					(end 28.24226 -342.206072)
				)
				(arc
					(start 28.24226 -342.431116)
					(mid 28.829 -343.017856)
					(end 29.41574 -342.431116)
				)
			)
		)
	)
	(zone
		(net "P5VB")
		(layer "F.Cu")
		(hatch none 0.5)
		(connect_pads
			(clearance 0.5)
		)
		(min_thickness 0.25)
		(fill yes
			(thermal_gap 0.5)
			(thermal_bridge_width 0.5)
			(island_removal_mode 0)
		)
		(polygon
			(pts
				(xy 67.309746 -486.0417) (xy 67.055746 -486.2957) (xy 67.055746 -490.9947) (xy 67.690746 -491.6297)
				(xy 70.611746 -491.6297) (xy 72.008746 -490.2327) (xy 72.008746 -487.0577) (xy 70.992746 -486.0417)
			)
		)
	)
	(zone
		(net "12V_PRE_6")
		(layer "F.Cu")
		(hatch none 0.5)
		(connect_pads
			(clearance 0.5)
		)
		(min_thickness 0.25)
		(fill yes
			(thermal_gap 0.5)
			(thermal_bridge_width 0.5)
			(island_removal_mode 0)
		)
		(polygon
			(pts
				(xy 37.083492 -389.537956) (xy 36.829492 -389.791956) (xy 36.829492 -390.172956) (xy 37.083492 -390.426956)
				(xy 43.052492 -390.426956) (xy 46.735492 -394.109956) (xy 56.387492 -394.109956) (xy 56.768492 -393.728956)
				(xy 56.768492 -391.696956) (xy 56.387492 -391.315956) (xy 48.132492 -391.315956) (xy 46.354492 -389.537956)
			)
		)
	)
	(zone
		(layer "F.Cu")
		(hatch none 0.5)
		(connect_pads
			(clearance 0)
		)
		(min_thickness 0.25)
		(keepout
			(tracks allowed)
			(vias allowed)
			(pads allowed)
			(copperpour allowed)
			(footprints not_allowed)
		)
		(placement
			(enabled no)
			(sheetname "")
		)
		(fill
			(thermal_gap 0.5)
			(thermal_bridge_width 0.5)
			(island_removal_mode 0)
		)
		(polygon
			(pts
				(arc
					(start 252.499876 -476.000064)
					(mid 256.499868 -480.000056)
					(end 252.499876 -484.000048)
				)
				(arc
					(start 252.499876 -484.000048)
					(mid 248.499884 -480.000056)
					(end 252.499876 -476.000064)
				)
			)
		)
	)
	(zone
		(layer "F.Cu")
		(hatch none 0.5)
		(connect_pads
			(clearance 0)
		)
		(min_thickness 0.25)
		(keepout
			(tracks allowed)
			(vias allowed)
			(pads allowed)
			(copperpour allowed)
			(footprints not_allowed)
		)
		(placement
			(enabled no)
			(sheetname "")
		)
		(fill
			(thermal_gap 0.5)
			(thermal_bridge_width 0.5)
			(island_removal_mode 0)
		)
		(polygon
			(pts
				(arc
					(start 252.499876 -275.500084)
					(mid 248.499884 -271.500092)
					(end 252.499876 -267.5001)
				)
				(arc
					(start 252.499876 -267.5001)
					(mid 256.499868 -271.500092)
					(end 252.499876 -275.500084)
				)
			)
		)
	)
	(zone
		(layer "F.Cu")
		(hatch none 0.5)
		(connect_pads
			(clearance 0)
		)
		(min_thickness 0.25)
		(keepout
			(tracks allowed)
			(vias allowed)
			(pads allowed)
			(copperpour allowed)
			(footprints not_allowed)
		)
		(placement
			(enabled no)
			(sheetname "")
		)
		(fill
			(thermal_gap 0.5)
			(thermal_bridge_width 0.5)
			(island_removal_mode 0)
		)
		(polygon
			(pts
				(xy 220.009974 -67.840098) (xy 204.900022 -67.840098) (xy 204.900022 -0.999998) (xy 220.009974 -0.999998)
				(xy 220.009974 -8.999982) (xy 231.119934 -8.999982) (xy 231.119934 -41.170098) (xy 220.009974 -41.170098)
			)
		)
	)
	(zone
		(layer "F.Cu")
		(hatch none 0.5)
		(connect_pads
			(clearance 0)
		)
		(min_thickness 0.25)
		(keepout
			(tracks not_allowed)
			(vias allowed)
			(pads allowed)
			(copperpour not_allowed)
			(footprints allowed)
		)
		(placement
			(enabled no)
			(sheetname "")
		)
		(fill
			(thermal_gap 0.5)
			(thermal_bridge_width 0.5)
			(island_removal_mode 0)
		)
		(polygon
			(pts
				(arc
					(start 32.190182 -273.691096)
					(mid 31.603569 -273.104102)
					(end 31.016702 -273.690842)
				)
				(arc
					(start 31.016702 -274.618958)
					(mid 31.603442 -275.205698)
					(end 32.190182 -274.618958)
				)
				(arc
					(start 32.190182 -274.383754)
					(mid 32.019078 -274.410462)
					(end 31.86049 -274.48002)
				)
				(arc
					(start 31.86049 -274.48002)
					(mid 31.383371 -274.811172)
					(end 31.775654 -274.382992)
				)
				(arc
					(start 31.775654 -274.382992)
					(mid 31.974203 -274.291269)
					(end 32.190182 -274.256754)
				)
				(arc
					(start 32.190182 -274.053046)
					(mid 31.974189 -274.01858)
					(end 31.775654 -273.926808)
				)
				(arc
					(start 31.775654 -273.926808)
					(mid 31.383423 -273.498673)
					(end 31.86049 -273.82978)
				)
				(arc
					(start 31.86049 -273.82978)
					(mid 32.019087 -273.899306)
					(end 32.190182 -273.926046)
				)
			)
		)
	)
	(zone
		(net "P5VC")
		(layer "F.Cu")
		(hatch none 0.5)
		(connect_pads
			(clearance 0.5)
		)
		(min_thickness 0.25)
		(fill yes
			(thermal_gap 0.5)
			(thermal_bridge_width 0.5)
			(island_removal_mode 0)
		)
		(polygon
			(pts
				(xy 47.624746 -133.632702) (xy 47.370746 -133.886702) (xy 47.370746 -140.109702) (xy 47.878746 -140.617702)
				(xy 49.783746 -140.617702) (xy 53.339746 -137.061702) (xy 53.339746 -133.886702) (xy 53.085746 -133.632702)
			)
		)
	)
	(zone
		(layer "F.Cu")
		(hatch none 0.5)
		(connect_pads
			(clearance 0)
		)
		(min_thickness 0.25)
		(keepout
			(tracks not_allowed)
			(vias allowed)
			(pads allowed)
			(copperpour not_allowed)
			(footprints allowed)
		)
		(placement
			(enabled no)
			(sheetname "")
		)
		(fill
			(thermal_gap 0.5)
			(thermal_bridge_width 0.5)
			(island_removal_mode 0)
		)
		(polygon
			(pts
				(arc
					(start 7.292086 -127.499618)
					(mid 6.705473 -126.912624)
					(end 6.118606 -127.499364)
				)
				(xy 6.118606 -127.76708)
				(arc
					(start 6.37413 -127.76708)
					(mid 6.449719 -127.756187)
					(end 6.519164 -127.724408)
				)
				(arc
					(start 6.519164 -127.724408)
					(mid 6.831761 -127.236062)
					(end 6.646164 -127.785368)
				)
				(arc
					(start 6.646164 -127.785368)
					(mid 6.533148 -127.860631)
					(end 6.401308 -127.893064)
				)
				(xy 6.400546 -127.89408) (xy 6.118606 -127.89408) (xy 6.118606 -128.09728) (xy 6.434328 -128.09728)
				(arc
					(start 6.435344 -128.098296)
					(mid 6.539539 -128.122186)
					(end 6.632194 -128.175512)
				)
				(arc
					(start 6.632194 -128.175512)
					(mid 6.845892 -128.714502)
					(end 6.505194 -128.245362)
				)
				(arc
					(start 6.505194 -128.245362)
					(mid 6.457687 -128.229592)
					(end 6.407912 -128.22428)
				)
				(xy 6.118606 -128.22428)
				(arc
					(start 6.118606 -128.458214)
					(mid 6.705346 -129.044954)
					(end 7.292086 -128.458214)
				)
			)
		)
	)
	(zone
		(net "P5V_HDD9")
		(layer "F.Cu")
		(hatch none 0.5)
		(connect_pads
			(clearance 0.5)
		)
		(min_thickness 0.25)
		(fill yes
			(thermal_gap 0.5)
			(thermal_bridge_width 0.5)
			(island_removal_mode 0)
		)
		(polygon
			(pts
				(xy 59.0804 -73.5076) (xy 58.6486 -73.9394) (xy 58.6486 -73.942956) (xy 57.784492 -73.942956) (xy 57.403492 -74.323956)
				(xy 57.403492 -76.863956) (xy 57.022492 -77.244956) (xy 50.164492 -77.244956) (xy 47.116492 -74.196956)
				(xy 36.956492 -74.196956) (xy 36.829492 -74.323956) (xy 36.829492 -76.355956) (xy 36.956492 -76.482956)
				(xy 40.259 -76.482956) (xy 41.322244 -77.5462) (xy 44.6278 -77.5462) (xy 46.993556 -79.911956) (xy 48.386492 -79.911956)
				(xy 61.566044 -79.911956) (xy 63.6524 -79.911956) (xy 64.385444 -80.645) (xy 65.7606 -80.645) (xy 66.166492 -80.239108)
				(xy 66.166492 -76.228956) (xy 65.604136 -75.6666) (xy 63.2206 -75.6666) (xy 63.2206 -73.7362) (xy 62.992 -73.5076)
			)
		)
		(polygon
			(pts
				(xy 56.184292 -78.768956) (xy 55.930292 -78.768956) (xy 55.930292 -79.022956) (xy 56.184292 -79.022956)
			)
		)
		(polygon
			(pts
				(xy 55.320692 -78.768956) (xy 55.066692 -78.768956) (xy 55.066692 -79.022956) (xy 55.320692 -79.022956)
			)
		)
		(polygon
			(pts
				(xy 59.943492 -76.609956) (xy 59.689492 -76.609956) (xy 59.689492 -76.863956) (xy 59.943492 -76.863956)
			)
		)
		(polygon
			(pts
				(xy 61.086492 -73.815956) (xy 60.832492 -73.815956) (xy 60.832492 -74.069956) (xy 61.086492 -74.069956)
			)
		)
		(polygon
			(pts
				(xy 59.943492 -73.815956) (xy 59.689492 -73.815956) (xy 59.689492 -74.069956) (xy 59.943492 -74.069956)
			)
		)
	)
	(zone
		(net "P12V_HDD5")
		(layer "F.Cu")
		(hatch none 0.5)
		(connect_pads
			(clearance 0.5)
		)
		(min_thickness 0.25)
		(fill yes
			(thermal_gap 0.5)
			(thermal_bridge_width 0.5)
			(island_removal_mode 0)
		)
		(polygon
			(pts
				(xy 59.054746 -492.0107) (xy 58.800746 -492.2647) (xy 58.800746 -494.0427) (xy 57.276746 -495.5667)
				(xy 53.339746 -495.5667) (xy 51.688746 -493.9157) (xy 37.210746 -493.9157) (xy 36.956746 -494.1697)
				(xy 36.956746 -495.6937) (xy 37.210746 -495.9477) (xy 39.5224 -495.9477) (xy 40.0177 -496.443) (xy 40.4495 -496.8748)
				(xy 49.8348 -496.8748) (xy 50.4444 -497.4844) (xy 51.676046 -497.4844) (xy 51.688746 -497.4717)
				(xy 61.087 -497.4717) (xy 61.7474 -498.1321) (xy 61.7474 -501.396) (xy 62.7761 -502.4247) (xy 71.754746 -502.4247)
				(xy 72.008746 -502.1707) (xy 72.008746 -498.1067) (xy 71.881746 -497.9797) (xy 69.9897 -497.9797)
				(xy 69.85 -497.84) (xy 69.85 -496.951) (xy 69.849746 -496.950746) (xy 69.849746 -493.1537) (xy 69.468746 -492.7727)
				(xy 61.848746 -492.7727) (xy 61.086746 -492.0107)
			)
		)
		(polygon
			(pts
				(xy 54.8132 -496.4684) (xy 54.5592 -496.4684) (xy 54.5592 -496.7224) (xy 54.8132 -496.7224)
			)
		)
		(polygon
			(pts
				(xy 53.9496 -496.4684) (xy 53.6956 -496.4684) (xy 53.6956 -496.7224) (xy 53.9496 -496.7224)
			)
		)
		(polygon
			(pts
				(xy 60.816236 -494.788698) (xy 60.562236 -494.788698) (xy 60.562236 -495.042698) (xy 60.816236 -495.042698)
			)
		)
		(polygon
			(pts
				(xy 59.673236 -494.788698) (xy 59.419236 -494.788698) (xy 59.419236 -495.042698) (xy 59.673236 -495.042698)
			)
		)
	)
	(zone
		(net "5V_PRE_11")
		(layer "F.Cu")
		(hatch none 0.5)
		(connect_pads
			(clearance 0.5)
		)
		(min_thickness 0.25)
		(fill yes
			(thermal_gap 0.5)
			(thermal_bridge_width 0.5)
			(island_removal_mode 0)
		)
		(polygon
			(pts
				(xy 26.161746 -325.783702) (xy 25.907746 -326.037702) (xy 25.907746 -327.307702) (xy 24.002746 -329.212702)
				(xy 20.573746 -329.212702) (xy 20.446746 -329.339702) (xy 20.446746 -329.974702) (xy 20.573746 -330.101702)
				(xy 24.764746 -330.101702) (xy 26.161746 -328.704702) (xy 27.558746 -328.704702) (xy 27.685746 -328.577702)
				(xy 27.685746 -325.910702) (xy 27.558746 -325.783702)
			)
		)
	)
	(zone
		(net "5V_PRE_12")
		(layer "F.Cu")
		(hatch none 0.5)
		(connect_pads
			(clearance 0.5)
		)
		(min_thickness 0.25)
		(fill yes
			(thermal_gap 0.5)
			(thermal_bridge_width 0.5)
			(island_removal_mode 0)
		)
		(polygon
			(pts
				(xy 23.240746 -225.9457) (xy 22.859746 -226.3267) (xy 20.700746 -226.3267) (xy 20.573746 -226.4537)
				(xy 20.573746 -226.7077) (xy 20.827746 -226.9617) (xy 23.367746 -226.9617) (xy 23.748746 -227.3427)
				(xy 24.891746 -227.3427) (xy 25.145746 -227.0887) (xy 25.145746 -226.1997) (xy 24.891746 -225.9457)
			)
		)
	)
	(zone
		(net "P12V")
		(layer "F.Cu")
		(hatch none 0.5)
		(connect_pads
			(clearance 0.5)
		)
		(min_thickness 0.25)
		(fill yes
			(thermal_gap 0.5)
			(thermal_bridge_width 0.5)
			(island_removal_mode 0)
		)
		(polygon
			(pts
				(xy 16.891 -407.289) (xy 26.289 -407.289) (xy 27.178 -406.4) (xy 27.178 -400.939) (xy 26.67 -400.431)
				(xy 18.161 -400.431) (xy 16.51 -402.082) (xy 16.51 -406.908)
			)
		)
	)
	(zone
		(net "P3V3_IN")
		(layer "F.Cu")
		(hatch none 0.5)
		(connect_pads
			(clearance 0.5)
		)
		(min_thickness 0.25)
		(fill yes
			(thermal_gap 0.5)
			(thermal_bridge_width 0.5)
			(island_removal_mode 0)
		)
		(polygon
			(pts
				(xy 223.266 -434.848) (xy 223.012 -435.102) (xy 223.012 -436.499) (xy 222.885 -436.626) (xy 221.742 -436.626)
				(xy 221.361 -437.007) (xy 221.361 -442.5188) (xy 221.5134 -442.6712) (xy 223.1644 -442.6712) (xy 223.3168 -442.5188)
				(xy 223.3168 -438.2262) (xy 223.52 -438.023) (xy 223.52 -436.753) (xy 223.774 -436.499) (xy 223.774 -434.975)
				(xy 223.647 -434.848)
			)
		)
		(polygon
			(pts
				(xy 222.4786 -441.579) (xy 222.2246 -441.579) (xy 222.2246 -441.833) (xy 222.4786 -441.833)
			)
		)
		(polygon
			(pts
				(xy 222.834454 -438.9247) (xy 222.580454 -438.9247) (xy 222.580454 -439.1787) (xy 222.834454 -439.1787)
			)
		)
		(polygon
			(pts
				(xy 222.834454 -438.3659) (xy 222.580454 -438.3659) (xy 222.580454 -438.6199) (xy 222.834454 -438.6199)
			)
		)
	)
	(zone
		(net "P12V_HDD10")
		(layer "F.Cu")
		(hatch none 0.5)
		(connect_pads
			(clearance 0.5)
		)
		(min_thickness 0.25)
		(fill yes
			(thermal_gap 0.5)
			(thermal_bridge_width 0.5)
			(island_removal_mode 0)
		)
		(polygon
			(pts
				(xy 34.1757 -412.0007) (xy 33.3756 -412.8008) (xy 33.3756 -416.6362) (xy 33.401 -416.6616) (xy 33.401 -416.969702)
				(xy 33.147 -417.223702) (xy 23.748746 -417.223702) (xy 20.192746 -420.779702) (xy 20.192746 -423.954702)
				(xy 20.446746 -424.208702) (xy 22.859746 -424.208702) (xy 23.113746 -423.954702) (xy 23.113746 -422.430702)
				(xy 25.907746 -419.636702) (xy 28.701746 -419.636702) (xy 29.082746 -420.017702) (xy 29.082746 -422.684702)
				(xy 29.463746 -423.065702) (xy 41.004744 -423.065702) (xy 41.147746 -422.9227) (xy 41.147746 -417.957)
				(xy 41.770046 -417.3347) (xy 43.814746 -417.3347) (xy 44.195746 -416.9537) (xy 44.195746 -412.5087)
				(xy 43.687746 -412.0007)
			)
		)
		(polygon
			(pts
				(xy 32.511746 -420.017702) (xy 32.257746 -420.017702) (xy 32.257746 -420.271702) (xy 32.511746 -420.271702)
			)
		)
		(polygon
			(pts
				(xy 31.368746 -420.017702) (xy 31.114746 -420.017702) (xy 31.114746 -420.271702) (xy 31.368746 -420.271702)
			)
		)
		(polygon
			(pts
				(xy 26.4922 -417.957) (xy 26.2382 -417.957) (xy 26.2382 -418.211) (xy 26.4922 -418.211)
			)
		)
		(polygon
			(pts
				(xy 25.6286 -417.957) (xy 25.3746 -417.957) (xy 25.3746 -418.211) (xy 25.6286 -418.211)
			)
		)
	)
	(zone
		(layer "F.Cu")
		(hatch none 0.5)
		(connect_pads
			(clearance 0)
		)
		(min_thickness 0.25)
		(keepout
			(tracks allowed)
			(vias allowed)
			(pads allowed)
			(copperpour allowed)
			(footprints allowed)
		)
		(placement
			(enabled no)
			(sheetname "")
		)
		(fill
			(thermal_gap 0.5)
			(thermal_bridge_width 0.5)
			(island_removal_mode 0)
		)
		(polygon
			(pts
				(xy 169.578782 -460.46898) (xy 169.705782 -460.34198) (xy 169.705782 -459.32598) (xy 169.578782 -459.19898)
				(xy 168.181782 -459.19898) (xy 167.567356 -459.19898) (xy 167.367712 -459.398624) (xy 167.367712 -460.34198)
				(xy 167.510206 -460.484474) (xy 169.563288 -460.484474)
			)
		)
	)
	(zone
		(net "GND")
		(layer "F.Cu")
		(hatch none 0.5)
		(connect_pads
			(clearance 0.5)
		)
		(min_thickness 0.25)
		(fill yes
			(thermal_gap 0.5)
			(thermal_bridge_width 0.5)
			(island_removal_mode 0)
		)
		(polygon
			(pts
				(xy 39.116 -112.776) (xy 39.0144 -112.8776) (xy 39.0144 -112.8903) (xy 38.735 -113.1697) (xy 35.178746 -113.1697)
				(xy 34.797746 -112.7887) (xy 32.257746 -112.7887) (xy 32.003746 -113.0427) (xy 32.003746 -115.518946)
				(xy 32.4866 -116.0018) (xy 43.2562 -116.0018) (xy 43.5102 -115.7478) (xy 43.5102 -114.4524) (xy 43.2435 -114.1857)
				(xy 40.4622 -114.1857) (xy 40.004746 -113.728246) (xy 40.004746 -112.928146) (xy 39.8526 -112.776)
			)
		)
		(polygon
			(pts
				(xy 34.671 -115.0112) (xy 34.417 -115.0112) (xy 34.417 -115.2652) (xy 34.671 -115.2652)
			)
		)
		(polygon
			(pts
				(xy 33.8074 -115.0112) (xy 33.5534 -115.0112) (xy 33.5534 -115.2652) (xy 33.8074 -115.2652)
			)
		)
	)
	(zone
		(net "P5V_HDD12")
		(layer "F.Cu")
		(hatch none 0.5)
		(connect_pads
			(clearance 0.5)
		)
		(min_thickness 0.25)
		(fill yes
			(thermal_gap 0.5)
			(thermal_bridge_width 0.5)
			(island_removal_mode 0)
		)
		(polygon
			(pts
				(xy 20.700746 -223.5327) (xy 20.446746 -223.7867) (xy 20.446746 -225.8187) (xy 20.573746 -225.9457)
				(xy 24.764746 -225.9457) (xy 25.145746 -225.5647) (xy 25.145746 -223.9137) (xy 24.764746 -223.5327)
			)
		)
	)
	(zone
		(layer "F.Cu")
		(hatch none 0.5)
		(connect_pads
			(clearance 0)
		)
		(min_thickness 0.25)
		(keepout
			(tracks not_allowed)
			(vias allowed)
			(pads allowed)
			(copperpour not_allowed)
			(footprints allowed)
		)
		(placement
			(enabled no)
			(sheetname "")
		)
		(fill
			(thermal_gap 0.5)
			(thermal_bridge_width 0.5)
			(island_removal_mode 0)
		)
		(polygon
			(pts
				(arc
					(start 24.388572 -349.758254)
					(mid 24.236361 -349.654203)
					(end 24.068278 -349.578422)
				)
				(arc
					(start 24.052022 -349.878904)
					(mid 24.606504 -350.496378)
					(end 25.223978 -349.941896)
				)
				(arc
					(start 25.282144 -348.859348)
					(mid 24.727789 -348.241881)
					(end 24.110188 -348.796102)
				)
				(xy 24.095964 -349.063056)
				(arc
					(start 24.12365 -349.063056)
					(mid 24.289292 -349.039613)
					(end 24.441912 -348.971108)
				)
				(arc
					(start 24.441912 -348.971108)
					(mid 24.913716 -348.63254)
					(end 24.528018 -349.066612)
				)
				(arc
					(start 24.528018 -349.066612)
					(mid 24.34789 -349.154471)
					(end 24.150574 -349.189548)
				)
				(xy 24.150066 -349.190056) (xy 24.089106 -349.190056)
				(arc
					(start 24.075136 -349.447104)
					(mid 24.286956 -349.537078)
					(end 24.477218 -349.66656)
				)
				(arc
					(start 24.477218 -349.66656)
					(mid 24.847688 -350.113818)
					(end 24.388572 -349.758254)
				)
			)
		)
	)
	(zone
		(net "P3V3")
		(layer "F.Cu")
		(hatch none 0.5)
		(connect_pads
			(clearance 0.5)
		)
		(min_thickness 0.25)
		(fill yes
			(thermal_gap 0.5)
			(thermal_bridge_width 0.5)
			(island_removal_mode 0)
		)
		(polygon
			(pts
				(xy 48.005746 -123.4567) (xy 47.548546 -123.9139) (xy 46.253146 -123.9139) (xy 45.973746 -124.1933)
				(xy 45.973746 -124.9045) (xy 46.684946 -125.6157) (xy 47.269146 -125.6157) (xy 47.624746 -125.9713)
				(xy 47.624746 -126.4793) (xy 47.421546 -126.6825) (xy 45.973746 -126.6825) (xy 45.821346 -126.8349)
				(xy 45.821346 -127.1397) (xy 45.922946 -127.2413) (xy 47.650146 -127.2413) (xy 47.751746 -127.1397)
				(xy 50.672746 -127.1397) (xy 51.307746 -126.5047) (xy 51.307746 -123.8377) (xy 50.926746 -123.4567)
			)
		)
		(polygon
			(pts
				(xy 49.8348 -126.365) (xy 49.5808 -126.365) (xy 49.5808 -126.619) (xy 49.8348 -126.619)
			)
		)
		(polygon
			(pts
				(xy 49.2252 -126.365) (xy 48.9712 -126.365) (xy 48.9712 -126.619) (xy 49.2252 -126.619)
			)
		)
	)
	(zone
		(net "12V_PRE_14")
		(layer "F.Cu")
		(hatch none 0.5)
		(connect_pads
			(clearance 0.5)
		)
		(min_thickness 0.25)
		(fill yes
			(thermal_gap 0.5)
			(thermal_bridge_width 0.5)
			(island_removal_mode 0)
		)
		(polygon
			(pts
				(xy 72.389746 -8.6487) (xy 72.008746 -9.0297) (xy 72.008746 -11.6967) (xy 72.897746 -12.5857) (xy 75.310746 -12.5857)
				(xy 75.818746 -12.0777) (xy 75.818746 -9.9187) (xy 75.437746 -9.5377) (xy 74.421746 -9.5377) (xy 73.532746 -8.6487)
			)
		)
	)
	(zone
		(net "P3V3")
		(layer "F.Cu")
		(hatch none 0.5)
		(connect_pads
			(clearance 0.5)
		)
		(min_thickness 0.25)
		(fill yes
			(thermal_gap 0.5)
			(thermal_bridge_width 0.5)
			(island_removal_mode 0)
		)
		(polygon
			(pts
				(xy 118.109746 -154.4447) (xy 88.086438 -184.468008) (xy 73.227438 -184.468008) (xy 72.008746 -185.6867)
				(xy 72.008746 -186.9567) (xy 72.135746 -187.0837) (xy 77.596746 -187.0837) (xy 78.485746 -187.9727)
				(xy 78.485746 -188.7347) (xy 78.612746 -188.8617) (xy 81.025746 -188.8617) (xy 81.279746 -188.6077)
				(xy 81.279746 -187.8711) (xy 81.635346 -187.5155) (xy 85.492082 -187.5155) (xy 85.851746 -187.875164)
				(xy 94.204282 -187.875164) (xy 122.046746 -160.0327) (xy 141.731746 -160.0327) (xy 142.874746 -158.8897)
				(xy 142.874746 -155.5877) (xy 141.731746 -154.4447)
			)
		)
		(polygon
			(pts
				(xy 79.196946 -188.0743) (xy 78.942946 -188.0743) (xy 78.942946 -188.3283) (xy 79.196946 -188.3283)
			)
		)
		(polygon
			(pts
				(xy 76.1238 -186.436) (xy 75.8698 -186.436) (xy 75.8698 -186.69) (xy 76.1238 -186.69)
			)
		)
		(polygon
			(pts
				(xy 75.5142 -186.436) (xy 75.2602 -186.436) (xy 75.2602 -186.69) (xy 75.5142 -186.69)
			)
		)
		(polygon
			(pts
				(xy 78.917546 -185.1787) (xy 78.663546 -185.1787) (xy 78.663546 -185.4327) (xy 78.917546 -185.4327)
			)
		)
		(polygon
			(pts
				(xy 78.307946 -185.1787) (xy 78.053946 -185.1787) (xy 78.053946 -185.4327) (xy 78.307946 -185.4327)
			)
		)
	)
	(zone
		(net "P12V")
		(layer "F.Cu")
		(hatch none 0.5)
		(connect_pads
			(clearance 0.5)
		)
		(min_thickness 0.25)
		(fill yes
			(thermal_gap 0.5)
			(thermal_bridge_width 0.5)
			(island_removal_mode 0)
		)
		(polygon
			(pts
				(xy 73.278746 -497.4717) (xy 72.643746 -498.1067) (xy 72.643746 -500.9007) (xy 72.897746 -501.1547)
				(xy 77.723746 -501.1547) (xy 77.730096 -501.148096) (xy 77.971904 -501.148096) (xy 78.359 -500.761)
				(xy 78.867 -500.761) (xy 79.120746 -500.507254) (xy 79.120746 -498.2337) (xy 78.358746 -497.4717)
			)
		)
		(polygon
			(pts
				(xy 78.3844 -500.018304) (xy 78.1304 -500.018304) (xy 78.1304 -500.272304) (xy 78.3844 -500.272304)
			)
		)
		(polygon
			(pts
				(xy 78.607158 -499.564914) (xy 78.353158 -499.564914) (xy 78.353158 -499.818914) (xy 78.607158 -499.818914)
			)
		)
		(polygon
			(pts
				(xy 78.607158 -499.006114) (xy 78.353158 -499.006114) (xy 78.353158 -499.260114) (xy 78.607158 -499.260114)
			)
		)
		(polygon
			(pts
				(xy 78.607158 -498.548914) (xy 78.353158 -498.548914) (xy 78.353158 -498.802914) (xy 78.607158 -498.802914)
			)
		)
		(polygon
			(pts
				(xy 78.607158 -497.990114) (xy 78.353158 -497.990114) (xy 78.353158 -498.244114) (xy 78.607158 -498.244114)
			)
		)
	)
	(zone
		(net "P3V3_LX_COOPER")
		(layer "F.Cu")
		(hatch none 0.5)
		(connect_pads
			(clearance 0.5)
		)
		(min_thickness 0.25)
		(fill yes
			(thermal_gap 0.5)
			(thermal_bridge_width 0.5)
			(island_removal_mode 0)
		)
		(polygon
			(pts
				(xy 211.4042 -436.9562) (xy 211.0486 -437.3118) (xy 211.0486 -439.293) (xy 211.2518 -439.4962) (xy 211.6836 -439.4962)
				(xy 211.8614 -439.674) (xy 211.8614 -441.2234) (xy 212.1408 -441.5028) (xy 219.7354 -441.5028) (xy 219.8878 -441.3504)
				(xy 219.8878 -438.277) (xy 218.567 -436.9562)
			)
		)
	)
	(zone
		(net "GND")
		(layer "F.Cu")
		(hatch none 0.5)
		(connect_pads
			(clearance 0.5)
		)
		(min_thickness 0.25)
		(fill yes
			(thermal_gap 0.5)
			(thermal_bridge_width 0.5)
			(island_removal_mode 0)
		)
		(polygon
			(pts
				(xy 210.057746 -180.4797) (xy 209.676746 -180.8607) (xy 209.676746 -182.3847) (xy 210.057746 -182.7657)
				(xy 211.454746 -182.7657) (xy 212.343746 -181.8767) (xy 218.820746 -181.8767) (xy 219.074746 -181.6227)
				(xy 219.074746 -180.7337) (xy 218.820746 -180.4797)
			)
		)
		(polygon
			(pts
				(xy 217.905584 -181.199028) (xy 217.651584 -181.199028) (xy 217.651584 -181.453028) (xy 217.905584 -181.453028)
			)
		)
		(polygon
			(pts
				(xy 217.041984 -181.199028) (xy 216.787984 -181.199028) (xy 216.787984 -181.453028) (xy 217.041984 -181.453028)
			)
		)
	)
	(zone
		(net "P5VB")
		(layer "F.Cu")
		(hatch none 0.5)
		(connect_pads
			(clearance 0.5)
		)
		(min_thickness 0.25)
		(fill yes
			(thermal_gap 0.5)
			(thermal_bridge_width 0.5)
			(island_removal_mode 0)
		)
		(polygon
			(pts
				(xy 67.944746 -382.6637) (xy 67.436746 -383.1717) (xy 67.436746 -388.6327) (xy 67.817746 -389.0137)
				(xy 71.119746 -389.0137) (xy 71.500746 -388.6327) (xy 71.500746 -382.9177) (xy 71.246746 -382.6637)
			)
		)
	)
	(zone
		(net "P5V_HDD14")
		(layer "F.Cu")
		(hatch none 0.5)
		(connect_pads
			(clearance 0.5)
		)
		(min_thickness 0.25)
		(fill yes
			(thermal_gap 0.5)
			(thermal_bridge_width 0.5)
			(island_removal_mode 0)
		)
		(polygon
			(pts
				(xy 18.541746 -17.2847) (xy 18.160746 -17.6657) (xy 18.160746 -19.3167) (xy 18.414746 -19.5707)
				(xy 22.732746 -19.5707) (xy 22.859746 -19.4437) (xy 22.859746 -17.9197) (xy 22.732746 -17.7927)
				(xy 20.192746 -17.7927) (xy 19.684746 -17.2847)
			)
		)
	)
	(zone
		(net "GND")
		(layer "F.Cu")
		(hatch none 0.5)
		(connect_pads
			(clearance 0.5)
		)
		(min_thickness 0.25)
		(fill yes
			(thermal_gap 0.5)
			(thermal_bridge_width 0.5)
			(island_removal_mode 0)
		)
		(polygon
			(pts
				(xy 35.940746 -459.7527) (xy 35.178746 -460.5147) (xy 35.178746 -461.2767) (xy 35.559746 -461.6577)
				(xy 65.912746 -461.6577) (xy 66.166746 -461.4037) (xy 66.166746 -460.2607) (xy 65.658746 -459.7527)
			)
		)
		(polygon
			(pts
				(arc
					(start 39.174928 -459.91653)
					(mid 39.187887 -459.814079)
					(end 39.10457 -459.753208)
				)
				(xy 35.998404 -459.753208) (xy 35.927792 -459.766416) (xy 35.179254 -460.514954) (xy 35.179254 -461.276446)
				(xy 35.56 -461.657192)
				(arc
					(start 39.162736 -461.657192)
					(mid 39.247236 -461.59301)
					(end 39.228522 -461.488536)
				)
				(arc
					(start 39.228522 -461.488536)
					(mid 38.918297 -460.712183)
					(end 39.174928 -459.91653)
				)
			)
		)
	)
	(zone
		(layer "F.Cu")
		(hatch none 0.5)
		(connect_pads
			(clearance 0)
		)
		(min_thickness 0.25)
		(keepout
			(tracks not_allowed)
			(vias allowed)
			(pads allowed)
			(copperpour not_allowed)
			(footprints allowed)
		)
		(placement
			(enabled no)
			(sheetname "")
		)
		(fill
			(thermal_gap 0.5)
			(thermal_bridge_width 0.5)
			(island_removal_mode 0)
		)
		(polygon
			(pts
				(arc
					(start 217.32621 -475.478602)
					(mid 217.278927 -474.920607)
					(end 216.78519 -474.656404)
				)
				(arc
					(start 215.92159 -474.661484)
					(mid 215.338406 -475.25178)
					(end 215.928702 -475.834964)
				)
				(arc
					(start 216.483438 -475.831662)
					(mid 216.36832 -475.761995)
					(end 216.264236 -475.676722)
				)
				(xy 216.263474 -475.676722)
				(arc
					(start 216.081864 -475.494858)
					(mid 215.718121 -475.042107)
					(end 216.171526 -475.404942)
				)
				(arc
					(start 216.334848 -475.568264)
					(mid 216.601249 -475.746297)
					(end 216.915492 -475.808802)
				)
				(arc
					(start 216.944702 -475.808802)
					(mid 217.113751 -475.731675)
					(end 217.250264 -475.605602)
				)
				(xy 217.061288 -475.605602)
				(arc
					(start 217.060272 -475.604586)
					(mid 216.95478 -475.580374)
					(end 216.861136 -475.5261)
				)
				(arc
					(start 216.861136 -475.5261)
					(mid 216.648461 -474.986971)
					(end 216.988136 -475.456504)
				)
				(arc
					(start 216.988136 -475.456504)
					(mid 217.03671 -475.473004)
					(end 217.087704 -475.478602)
				)
			)
		)
	)
	(zone
		(layer "F.Cu")
		(hatch none 0.5)
		(connect_pads
			(clearance 0)
		)
		(min_thickness 0.25)
		(keepout
			(tracks allowed)
			(vias allowed)
			(pads allowed)
			(copperpour allowed)
			(footprints not_allowed)
		)
		(placement
			(enabled no)
			(sheetname "")
		)
		(fill
			(thermal_gap 0.5)
			(thermal_bridge_width 0.5)
			(island_removal_mode 0)
		)
		(polygon
			(pts
				(arc
					(start 4.500118 -487.400092)
					(mid 0.500126 -483.4001)
					(end 4.500118 -479.400108)
				)
				(arc
					(start 4.500118 -479.400108)
					(mid 8.50011 -483.4001)
					(end 4.500118 -487.400092)
				)
			)
		)
	)
	(zone
		(net "P12V")
		(layer "F.Cu")
		(hatch none 0.5)
		(connect_pads
			(clearance 0.5)
		)
		(min_thickness 0.25)
		(fill yes
			(thermal_gap 0.5)
			(thermal_bridge_width 0.5)
			(island_removal_mode 0)
		)
		(polygon
			(pts
				(xy 73.913746 -191.7827) (xy 73.532746 -192.1637) (xy 73.532746 -195.0847) (xy 73.786746 -195.3387)
				(xy 76.9747 -195.3387) (xy 77.851 -196.215) (xy 79.248 -196.215) (xy 79.375 -196.088) (xy 79.375 -195.707)
				(xy 79.121 -195.453) (xy 78.486 -195.453) (xy 78.422246 -195.389246) (xy 78.422246 -191.9732) (xy 78.231746 -191.7827)
			)
		)
		(polygon
			(pts
				(xy 78.028546 -194.9831) (xy 77.774546 -194.9831) (xy 77.774546 -195.2371) (xy 78.028546 -195.2371)
			)
		)
		(polygon
			(pts
				(xy 78.028546 -194.4243) (xy 77.774546 -194.4243) (xy 77.774546 -194.6783) (xy 78.028546 -194.6783)
			)
		)
		(polygon
			(pts
				(xy 78.028546 -193.8401) (xy 77.774546 -193.8401) (xy 77.774546 -194.0941) (xy 78.028546 -194.0941)
			)
		)
		(polygon
			(pts
				(xy 78.028546 -193.2813) (xy 77.774546 -193.2813) (xy 77.774546 -193.5353) (xy 78.028546 -193.5353)
			)
		)
	)
	(zone
		(net "P12V_HDD7")
		(layer "F.Cu")
		(hatch none 0.5)
		(connect_pads
			(clearance 0.5)
		)
		(min_thickness 0.25)
		(fill yes
			(thermal_gap 0.5)
			(thermal_bridge_width 0.5)
			(island_removal_mode 0)
		)
		(polygon
			(pts
				(xy 20.446746 -283.9847) (xy 18.668746 -285.7627) (xy 18.668746 -292.2778) (xy 18.7071 -292.3159)
				(xy 18.7071 -299.1231) (xy 19.431 -299.847) (xy 19.545046 -299.847) (xy 19.557746 -299.8597) (xy 24.256746 -299.8597)
				(xy 25.272746 -298.8437) (xy 35.0393 -298.8437) (xy 35.2552 -298.6278) (xy 35.2552 -294.195246)
				(xy 39.623746 -289.8267) (xy 39.623746 -288.1757) (xy 39.369746 -287.9217) (xy 37.083746 -287.9217)
				(xy 33.070292 -291.9349) (xy 28.2067 -291.9349) (xy 27.2796 -291.0078) (xy 27.2796 -290.068) (xy 26.9748 -289.7632)
				(xy 24.9682 -289.7632) (xy 24.003 -288.798) (xy 24.003 -284.607) (xy 23.3807 -283.9847)
			)
		)
		(polygon
			(pts
				(xy 34.3916 -297.7896) (xy 34.1376 -297.7896) (xy 34.1376 -298.0436) (xy 34.3916 -298.0436)
			)
		)
		(polygon
			(pts
				(xy 31.495746 -295.6052) (xy 31.241746 -295.6052) (xy 31.241746 -295.8592) (xy 31.495746 -295.8592)
			)
		)
		(polygon
			(pts
				(xy 28.701746 -295.6052) (xy 28.447746 -295.6052) (xy 28.447746 -295.8592) (xy 28.701746 -295.8592)
			)
		)
		(polygon
			(pts
				(xy 31.495746 -294.4622) (xy 31.241746 -294.4622) (xy 31.241746 -294.7162) (xy 31.495746 -294.7162)
			)
		)
		(polygon
			(pts
				(xy 28.701746 -294.4622) (xy 28.447746 -294.4622) (xy 28.447746 -294.7162) (xy 28.701746 -294.7162)
			)
		)
	)
	(zone
		(layer "F.Cu")
		(hatch none 0.5)
		(connect_pads
			(clearance 0)
		)
		(min_thickness 0.25)
		(keepout
			(tracks not_allowed)
			(vias allowed)
			(pads allowed)
			(copperpour not_allowed)
			(footprints allowed)
		)
		(placement
			(enabled no)
			(sheetname "")
		)
		(fill
			(thermal_gap 0.5)
			(thermal_bridge_width 0.5)
			(island_removal_mode 0)
		)
		(polygon
			(pts
				(arc
					(start 7.568946 -157.531816)
					(mid 6.984873 -156.947362)
					(end 6.400546 -157.531562)
				)
				(arc
					(start 6.400546 -157.757114)
					(mid 6.56419 -157.718412)
					(end 6.718554 -157.651704)
				)
				(arc
					(start 6.718554 -157.651704)
					(mid 7.218122 -157.355983)
					(end 6.795516 -157.754066)
				)
				(arc
					(start 6.795516 -157.754066)
					(mid 6.60438 -157.838732)
					(end 6.400546 -157.88513)
				)
				(arc
					(start 6.400546 -158.09722)
					(mid 6.616076 -158.130634)
					(end 6.813804 -158.222696)
				)
				(arc
					(start 6.813804 -158.222696)
					(mid 7.204126 -158.652639)
					(end 6.728714 -158.319216)
				)
				(arc
					(start 6.728714 -158.319216)
					(mid 6.570994 -158.249741)
					(end 6.400546 -158.22422)
				)
				(arc
					(start 6.400546 -158.459678)
					(mid 6.984746 -159.043878)
					(end 7.568946 -158.459678)
				)
			)
		)
	)
	(zone
		(layer "F.Cu")
		(hatch none 0.5)
		(connect_pads
			(clearance 0)
		)
		(min_thickness 0.25)
		(keepout
			(tracks allowed)
			(vias allowed)
			(pads allowed)
			(copperpour allowed)
			(footprints allowed)
		)
		(placement
			(enabled no)
			(sheetname "")
		)
		(fill
			(thermal_gap 0.5)
			(thermal_bridge_width 0.5)
			(island_removal_mode 0)
		)
		(polygon
			(pts
				(xy 9.270746 -492.1377) (xy 10.794746 -492.1377) (xy 10.921746 -492.0107) (xy 10.921746 -490.6137)
				(xy 10.794746 -490.4867) (xy 9.397746 -490.4867) (xy 9.143746 -490.7407) (xy 9.143746 -492.0107)
			)
		)
	)
	(zone
		(layer "F.Cu")
		(hatch none 0.5)
		(connect_pads
			(clearance 0)
		)
		(min_thickness 0.25)
		(keepout
			(tracks not_allowed)
			(vias allowed)
			(pads allowed)
			(copperpour not_allowed)
			(footprints allowed)
		)
		(placement
			(enabled no)
			(sheetname "")
		)
		(fill
			(thermal_gap 0.5)
			(thermal_bridge_width 0.5)
			(island_removal_mode 0)
		)
		(polygon
			(pts
				(arc
					(start 7.340346 -409.273756)
					(mid 6.779006 -409.835096)
					(end 7.340346 -410.396436)
				)
				(arc
					(start 8.203946 -410.396436)
					(mid 8.765286 -409.835096)
					(end 8.203946 -409.273756)
				)
				(arc
					(start 8.005064 -409.273756)
					(mid 7.949412 -409.312842)
					(end 7.898638 -409.358084)
				)
				(arc
					(start 7.889494 -409.367482)
					(mid 7.860882 -409.442446)
					(end 7.892288 -409.516326)
				)
				(arc
					(start 8.001 -409.625038)
					(mid 8.448928 -409.994266)
					(end 7.930134 -409.73375)
				)
				(xy 7.78383 -409.5877)
				(arc
					(start 7.78383 -409.58516)
					(mid 7.734094 -409.430814)
					(end 7.79653 -409.281122)
				)
				(xy 7.803388 -409.273756)
				(arc
					(start 7.544562 -409.273756)
					(mid 7.473183 -409.409736)
					(end 7.426198 -409.55595)
				)
				(arc
					(start 7.426198 -409.55595)
					(mid 7.317825 -410.126276)
					(end 7.298436 -409.546044)
				)
				(arc
					(start 7.298436 -409.546044)
					(mid 7.338238 -409.406362)
					(end 7.397496 -409.273756)
				)
				(xy 7.3406 -409.273756)
			)
		)
	)
	(zone
		(layer "F.Cu")
		(hatch none 0.5)
		(connect_pads
			(clearance 0)
		)
		(min_thickness 0.25)
		(keepout
			(tracks not_allowed)
			(vias allowed)
			(pads allowed)
			(copperpour not_allowed)
			(footprints allowed)
		)
		(placement
			(enabled no)
			(sheetname "")
		)
		(fill
			(thermal_gap 0.5)
			(thermal_bridge_width 0.5)
			(island_removal_mode 0)
		)
		(polygon
			(pts
				(arc
					(start 215.344756 -165.87724)
					(mid 214.747348 -166.453312)
					(end 215.32342 -167.05072)
				)
				(arc
					(start 216.186766 -167.066468)
					(mid 216.309771 -167.055712)
					(end 216.427812 -167.019478)
				)
				(xy 216.045288 -167.019478)
				(arc
					(start 216.04478 -167.01897)
					(mid 215.820346 -166.969508)
					(end 215.626696 -166.845742)
				)
				(xy 215.625934 -166.845742) (xy 215.607392 -166.8272)
				(arc
					(start 215.490806 -166.710614)
					(mid 215.127462 -166.257354)
					(end 215.580722 -166.620698)
				)
				(arc
					(start 215.697308 -166.737284)
					(mid 215.869067 -166.852143)
					(end 216.071704 -166.892478)
				)
				(arc
					(start 216.614756 -166.892478)
					(mid 216.690848 -166.797692)
					(end 216.74582 -166.689278)
				)
				(xy 216.523824 -166.689278)
				(arc
					(start 216.523316 -166.688516)
					(mid 216.469606 -166.683322)
					(end 216.416636 -166.673022)
				)
				(arc
					(start 216.416636 -166.673022)
					(mid 215.941037 -166.340593)
					(end 216.479628 -166.556436)
				)
				(arc
					(start 216.479628 -166.556436)
					(mid 216.514815 -166.560801)
					(end 216.55024 -166.562278)
				)
				(arc
					(start 216.778586 -166.562278)
					(mid 216.644275 -166.09918)
					(end 216.208356 -165.892988)
				)
			)
		)
	)
	(zone
		(net "P5V_HDD7")
		(layer "F.Cu")
		(hatch none 0.5)
		(connect_pads
			(clearance 0.5)
		)
		(min_thickness 0.25)
		(fill yes
			(thermal_gap 0.5)
			(thermal_bridge_width 0.5)
			(island_removal_mode 0)
		)
		(polygon
			(pts
				(xy 59.563 -278.3586) (xy 59.4106 -278.511) (xy 59.4106 -281.1018) (xy 57.8612 -282.6512) (xy 52.4002 -282.6512)
				(xy 50.0634 -280.3144) (xy 37.1856 -280.3144) (xy 37.1094 -280.3906) (xy 37.1094 -282.0416) (xy 37.3126 -282.2448)
				(xy 40.386 -282.2448) (xy 41.3004 -283.1592) (xy 47.0916 -283.1592) (xy 49.4792 -285.5468) (xy 51.2826 -285.5468)
				(xy 58.166 -285.5468) (xy 58.3311 -285.7119) (xy 58.3311 -289.6616) (xy 58.7502 -290.0807) (xy 61.6839 -290.0807)
				(xy 61.976 -289.7886) (xy 61.976 -287.782) (xy 62.2046 -287.5534) (xy 63.6778 -287.5534) (xy 63.9572 -287.274)
				(xy 63.9572 -286.1056) (xy 63.7794 -285.9278) (xy 62.865 -285.9278) (xy 62.6618 -285.7246) (xy 62.6618 -284.5308)
				(xy 62.6618 -278.8412) (xy 62.1792 -278.3586)
			)
		)
		(polygon
			(pts
				(xy 55.8292 -284.48) (xy 55.5752 -284.48) (xy 55.5752 -284.734) (xy 55.8292 -284.734)
			)
		)
		(polygon
			(pts
				(xy 54.9656 -284.48) (xy 54.7116 -284.48) (xy 54.7116 -284.734) (xy 54.9656 -284.734)
			)
		)
		(polygon
			(pts
				(xy 61.087 -281.4574) (xy 60.833 -281.4574) (xy 60.833 -281.7114) (xy 61.087 -281.7114)
			)
		)
		(polygon
			(pts
				(xy 59.944 -281.4574) (xy 59.69 -281.4574) (xy 59.69 -281.7114) (xy 59.944 -281.7114)
			)
		)
		(polygon
			(pts
				(xy 61.087 -278.6634) (xy 60.833 -278.6634) (xy 60.833 -278.9174) (xy 61.087 -278.9174)
			)
		)
		(polygon
			(pts
				(xy 59.944 -278.6634) (xy 59.69 -278.6634) (xy 59.69 -278.9174) (xy 59.944 -278.9174)
			)
		)
	)
	(zone
		(net "12V_PRE_9")
		(layer "F.Cu")
		(hatch none 0.5)
		(connect_pads
			(clearance 0.5)
		)
		(min_thickness 0.25)
		(fill yes
			(thermal_gap 0.5)
			(thermal_bridge_width 0.5)
			(island_removal_mode 0)
		)
		(polygon
			(pts
				(xy 37.083492 -80.546956) (xy 36.829492 -80.800956) (xy 36.829492 -81.181956) (xy 37.083492 -81.435956)
				(xy 43.052492 -81.435956) (xy 46.735492 -85.118956) (xy 56.387492 -85.118956) (xy 56.768492 -84.737956)
				(xy 56.768492 -82.705956) (xy 56.387492 -82.324956) (xy 48.132492 -82.324956) (xy 46.354492 -80.546956)
			)
		)
	)
	(zone
		(net "5V_PRE_14")
		(layer "F.Cu")
		(hatch none 0.5)
		(connect_pads
			(clearance 0.5)
		)
		(min_thickness 0.25)
		(fill yes
			(thermal_gap 0.5)
			(thermal_bridge_width 0.5)
			(island_removal_mode 0)
		)
		(polygon
			(pts
				(xy 18.287746 -20.2057) (xy 18.033746 -20.4597) (xy 18.033746 -21.7297) (xy 18.287746 -21.9837)
				(xy 19.684746 -21.9837) (xy 19.811746 -21.8567) (xy 19.811746 -21.0947) (xy 19.938746 -20.9677)
				(xy 22.605746 -20.9677) (xy 22.859746 -20.7137) (xy 22.859746 -20.3327) (xy 22.732746 -20.2057)
			)
		)
	)
	(zone
		(layer "F.Cu")
		(hatch none 0.5)
		(connect_pads
			(clearance 0)
		)
		(min_thickness 0.25)
		(keepout
			(tracks not_allowed)
			(vias allowed)
			(pads allowed)
			(copperpour not_allowed)
			(footprints allowed)
		)
		(placement
			(enabled no)
			(sheetname "")
		)
		(fill
			(thermal_gap 0.5)
			(thermal_bridge_width 0.5)
			(island_removal_mode 0)
		)
		(polygon
			(pts
				(xy 8.203184 -370.914422)
				(arc
					(start 7.74319 -370.89334)
					(mid 7.13004 -371.452521)
					(end 7.689088 -372.065804)
				)
				(arc
					(start 8.587486 -372.107206)
					(mid 9.1916 -371.62845)
					(end 8.800338 -370.96446)
				)
				(arc
					(start 8.773922 -370.990876)
					(mid 8.702907 -371.097157)
					(end 8.67791 -371.222524)
				)
				(arc
					(start 8.67791 -371.235986)
					(mid 8.61441 -371.812951)
					(end 8.55091 -371.235986)
				)
				(xy 8.55091 -371.196108)
				(arc
					(start 8.551672 -371.195346)
					(mid 8.581953 -371.057476)
					(end 8.653018 -370.935504)
				)
				(xy 8.641334 -370.934742) (xy 8.374888 -370.92255)
				(arc
					(start 7.966964 -371.33022)
					(mid 7.503549 -371.679928)
					(end 7.879842 -371.237764)
				)
			)
		)
	)
	(zone
		(net "P12V")
		(layer "F.Cu")
		(hatch none 0.5)
		(connect_pads
			(clearance 0.5)
		)
		(min_thickness 0.25)
		(fill yes
			(thermal_gap 0.5)
			(thermal_bridge_width 0.5)
			(island_removal_mode 0)
		)
		(polygon
			(pts
				(xy 197.104 -394.029184) (xy 196.469 -394.664184) (xy 196.469 -394.716) (xy 196.342 -394.843) (xy 196.342 -396.24)
				(xy 196.215 -396.367) (xy 194.437 -396.367) (xy 194.31 -396.494) (xy 194.31 -396.875) (xy 194.691 -397.256)
				(xy 195.453 -397.256) (xy 196.215 -398.018) (xy 196.215 -399.923) (xy 196.469 -400.177) (xy 199.39 -400.177)
				(xy 200.235058 -399.331942) (xy 200.235058 -394.410184) (xy 199.854058 -394.029184)
			)
		)
		(polygon
			(pts
				(xy 196.1388 -396.875) (xy 195.8848 -396.875) (xy 195.8848 -397.129) (xy 196.1388 -397.129)
			)
		)
		(polygon
			(pts
				(xy 195.0974 -396.8242) (xy 194.8434 -396.8242) (xy 194.8434 -397.0782) (xy 195.0974 -397.0782)
			)
		)
	)
	(zone
		(layer "F.Cu")
		(hatch none 0.5)
		(connect_pads
			(clearance 0)
		)
		(min_thickness 0.25)
		(keepout
			(tracks not_allowed)
			(vias allowed)
			(pads allowed)
			(copperpour not_allowed)
			(footprints allowed)
		)
		(placement
			(enabled no)
			(sheetname "")
		)
		(fill
			(thermal_gap 0.5)
			(thermal_bridge_width 0.5)
			(island_removal_mode 0)
		)
		(polygon
			(pts
				(arc
					(start 27.355546 -442.1886)
					(mid 27.280602 -442.185401)
					(end 27.206194 -442.1759)
				)
				(arc
					(start 27.211782 -442.403484)
					(mid 27.283428 -442.394735)
					(end 27.355546 -442.3918)
				)
				(arc
					(start 27.355546 -442.3918)
					(mid 27.413397 -442.400933)
					(end 27.465528 -442.427614)
				)
				(xy 27.46883 -442.427614) (xy 27.487372 -442.446156)
				(arc
					(start 27.656028 -442.615066)
					(mid 28.019771 -443.067817)
					(end 27.566366 -442.704982)
				)
				(arc
					(start 27.397456 -442.536072)
					(mid 27.378228 -442.523224)
					(end 27.355546 -442.5188)
				)
				(arc
					(start 27.355546 -442.5188)
					(mid 27.285017 -442.522038)
					(end 27.215084 -442.531754)
				)
				(xy 27.220418 -442.742828) (xy 27.22372 -442.876178) (xy 27.223974 -442.876432)
				(arc
					(start 27.22626 -442.876432)
					(mid 27.827478 -443.448186)
					(end 28.399232 -442.846968)
				)
				(xy 28.401772 -442.846968) (xy 28.391866 -442.446156) (xy 28.391358 -442.427614) (xy 28.376372 -441.830968)
				(arc
					(start 28.373832 -441.830968)
					(mid 27.772614 -441.259214)
					(end 27.20086 -441.860432)
				)
				(xy 27.19832 -441.860432)
				(arc
					(start 27.202892 -442.046106)
					(mid 27.278829 -442.057698)
					(end 27.355546 -442.0616)
				)
				(arc
					(start 27.3558 -442.0616)
					(mid 27.455508 -442.049938)
					(end 27.549856 -442.015626)
				)
				(arc
					(start 27.549856 -442.015626)
					(mid 27.979327 -441.625655)
					(end 27.651202 -442.104018)
				)
				(arc
					(start 27.651202 -442.104018)
					(mid 27.509548 -442.166965)
					(end 27.356054 -442.1886)
				)
			)
		)
	)
	(zone
		(net "P12V_HDD8")
		(layer "F.Cu")
		(hatch none 0.5)
		(connect_pads
			(clearance 0.5)
		)
		(min_thickness 0.25)
		(fill yes
			(thermal_gap 0.5)
			(thermal_bridge_width 0.5)
			(island_removal_mode 0)
		)
		(polygon
			(pts
				(xy 37.1348 -186.9567) (xy 39.497 -186.9567) (xy 40.76065 -188.22035) (xy 43.681396 -188.22035)
				(xy 46.989746 -191.5287) (xy 61.341 -191.5287) (xy 61.9506 -192.1383) (xy 61.9506 -195.1482) (xy 63.7921 -196.9897)
				(xy 72.135746 -196.9897) (xy 72.643746 -196.4817) (xy 72.643746 -192.2907) (xy 72.262746 -191.9097)
				(xy 70.1167 -191.9097) (xy 69.723 -191.516) (xy 69.723 -190.627) (xy 69.722746 -190.626746) (xy 69.722746 -185.6867)
				(xy 69.595746 -185.5597) (xy 58.927746 -185.5597) (xy 58.673746 -185.8137) (xy 58.673746 -188.2267)
				(xy 57.911746 -188.9887) (xy 49.656746 -188.9887) (xy 45.592746 -184.9247) (xy 37.084 -184.9247)
				(xy 37.0332 -184.9755) (xy 37.0332 -186.8551)
			)
		)
		(polygon
			(pts
				(xy 55.066946 -190.5127) (xy 54.812946 -190.5127) (xy 54.812946 -190.7667) (xy 55.066946 -190.7667)
			)
		)
		(polygon
			(pts
				(xy 54.203346 -190.5127) (xy 53.949346 -190.5127) (xy 53.949346 -190.7667) (xy 54.203346 -190.7667)
			)
		)
		(polygon
			(pts
				(xy 61.086746 -188.4807) (xy 60.832746 -188.4807) (xy 60.832746 -188.7347) (xy 61.086746 -188.7347)
			)
		)
		(polygon
			(pts
				(xy 59.943746 -188.4807) (xy 59.689746 -188.4807) (xy 59.689746 -188.7347) (xy 59.943746 -188.7347)
			)
		)
	)
	(zone
		(net "5V_PRE_1")
		(layer "F.Cu")
		(hatch none 0.5)
		(connect_pads
			(clearance 0.5)
		)
		(min_thickness 0.25)
		(fill yes
			(thermal_gap 0.5)
			(thermal_bridge_width 0.5)
			(island_removal_mode 0)
		)
		(polygon
			(pts
				(xy 216.872058 -379.805184) (xy 216.618058 -380.059184) (xy 216.618058 -382.599184) (xy 216.872058 -382.853184)
				(xy 224.619058 -382.853184) (xy 224.873058 -382.599184) (xy 224.873058 -382.091184) (xy 224.619058 -381.837184)
				(xy 221.190058 -381.837184) (xy 219.158058 -379.805184)
			)
		)
	)
	(zone
		(layer "F.Cu")
		(hatch none 0.5)
		(connect_pads
			(clearance 0.5)
		)
		(min_thickness 0.25)
		(fill
			(thermal_gap 0.5)
			(thermal_bridge_width 0.5)
			(island_removal_mode 0)
		)
		(polygon
			(pts
				(xy 11.556746 -483.7557) (xy 9.778746 -485.5337) (xy 9.778746 -488.3277) (xy 11.175746 -489.7247)
				(xy 11.175746 -491.997746) (xy 11.43 -492.252) (xy 14.351 -492.252) (xy 14.351 -492.264954) (xy 17.652746 -495.5667)
				(xy 21.462746 -495.5667) (xy 22.732746 -494.2967) (xy 22.732746 -486.9307) (xy 21.589746 -485.7877)
				(xy 18.541746 -485.7877) (xy 17.392396 -484.638604) (xy 14.738604 -484.638604) (xy 14.732 -484.632)
				(xy 13.335 -484.632) (xy 13.208 -484.505) (xy 13.208 -483.997) (xy 12.9667 -483.7557)
			)
		)
		(polygon
			(pts
				(xy 10.540746 -487.3625) (xy 10.286746 -487.3625) (xy 10.286746 -487.8959) (xy 10.540746 -487.8959)
			)
		)
		(polygon
			(pts
				(xy 10.540746 -486.7529) (xy 10.286746 -486.7529) (xy 10.286746 -487.0069) (xy 10.540746 -487.0069)
			)
		)
		(polygon
			(pts
				(xy 12.979146 -484.0859) (xy 12.725146 -484.0859) (xy 12.725146 -484.3399) (xy 12.979146 -484.3399)
			)
		)
		(polygon
			(pts
				(xy 12.420346 -484.0859) (xy 12.166346 -484.0859) (xy 12.166346 -484.3399) (xy 12.420346 -484.3399)
			)
		)
	)
	(zone
		(net "12V_PRE_14")
		(layer "F.Cu")
		(hatch none 0.5)
		(connect_pads
			(clearance 0.5)
		)
		(min_thickness 0.25)
		(fill yes
			(thermal_gap 0.5)
			(thermal_bridge_width 0.5)
			(island_removal_mode 0)
		)
		(polygon
			(pts
				(xy 20.954746 -12.1793) (xy 20.319746 -12.8143) (xy 20.319746 -13.3223) (xy 20.700746 -13.7033)
				(xy 25.399746 -13.7033) (xy 25.907746 -13.1953) (xy 25.907746 -12.5603) (xy 25.526746 -12.1793)
			)
		)
	)
	(zone
		(layer "F.Cu")
		(hatch none 0.5)
		(connect_pads
			(clearance 0)
		)
		(min_thickness 0.25)
		(keepout
			(tracks allowed)
			(vias allowed)
			(pads allowed)
			(copperpour allowed)
			(footprints not_allowed)
		)
		(placement
			(enabled no)
			(sheetname "")
		)
		(fill
			(thermal_gap 0.5)
			(thermal_bridge_width 0.5)
			(island_removal_mode 0)
		)
		(polygon
			(pts
				(arc
					(start 69.000116 -269.999968)
					(mid 73.000108 -273.99996)
					(end 69.000116 -277.999952)
				)
				(arc
					(start 69.000116 -277.999952)
					(mid 65.000124 -273.99996)
					(end 69.000116 -269.999968)
				)
			)
		)
	)
	(zone
		(net "5V_PRE_10")
		(layer "F.Cu")
		(hatch none 0.5)
		(connect_pads
			(clearance 0.5)
		)
		(min_thickness 0.25)
		(fill yes
			(thermal_gap 0.5)
			(thermal_bridge_width 0.5)
			(island_removal_mode 0)
		)
		(polygon
			(pts
				(xy 26.161746 -428.526702) (xy 25.780746 -428.907702) (xy 25.780746 -430.304702) (xy 23.875746 -432.209702)
				(xy 20.446746 -432.209702) (xy 20.319746 -432.336702) (xy 20.319746 -432.971702) (xy 20.446746 -433.098702)
				(xy 24.891746 -433.098702) (xy 26.415746 -431.574702) (xy 27.939746 -431.574702) (xy 28.193746 -431.320702)
				(xy 28.193746 -428.780702) (xy 27.939746 -428.526702)
			)
		)
	)
	(zone
		(layer "F.Cu")
		(hatch none 0.5)
		(connect_pads
			(clearance 0)
		)
		(min_thickness 0.25)
		(keepout
			(tracks allowed)
			(vias allowed)
			(pads allowed)
			(copperpour allowed)
			(footprints allowed)
		)
		(placement
			(enabled no)
			(sheetname "")
		)
		(fill
			(thermal_gap 0.5)
			(thermal_bridge_width 0.5)
			(island_removal_mode 0)
		)
		(polygon
			(pts
				(xy 49.402746 -20.8407) (xy 51.053746 -20.8407) (xy 51.307746 -20.5867) (xy 51.307746 -18.8087)
				(xy 51.180746 -18.6817) (xy 49.529746 -18.6817) (xy 49.275746 -18.9357) (xy 49.275746 -20.7137)
			)
		)
	)
	(zone
		(net "12V_PRE_0")
		(layer "F.Cu")
		(hatch none 0.5)
		(connect_pads
			(clearance 0.5)
		)
		(min_thickness 0.25)
		(fill yes
			(thermal_gap 0.5)
			(thermal_bridge_width 0.5)
			(island_removal_mode 0)
		)
		(polygon
			(pts
				(xy 217.677746 -491.5027) (xy 217.550746 -491.6297) (xy 217.550746 -494.2967) (xy 217.677746 -494.4237)
				(xy 218.947746 -494.4237) (xy 219.963746 -493.4077) (xy 224.281746 -493.4077) (xy 224.535746 -493.1537)
				(xy 224.535746 -492.7727) (xy 224.408746 -492.6457) (xy 220.344746 -492.6457) (xy 219.201746 -491.5027)
			)
		)
	)
	(zone
		(net "P3V3")
		(layer "F.Cu")
		(hatch none 0.5)
		(connect_pads
			(clearance 0.5)
		)
		(min_thickness 0.25)
		(fill yes
			(thermal_gap 0.5)
			(thermal_bridge_width 0.5)
			(island_removal_mode 0)
		)
		(polygon
			(pts
				(xy 189.229746 -180.0987) (xy 188.975746 -180.3527) (xy 188.975746 -183.0197) (xy 189.356746 -183.4007)
				(xy 190.753746 -183.4007) (xy 191.134746 -183.7817) (xy 191.134746 -184.5437) (xy 193.547746 -184.5437)
				(xy 193.801746 -184.2897) (xy 193.801746 -183.2737) (xy 194.055746 -183.0197) (xy 196.976746 -183.0197)
				(xy 197.230746 -183.2737) (xy 197.230746 -185.3057) (xy 197.357746 -185.4327) (xy 198.119746 -185.4327)
				(xy 198.246746 -185.3057) (xy 198.246746 -182.6387) (xy 198.373746 -182.5117) (xy 200.024746 -182.5117)
				(xy 200.405746 -182.8927) (xy 200.405746 -183.9087) (xy 200.532746 -184.0357) (xy 201.929746 -184.0357)
				(xy 202.183746 -183.7817) (xy 202.183746 -182.3847) (xy 201.802746 -182.0037) (xy 200.532746 -182.0037)
				(xy 200.024746 -181.4957) (xy 200.024746 -180.3527) (xy 199.770746 -180.0987)
			)
		)
		(polygon
			(pts
				(xy 197.941946 -184.6453) (xy 197.687946 -184.6453) (xy 197.687946 -184.8993) (xy 197.941946 -184.8993)
			)
		)
		(polygon
			(pts
				(xy 191.768984 -183.713628) (xy 191.514984 -183.713628) (xy 191.514984 -183.967628) (xy 191.768984 -183.967628)
			)
		)
		(polygon
			(pts
				(xy 197.941946 -183.5023) (xy 197.687946 -183.5023) (xy 197.687946 -183.7563) (xy 197.941946 -183.7563)
			)
		)
		(polygon
			(pts
				(xy 197.9168 -180.467) (xy 197.6628 -180.467) (xy 197.6628 -180.721) (xy 197.9168 -180.721)
			)
		)
		(polygon
			(pts
				(xy 197.3072 -180.467) (xy 197.0532 -180.467) (xy 197.0532 -180.721) (xy 197.3072 -180.721)
			)
		)
		(polygon
			(pts
				(xy 192.3288 -180.467) (xy 192.0748 -180.467) (xy 192.0748 -180.721) (xy 192.3288 -180.721)
			)
		)
		(polygon
			(pts
				(xy 191.7192 -180.467) (xy 191.4652 -180.467) (xy 191.4652 -180.721) (xy 191.7192 -180.721)
			)
		)
	)
	(zone
		(layer "F.Cu")
		(hatch none 0.5)
		(connect_pads
			(clearance 0)
		)
		(min_thickness 0.25)
		(keepout
			(tracks not_allowed)
			(vias allowed)
			(pads allowed)
			(copperpour not_allowed)
			(footprints allowed)
		)
		(placement
			(enabled no)
			(sheetname "")
		)
		(fill
			(thermal_gap 0.5)
			(thermal_bridge_width 0.5)
			(island_removal_mode 0)
		)
		(polygon
			(pts
				(arc
					(start 7.619238 -169.531792)
					(mid 7.032625 -168.944798)
					(end 6.445758 -169.531538)
				)
				(arc
					(start 6.445758 -169.761662)
					(mid 6.612689 -169.726043)
					(end 6.769354 -169.658284)
				)
				(arc
					(start 6.769354 -169.658284)
					(mid 7.261358 -169.350065)
					(end 6.84911 -169.758868)
				)
				(arc
					(start 6.84911 -169.758868)
					(mid 6.654506 -169.846002)
					(end 6.445758 -169.889424)
				)
				(arc
					(start 6.445758 -170.101768)
					(mid 6.654496 -170.145222)
					(end 6.84911 -170.232324)
				)
				(arc
					(start 6.84911 -170.232324)
					(mid 7.261359 -170.641128)
					(end 6.769354 -170.332908)
				)
				(arc
					(start 6.769354 -170.332908)
					(mid 6.612694 -170.265133)
					(end 6.445758 -170.22953)
				)
				(arc
					(start 6.445758 -170.459654)
					(mid 7.032498 -171.046394)
					(end 7.619238 -170.459654)
				)
			)
		)
	)
	(zone
		(layer "F.Cu")
		(hatch none 0.5)
		(connect_pads
			(clearance 0)
		)
		(min_thickness 0.25)
		(keepout
			(tracks not_allowed)
			(vias allowed)
			(pads allowed)
			(copperpour not_allowed)
			(footprints allowed)
		)
		(placement
			(enabled no)
			(sheetname "")
		)
		(fill
			(thermal_gap 0.5)
			(thermal_bridge_width 0.5)
			(island_removal_mode 0)
		)
		(polygon
			(pts
				(arc
					(start 30.4038 -362.255308)
					(mid 29.817187 -361.668314)
					(end 29.23032 -362.255054)
				)
				(arc
					(start 29.23032 -363.213904)
					(mid 29.81706 -363.800644)
					(end 30.4038 -363.213904)
				)
				(xy 30.4038 -362.93044)
				(arc
					(start 30.297882 -362.93044)
					(mid 30.159792 -362.953964)
					(end 30.037278 -363.02188)
				)
				(arc
					(start 30.037278 -363.02188)
					(mid 29.646194 -363.450955)
					(end 29.930852 -362.944918)
				)
				(xy 29.931614 -362.944156)
				(arc
					(start 29.93263 -362.944156)
					(mid 30.089675 -362.844893)
					(end 30.270958 -362.804202)
				)
				(xy 30.271466 -362.80344) (xy 30.4038 -362.80344) (xy 30.4038 -362.60024) (xy 30.271466 -362.60024)
				(arc
					(start 30.270958 -362.599478)
					(mid 30.118062 -362.569578)
					(end 29.979874 -362.497624)
				)
				(arc
					(start 29.979874 -362.497624)
					(mid 29.605351 -362.053651)
					(end 30.068266 -362.404406)
				)
				(arc
					(start 30.068266 -362.404406)
					(mid 30.178025 -362.45567)
					(end 30.297882 -362.47324)
				)
				(xy 30.4038 -362.47324)
			)
		)
	)
	(zone
		(net "P5V_HDD6")
		(layer "F.Cu")
		(hatch none 0.5)
		(connect_pads
			(clearance 0.5)
		)
		(min_thickness 0.25)
		(fill yes
			(thermal_gap 0.5)
			(thermal_bridge_width 0.5)
			(island_removal_mode 0)
		)
		(polygon
			(pts
				(xy 57.785 -382.3716) (xy 57.403492 -382.753108) (xy 57.403492 -385.854956) (xy 57.022492 -386.235956)
				(xy 50.164492 -386.235956) (xy 47.116492 -383.187956) (xy 36.956492 -383.187956) (xy 36.829492 -383.314956)
				(xy 36.829492 -385.346956) (xy 36.956492 -385.473956) (xy 40.1066 -385.473956) (xy 41.044876 -386.412232)
				(xy 45.2374 -386.412232) (xy 47.728124 -388.902956) (xy 48.386492 -388.902956) (xy 59.943492 -388.902956)
				(xy 66.138044 -388.902956) (xy 66.160904 -388.880096) (xy 66.421 -388.62) (xy 66.421 -385.572) (xy 65.919096 -385.070096)
				(xy 65.157096 -385.070096) (xy 65.150746 -385.0767) (xy 63.3222 -385.0767) (xy 62.9793 -384.7338)
				(xy 62.9793 -384.2131) (xy 63.0174 -384.175) (xy 63.0174 -382.6002) (xy 62.7888 -382.3716)
			)
		)
		(polygon
			(pts
				(xy 55.930546 -387.8707) (xy 55.676546 -387.8707) (xy 55.676546 -388.1247) (xy 55.930546 -388.1247)
			)
		)
		(polygon
			(pts
				(xy 55.066946 -387.8707) (xy 54.812946 -387.8707) (xy 54.812946 -388.1247) (xy 55.066946 -388.1247)
			)
		)
		(polygon
			(pts
				(xy 59.6392 -385.6736) (xy 59.3852 -385.6736) (xy 59.3852 -385.9276) (xy 59.6392 -385.9276)
			)
		)
		(polygon
			(pts
				(xy 60.7822 -382.8796) (xy 60.5282 -382.8796) (xy 60.5282 -383.1336) (xy 60.7822 -383.1336)
			)
		)
		(polygon
			(pts
				(xy 59.6392 -382.8796) (xy 59.3852 -382.8796) (xy 59.3852 -383.1336) (xy 59.6392 -383.1336)
			)
		)
	)
	(zone
		(net "P3V3_FB")
		(layer "F.Cu")
		(hatch none 0.5)
		(connect_pads
			(clearance 0.5)
		)
		(min_thickness 0.25)
		(fill yes
			(thermal_gap 0.5)
			(thermal_bridge_width 0.5)
			(island_removal_mode 0)
		)
		(polygon
			(pts
				(xy 224.2566 -429.5648) (xy 224.1042 -429.7172) (xy 224.1042 -433.0954) (xy 224.282 -433.2732) (xy 227.8126 -433.2732)
				(xy 227.9142 -433.1716) (xy 227.9142 -429.8696) (xy 227.6094 -429.5648)
			)
		)
		(polygon
			(pts
				(xy 226.3902 -432.5874) (xy 226.1362 -432.5874) (xy 226.1362 -432.8414) (xy 226.3902 -432.8414)
			)
		)
		(polygon
			(pts
				(xy 225.8314 -432.5874) (xy 225.5774 -432.5874) (xy 225.5774 -432.8414) (xy 225.8314 -432.8414)
			)
		)
		(polygon
			(pts
				(xy 226.9744 -432.308) (xy 226.7204 -432.308) (xy 226.7204 -432.562) (xy 226.9744 -432.562)
			)
		)
		(polygon
			(pts
				(xy 225.145854 -430.5427) (xy 224.891854 -430.5427) (xy 224.891854 -430.7967) (xy 225.145854 -430.7967)
			)
		)
	)
	(zone
		(net "P5VC")
		(layer "F.Cu")
		(hatch none 0.5)
		(connect_pads
			(clearance 0.5)
		)
		(min_thickness 0.25)
		(fill yes
			(thermal_gap 0.5)
			(thermal_bridge_width 0.5)
			(island_removal_mode 0)
		)
		(polygon
			(pts
				(xy 39.369746 -434.876702) (xy 39.115746 -435.130702) (xy 39.115746 -439.956702) (xy 39.496746 -440.337702)
				(xy 44.322746 -440.337702) (xy 44.703746 -439.956702) (xy 44.703746 -435.257702) (xy 44.322746 -434.876702)
			)
		)
	)
	(zone
		(net "5V_PRE_5")
		(layer "F.Cu")
		(hatch none 0.5)
		(connect_pads
			(clearance 0.5)
		)
		(min_thickness 0.25)
		(fill yes
			(thermal_gap 0.5)
			(thermal_bridge_width 0.5)
			(island_removal_mode 0)
		)
		(polygon
			(pts
				(xy 55.244746 -482.8667) (xy 54.616096 -483.495096) (xy 40.976804 -483.495096) (xy 39.4462 -485.0257)
				(xy 37.210746 -485.0257) (xy 36.956746 -485.2797) (xy 36.956746 -485.6607) (xy 37.083746 -485.7877)
				(xy 39.9288 -485.7877) (xy 40.8813 -484.8352) (xy 53.1749 -484.8352) (xy 54.1274 -485.7877) (xy 56.260746 -485.7877)
				(xy 56.514746 -485.5337) (xy 56.514746 -483.1207) (xy 56.260746 -482.8667)
			)
		)
	)
	(zone
		(net "P12V_HDD13")
		(layer "F.Cu")
		(hatch none 0.5)
		(connect_pads
			(clearance 0.5)
		)
		(min_thickness 0.25)
		(fill yes
			(thermal_gap 0.5)
			(thermal_bridge_width 0.5)
			(island_removal_mode 0)
		)
		(polygon
			(pts
				(xy 48.0568 -108.7374) (xy 47.751746 -109.042454) (xy 47.751746 -114.947954) (xy 47.498 -115.2017)
				(xy 44.576746 -115.2017) (xy 43.433746 -116.3447) (xy 32.765746 -116.3447) (xy 32.753046 -116.332)
				(xy 31.3436 -116.332) (xy 31.2674 -116.4082) (xy 31.2674 -118.0592) (xy 31.8389 -118.6307) (xy 36.194746 -118.6307)
				(xy 39.623746 -122.0597) (xy 44.2722 -122.0597) (xy 44.6405 -122.428) (xy 48.641 -122.428) (xy 51.816 -122.428)
				(xy 53.593746 -120.650254) (xy 53.593746 -110.210346) (xy 52.1208 -108.7374)
			)
		)
		(polygon
			(pts
				(xy 41.147746 -119.0117) (xy 40.893746 -119.0117) (xy 40.893746 -119.2657) (xy 41.147746 -119.2657)
			)
		)
		(polygon
			(pts
				(xy 40.004746 -119.0117) (xy 39.750746 -119.0117) (xy 39.750746 -119.2657) (xy 40.004746 -119.2657)
			)
		)
		(polygon
			(pts
				(xy 34.671 -117.2972) (xy 34.417 -117.2972) (xy 34.417 -117.5512) (xy 34.671 -117.5512)
			)
		)
		(polygon
			(pts
				(xy 33.8074 -117.2972) (xy 33.5534 -117.2972) (xy 33.5534 -117.5512) (xy 33.8074 -117.5512)
			)
		)
	)
	(zone
		(net "12V_PRE_3")
		(layer "F.Cu")
		(hatch none 0.5)
		(connect_pads
			(clearance 0.5)
		)
		(min_thickness 0.25)
		(fill yes
			(thermal_gap 0.5)
			(thermal_bridge_width 0.5)
			(island_removal_mode 0)
		)
		(polygon
			(pts
				(xy 217.296746 -182.6387) (xy 217.169746 -182.7657) (xy 217.169746 -185.4327) (xy 217.296746 -185.5597)
				(xy 220.0148 -185.5597) (xy 221.1578 -184.4167) (xy 221.970346 -184.4167) (xy 224.408746 -184.4167)
				(xy 224.535746 -184.2897) (xy 224.535746 -183.7817) (xy 224.408746 -183.6547) (xy 219.328746 -183.6547)
				(xy 218.312746 -182.6387)
			)
		)
	)
	(zone
		(net "P5V_HDD4")
		(layer "F.Cu")
		(hatch none 0.5)
		(connect_pads
			(clearance 0.5)
		)
		(min_thickness 0.25)
		(fill yes
			(thermal_gap 0.5)
			(thermal_bridge_width 0.5)
			(island_removal_mode 0)
		)
		(polygon
			(pts
				(xy 208.279746 -71.6534) (xy 208.025746 -71.9074) (xy 208.025746 -76.9747) (xy 208.279746 -77.2287)
				(xy 209.930746 -77.2287) (xy 210.692746 -77.9907) (xy 210.693 -77.9907) (xy 210.914996 -78.212696)
				(xy 211.334096 -78.212696) (xy 219.831412 -78.212696) (xy 221.609412 -76.434696) (xy 224.403412 -76.434696)
				(xy 224.657412 -76.180696) (xy 224.657412 -74.656696) (xy 224.403412 -74.402696) (xy 220.339412 -74.402696)
				(xy 219.323412 -75.418696) (xy 216.478612 -75.418696) (xy 216.097612 -75.037696) (xy 216.097612 -72.370696)
				(xy 215.843612 -72.116696) (xy 213.7664 -72.116696) (xy 213.277704 -71.628) (xy 213.252304 -71.6026)
				(xy 208.330546 -71.6026)
			)
		)
		(polygon
			(pts
				(xy 218.744546 -77.2287) (xy 218.490546 -77.2287) (xy 218.490546 -77.4827) (xy 218.744546 -77.4827)
			)
		)
		(polygon
			(pts
				(xy 217.880946 -77.2287) (xy 217.626946 -77.2287) (xy 217.626946 -77.4827) (xy 217.880946 -77.4827)
			)
		)
		(polygon
			(pts
				(xy 213.544912 -74.961496) (xy 213.290912 -74.961496) (xy 213.290912 -75.215496) (xy 213.544912 -75.215496)
			)
		)
		(polygon
			(pts
				(xy 213.544912 -72.167496) (xy 213.290912 -72.167496) (xy 213.290912 -72.421496) (xy 213.544912 -72.421496)
			)
		)
		(polygon
			(pts
				(xy 212.401912 -72.167496) (xy 212.147912 -72.167496) (xy 212.147912 -72.421496) (xy 212.401912 -72.421496)
			)
		)
	)
	(zone
		(net "5V_PRE_12")
		(layer "F.Cu")
		(hatch none 0.5)
		(connect_pads
			(clearance 0.5)
		)
		(min_thickness 0.25)
		(fill yes
			(thermal_gap 0.5)
			(thermal_bridge_width 0.5)
			(island_removal_mode 0)
		)
		(polygon
			(pts
				(xy 39.369746 -228.4857) (xy 39.115746 -228.7397) (xy 39.115746 -231.4067) (xy 39.496746 -231.7877)
				(xy 42.290746 -231.7877) (xy 42.544746 -231.5337) (xy 42.544746 -228.8667) (xy 42.163746 -228.4857)
			)
		)
		(polygon
			(pts
				(xy 41.274746 -228.755702) (xy 41.020746 -228.755702) (xy 41.020746 -229.009702) (xy 41.274746 -229.009702)
			)
		)
	)
	(zone
		(layer "F.Cu")
		(hatch none 0.5)
		(connect_pads
			(clearance 0)
		)
		(min_thickness 0.25)
		(keepout
			(tracks not_allowed)
			(vias allowed)
			(pads allowed)
			(copperpour not_allowed)
			(footprints allowed)
		)
		(placement
			(enabled no)
			(sheetname "")
		)
		(fill
			(thermal_gap 0.5)
			(thermal_bridge_width 0.5)
			(island_removal_mode 0)
		)
		(polygon
			(pts
				(arc
					(start 8.689086 -385.533138)
					(mid 8.127873 -384.971544)
					(end 7.566406 -385.532884)
				)
				(xy 7.566406 -385.767072)
				(arc
					(start 7.619746 -385.767072)
					(mid 7.652988 -385.765769)
					(end 7.68604 -385.761992)
				)
				(arc
					(start 7.68604 -385.761992)
					(mid 7.786475 -385.734362)
					(end 7.87781 -385.684268)
				)
				(arc
					(start 7.87781 -385.684268)
					(mid 8.337854 -385.329941)
					(end 7.96671 -385.77647)
				)
				(arc
					(start 7.96671 -385.77647)
					(mid 7.842992 -385.848362)
					(end 7.705344 -385.887468)
				)
				(arc
					(start 7.705344 -385.887468)
					(mid 7.676082 -385.891147)
					(end 7.64667 -385.89331)
				)
				(xy 7.646162 -385.894072) (xy 7.566406 -385.894072) (xy 7.566406 -386.097272) (xy 7.646162 -386.097272)
				(arc
					(start 7.64667 -386.09778)
					(mid 7.816262 -386.132397)
					(end 7.967472 -386.216652)
				)
				(arc
					(start 7.967472 -386.216652)
					(mid 8.338063 -386.663784)
					(end 7.878572 -386.3086)
				)
				(arc
					(start 7.878572 -386.3086)
					(mid 7.756122 -386.245864)
					(end 7.620254 -386.224272)
				)
				(xy 7.566406 -386.224272)
				(arc
					(start 7.566406 -386.461)
					(mid 8.127746 -387.02234)
					(end 8.689086 -386.461)
				)
			)
		)
	)
	(zone
		(net "P3V3")
		(layer "F.Cu")
		(hatch none 0.5)
		(connect_pads
			(clearance 0.5)
		)
		(min_thickness 0.25)
		(fill yes
			(thermal_gap 0.5)
			(thermal_bridge_width 0.5)
			(island_removal_mode 0)
		)
		(polygon
			(pts
				(xy 99.567746 -13.8557) (xy 99.440746 -13.9827) (xy 99.440746 -14.6177) (xy 98.932746 -15.1257)
				(xy 95.884746 -15.1257) (xy 95.630746 -14.8717) (xy 95.630746 -14.3637) (xy 95.503746 -14.2367)
				(xy 93.852746 -14.2367) (xy 91.820746 -16.2687) (xy 89.534746 -16.2687) (xy 89.280746 -16.5227)
				(xy 89.280746 -18.3007) (xy 89.661746 -18.6817) (xy 101.726746 -18.6817) (xy 102.107746 -18.3007)
				(xy 102.107746 -13.9827) (xy 101.980746 -13.8557)
			)
		)
		(polygon
			(pts
				(xy 94.234 -17.9324) (xy 93.98 -17.9324) (xy 93.98 -18.1864) (xy 94.234 -18.1864)
			)
		)
		(polygon
			(pts
				(xy 93.6244 -17.9324) (xy 93.3704 -17.9324) (xy 93.3704 -18.1864) (xy 93.6244 -18.1864)
			)
		)
		(polygon
			(pts
				(xy 99.3648 -17.907) (xy 99.1108 -17.907) (xy 99.1108 -18.161) (xy 99.3648 -18.161)
			)
		)
		(polygon
			(pts
				(xy 98.7552 -17.907) (xy 98.5012 -17.907) (xy 98.5012 -18.161) (xy 98.7552 -18.161)
			)
		)
		(polygon
			(pts
				(xy 95.173546 -14.6431) (xy 94.919546 -14.6431) (xy 94.919546 -14.8971) (xy 95.173546 -14.8971)
			)
		)
		(polygon
			(pts
				(xy 101.650546 -14.3891) (xy 101.396546 -14.3891) (xy 101.396546 -14.6431) (xy 101.650546 -14.6431)
			)
		)
	)
	(zone
		(layer "F.Cu")
		(hatch none 0.5)
		(connect_pads
			(clearance 0)
		)
		(min_thickness 0.25)
		(keepout
			(tracks not_allowed)
			(vias allowed)
			(pads allowed)
			(copperpour not_allowed)
			(footprints allowed)
		)
		(placement
			(enabled no)
			(sheetname "")
		)
		(fill
			(thermal_gap 0.5)
			(thermal_bridge_width 0.5)
			(island_removal_mode 0)
		)
		(polygon
			(pts
				(arc
					(start 7.266686 -101.498908)
					(mid 6.680073 -100.911914)
					(end 6.093206 -101.498654)
				)
				(xy 6.093206 -101.766624)
				(arc
					(start 6.452108 -101.766624)
					(mid 6.49119 -101.761909)
					(end 6.528054 -101.748082)
				)
				(arc
					(start 6.528054 -101.748082)
					(mid 6.762026 -101.218177)
					(end 6.674358 -101.790754)
				)
				(arc
					(start 6.674358 -101.790754)
					(mid 6.58701 -101.860582)
					(end 6.479794 -101.892354)
				)
				(xy 6.478524 -101.893624) (xy 6.093206 -101.893624) (xy 6.093206 -102.096824) (xy 6.478524 -102.096824)
				(arc
					(start 6.48081 -102.09911)
					(mid 6.527957 -102.114245)
					(end 6.568948 -102.142036)
				)
				(arc
					(start 6.568948 -102.142036)
					(mid 6.590971 -102.157021)
					(end 6.611874 -102.173532)
				)
				(arc
					(start 6.611874 -102.173532)
					(mid 6.814761 -102.716538)
					(end 6.486398 -102.23881)
				)
				(arc
					(start 6.485128 -102.23754)
					(mid 6.469978 -102.227417)
					(end 6.452108 -102.223824)
				)
				(xy 6.093206 -102.223824)
				(arc
					(start 6.093206 -102.457504)
					(mid 6.679946 -103.044244)
					(end 7.266686 -102.457504)
				)
			)
		)
	)
	(zone
		(net "P12V")
		(layer "F.Cu")
		(hatch none 0.5)
		(connect_pads
			(clearance 0.5)
		)
		(min_thickness 0.25)
		(fill yes
			(thermal_gap 0.5)
			(thermal_bridge_width 0.5)
			(island_removal_mode 0)
		)
		(polygon
			(pts
				(xy 73.659492 -88.674956) (xy 73.278492 -89.055956) (xy 73.278492 -91.976956) (xy 73.532492 -92.230956)
				(xy 77.216 -92.230956) (xy 77.343 -92.357956) (xy 77.343 -92.964) (xy 77.47 -93.091) (xy 78.105 -93.091)
				(xy 78.232 -92.964) (xy 78.232 -91.977464) (xy 78.231492 -91.976956) (xy 78.231492 -88.928956) (xy 77.977492 -88.674956)
			)
		)
		(polygon
			(pts
				(xy 77.774546 -91.6051) (xy 77.520546 -91.6051) (xy 77.520546 -91.8591) (xy 77.774546 -91.8591)
			)
		)
		(polygon
			(pts
				(xy 77.774546 -91.0463) (xy 77.520546 -91.0463) (xy 77.520546 -91.3003) (xy 77.774546 -91.3003)
			)
		)
		(polygon
			(pts
				(xy 77.774546 -90.5891) (xy 77.520546 -90.5891) (xy 77.520546 -90.8431) (xy 77.774546 -90.8431)
			)
		)
		(polygon
			(pts
				(xy 77.774546 -90.0303) (xy 77.520546 -90.0303) (xy 77.520546 -90.2843) (xy 77.774546 -90.2843)
			)
		)
	)
	(zone
		(net "P12V_HDD3")
		(layer "F.Cu")
		(hatch none 0.5)
		(connect_pads
			(clearance 0.5)
		)
		(min_thickness 0.25)
		(fill yes
			(thermal_gap 0.5)
			(thermal_bridge_width 0.5)
			(island_removal_mode 0)
		)
		(polygon
			(pts
				(xy 212.851746 -182.6387) (xy 211.835746 -183.6547) (xy 204.596746 -183.6547) (xy 203.707746 -184.5437)
				(xy 203.707746 -187.7187) (xy 203.707746 -187.985654) (xy 203.5937 -188.0997) (xy 201.421746 -188.0997)
				(xy 201.040746 -188.4807) (xy 201.040746 -193.0527) (xy 201.675746 -193.6877) (xy 211.2899 -193.6877)
				(xy 211.7852 -193.1924) (xy 211.7852 -188.7474) (xy 211.9249 -188.6077) (xy 222.757746 -188.6077)
				(xy 224.535746 -186.8297) (xy 224.535746 -185.0517) (xy 224.408746 -184.9247) (xy 222.122746 -184.9247)
				(xy 221.1959 -184.9247) (xy 220.1799 -185.9407) (xy 217.17 -185.9407) (xy 216.408 -185.1787) (xy 216.408 -183.388)
				(xy 215.6587 -182.6387) (xy 214.883746 -182.6387)
			)
		)
		(polygon
			(pts
				(xy 219.734384 -187.599828) (xy 219.480384 -187.599828) (xy 219.480384 -187.853828) (xy 219.734384 -187.853828)
			)
		)
		(polygon
			(pts
				(xy 218.870784 -187.599828) (xy 218.616784 -187.599828) (xy 218.616784 -187.853828) (xy 218.870784 -187.853828)
			)
		)
		(polygon
			(pts
				(xy 213.867746 -185.3057) (xy 213.613746 -185.3057) (xy 213.613746 -185.5597) (xy 213.867746 -185.5597)
			)
		)
		(polygon
			(pts
				(xy 212.724746 -185.3057) (xy 212.470746 -185.3057) (xy 212.470746 -185.5597) (xy 212.724746 -185.5597)
			)
		)
	)
	(zone
		(layer "F.Cu")
		(hatch none 0.5)
		(connect_pads
			(clearance 0)
		)
		(min_thickness 0.25)
		(keepout
			(tracks allowed)
			(vias allowed)
			(pads allowed)
			(copperpour allowed)
			(footprints not_allowed)
		)
		(placement
			(enabled no)
			(sheetname "")
		)
		(fill
			(thermal_gap 0.5)
			(thermal_bridge_width 0.5)
			(island_removal_mode 0)
		)
		(polygon
			(pts
				(xy 43.109896 -41.170098) (xy 43.109896 -8.999982) (xy 24.99995 -8.999982) (xy 24.99995 -51.839876)
				(xy 16.889984 -51.839876) (xy 16.889984 -66.8401) (xy 31.999936 -66.8401) (xy 31.999936 -41.170098)
			)
		)
	)
	(zone
		(layer "F.Cu")
		(hatch none 0.5)
		(connect_pads
			(clearance 0)
		)
		(min_thickness 0.25)
		(keepout
			(tracks not_allowed)
			(vias allowed)
			(pads allowed)
			(copperpour not_allowed)
			(footprints allowed)
		)
		(placement
			(enabled no)
			(sheetname "")
		)
		(fill
			(thermal_gap 0.5)
			(thermal_bridge_width 0.5)
			(island_removal_mode 0)
		)
		(polygon
			(pts
				(arc
					(start 216.807796 -63.429896)
					(mid 216.612058 -63.052917)
					(end 216.213182 -62.906656)
				)
				(arc
					(start 215.349836 -62.92342)
					(mid 214.774524 -63.521463)
					(end 215.372442 -64.0969)
				)
				(arc
					(start 216.083388 -64.083184)
					(mid 215.796811 -63.932726)
					(end 215.531446 -63.747396)
				)
				(arc
					(start 215.531446 -63.747396)
					(mid 215.142565 -63.316284)
					(end 215.616028 -63.6524)
				)
				(arc
					(start 215.616028 -63.6524)
					(mid 215.978208 -63.890168)
					(end 216.376758 -64.06007)
				)
				(arc
					(start 216.376758 -64.06007)
					(mid 216.670158 -63.875176)
					(end 216.807796 -63.556896)
				)
				(arc
					(start 216.5096 -63.556896)
					(mid 215.932635 -63.493396)
					(end 216.5096 -63.429896)
				)
			)
		)
	)
	(zone
		(layer "F.Cu")
		(hatch none 0.5)
		(connect_pads
			(clearance 0)
		)
		(min_thickness 0.25)
		(keepout
			(tracks not_allowed)
			(vias allowed)
			(pads allowed)
			(copperpour not_allowed)
			(footprints allowed)
		)
		(placement
			(enabled no)
			(sheetname "")
		)
		(fill
			(thermal_gap 0.5)
			(thermal_bridge_width 0.5)
			(island_removal_mode 0)
		)
		(polygon
			(pts
				(arc
					(start 31.927546 -475.163896)
					(mid 31.307532 -474.612462)
					(end 30.756098 -475.232476)
				)
				(xy 30.753558 -475.23273) (xy 30.804104 -476.09506)
				(arc
					(start 30.806644 -476.094806)
					(mid 31.426658 -476.64624)
					(end 31.978092 -476.026226)
				)
				(xy 31.980632 -476.025972) (xy 31.969964 -475.844616)
				(arc
					(start 31.825946 -475.844616)
					(mid 31.728186 -475.860509)
					(end 31.640526 -475.906592)
				)
				(arc
					(start 31.640526 -475.906592)
					(mid 31.183362 -476.264579)
					(end 31.551118 -475.815152)
				)
				(arc
					(start 31.551118 -475.815152)
					(mid 31.667381 -475.747416)
					(end 31.798768 -475.718378)
				)
				(xy 31.79953 -475.717616) (xy 31.962598 -475.717616) (xy 31.949136 -475.488) (xy 31.72333 -475.488)
				(arc
					(start 31.722822 -475.487238)
					(mid 31.617464 -475.470103)
					(end 31.518098 -475.431104)
				)
				(arc
					(start 31.518098 -475.431104)
					(mid 31.117772 -475.010768)
					(end 31.602172 -475.33052)
				)
				(arc
					(start 31.602172 -475.33052)
					(mid 31.674412 -475.353253)
					(end 31.749746 -475.361)
				)
				(xy 31.941516 -475.361) (xy 31.930086 -475.163896) (xy 31.929832 -475.163642)
			)
		)
	)
	(zone
		(layer "F.Cu")
		(hatch none 0.5)
		(connect_pads
			(clearance 0)
		)
		(min_thickness 0.25)
		(keepout
			(tracks not_allowed)
			(vias allowed)
			(pads allowed)
			(copperpour not_allowed)
			(footprints allowed)
		)
		(placement
			(enabled no)
			(sheetname "")
		)
		(fill
			(thermal_gap 0.5)
			(thermal_bridge_width 0.5)
			(island_removal_mode 0)
		)
		(polygon
			(pts
				(arc
					(start 217.06205 -372.534434)
					(mid 216.921083 -372.063661)
					(end 216.4715 -371.865144)
				)
				(arc
					(start 215.608154 -371.879368)
					(mid 215.031064 -372.475633)
					(end 215.627204 -373.052848)
				)
				(arc
					(start 216.490804 -373.038624)
					(mid 216.603312 -373.025798)
					(end 216.711276 -372.991634)
				)
				(xy 216.58453 -372.991634)
				(arc
					(start 216.584276 -372.99138)
					(mid 216.160537 -372.914076)
					(end 215.782906 -372.7069)
				)
				(arc
					(start 215.782906 -372.7069)
					(mid 215.404114 -372.266613)
					(end 215.869774 -372.613682)
				)
				(arc
					(start 215.869774 -372.613682)
					(mid 216.219568 -372.800159)
					(end 216.610692 -372.864634)
				)
				(arc
					(start 216.89822 -372.864634)
					(mid 216.974312 -372.769848)
					(end 217.029284 -372.661434)
				)
				(xy 216.807288 -372.661434)
				(arc
					(start 216.80678 -372.660672)
					(mid 216.75307 -372.655478)
					(end 216.7001 -372.645178)
				)
				(arc
					(start 216.7001 -372.645178)
					(mid 216.224501 -372.312749)
					(end 216.763092 -372.528592)
				)
				(arc
					(start 216.763092 -372.528592)
					(mid 216.798279 -372.532957)
					(end 216.833704 -372.534434)
				)
			)
		)
	)
	(zone
		(net "P3V3")
		(layer "F.Cu")
		(hatch none 0.5)
		(connect_pads
			(clearance 0.5)
		)
		(min_thickness 0.25)
		(fill yes
			(thermal_gap 0.5)
			(thermal_bridge_width 0.5)
			(island_removal_mode 0)
		)
		(polygon
			(pts
				(xy 192.023746 -77.9907) (xy 191.388746 -78.6257) (xy 191.134746 -78.6257) (xy 190.372746 -79.3877)
				(xy 190.372746 -81.0387) (xy 191.261746 -81.9277) (xy 191.261746 -82.6897) (xy 193.674746 -82.6897)
				(xy 193.928746 -82.4357) (xy 193.928746 -81.5467) (xy 194.182746 -81.2927) (xy 197.611746 -81.2927)
				(xy 197.738746 -81.4197) (xy 197.738746 -83.0707) (xy 197.865746 -83.1977) (xy 198.246746 -83.1977)
				(xy 198.373746 -83.0707) (xy 198.373746 -82.1817) (xy 198.500746 -82.0547) (xy 198.500746 -81.1657)
				(xy 199.135746 -80.5307) (xy 201.675746 -80.5307) (xy 201.802746 -80.4037) (xy 201.802746 -78.7527)
				(xy 201.040746 -77.9907)
			)
		)
		(polygon
			(pts
				(xy 192.094612 -81.870296) (xy 191.840612 -81.870296) (xy 191.840612 -82.124296) (xy 192.094612 -82.124296)
			)
		)
		(polygon
			(pts
				(xy 194.6148 -78.486) (xy 194.3608 -78.486) (xy 194.3608 -78.74) (xy 194.6148 -78.74)
			)
		)
		(polygon
			(pts
				(xy 194.0052 -78.486) (xy 193.7512 -78.486) (xy 193.7512 -78.74) (xy 194.0052 -78.74)
			)
		)
		(polygon
			(pts
				(xy 198.546212 -78.466696) (xy 198.292212 -78.466696) (xy 198.292212 -78.720696) (xy 198.546212 -78.720696)
			)
		)
		(polygon
			(pts
				(xy 197.936612 -78.466696) (xy 197.682612 -78.466696) (xy 197.682612 -78.720696) (xy 197.936612 -78.720696)
			)
		)
	)
	(zone
		(layer "F.Cu")
		(hatch none 0.5)
		(connect_pads
			(clearance 0)
		)
		(min_thickness 0.25)
		(keepout
			(tracks not_allowed)
			(vias allowed)
			(pads allowed)
			(copperpour not_allowed)
			(footprints allowed)
		)
		(placement
			(enabled no)
			(sheetname "")
		)
		(fill
			(thermal_gap 0.5)
			(thermal_bridge_width 0.5)
			(island_removal_mode 0)
		)
		(polygon
			(pts
				(arc
					(start 7.746746 -379.79096)
					(mid 7.160006 -380.3777)
					(end 7.746746 -380.96444)
				)
				(xy 8.660892 -380.96444)
				(arc
					(start 8.661146 -380.96444)
					(mid 9.247886 -380.3777)
					(end 8.661146 -379.79096)
				)
				(xy 8.432546 -379.79096)
				(arc
					(start 8.432546 -379.8697)
					(mid 8.45274 -380.004156)
					(end 8.51154 -380.126748)
				)
				(arc
					(start 8.51154 -380.126748)
					(mid 8.862655 -380.589115)
					(end 8.418576 -380.21514)
				)
				(arc
					(start 8.418576 -380.21514)
					(mid 8.338835 -380.06418)
					(end 8.306054 -379.896624)
				)
				(xy 8.305546 -379.896116) (xy 8.305546 -379.79096) (xy 8.102346 -379.79096) (xy 8.102346 -379.896116)
				(arc
					(start 8.101838 -379.896624)
					(mid 8.069093 -380.064192)
					(end 7.989316 -380.21514)
				)
				(arc
					(start 7.989316 -380.21514)
					(mid 7.545238 -380.589114)
					(end 7.896352 -380.126748)
				)
				(arc
					(start 7.896352 -380.126748)
					(mid 7.955153 -380.004156)
					(end 7.975346 -379.8697)
				)
				(xy 7.975346 -379.79096)
			)
		)
	)
	(zone
		(net "P3V3")
		(layer "F.Cu")
		(hatch none 0.5)
		(connect_pads
			(clearance 0.5)
		)
		(min_thickness 0.25)
		(fill yes
			(thermal_gap 0.5)
			(thermal_bridge_width 0.5)
			(island_removal_mode 0)
		)
		(polygon
			(pts
				(xy 22.605746 -276.6187) (xy 22.097746 -277.1267) (xy 22.097746 -280.924) (xy 22.098 -280.924) (xy 22.352 -281.178)
				(xy 23.749 -281.178) (xy 24.892 -280.035) (xy 25.514046 -280.035) (xy 25.526746 -280.0477) (xy 26.796746 -280.0477)
				(xy 27.050746 -279.7937) (xy 27.050746 -278.3967) (xy 27.304746 -278.1427) (xy 28.447746 -278.1427)
				(xy 28.574746 -278.0157) (xy 28.574746 -277.7617) (xy 28.447746 -277.6347) (xy 25.399746 -277.6347)
				(xy 25.018746 -277.2537) (xy 25.018746 -276.7457) (xy 24.891746 -276.6187)
			)
		)
		(polygon
			(pts
				(xy 22.86 -280.7208) (xy 22.606 -280.7208) (xy 22.606 -280.9748) (xy 22.86 -280.9748)
			)
		)
		(polygon
			(pts
				(xy 22.86 -280.1112) (xy 22.606 -280.1112) (xy 22.606 -280.3652) (xy 22.86 -280.3652)
			)
		)
		(polygon
			(pts
				(xy 22.86 -278.9428) (xy 22.606 -278.9428) (xy 22.606 -279.1968) (xy 22.86 -279.1968)
			)
		)
		(polygon
			(pts
				(xy 22.86 -278.3332) (xy 22.606 -278.3332) (xy 22.606 -278.5872) (xy 22.86 -278.5872)
			)
		)
		(polygon
			(pts
				(xy 24.612346 -277.0759) (xy 24.358346 -277.0759) (xy 24.358346 -277.3299) (xy 24.612346 -277.3299)
			)
		)
	)
	(zone
		(layer "F.Cu")
		(hatch none 0.5)
		(connect_pads
			(clearance 0.5)
		)
		(min_thickness 0.25)
		(fill
			(thermal_gap 0.5)
			(thermal_bridge_width 0.5)
			(island_removal_mode 0)
		)
		(polygon
			(pts
				(xy 8.896096 -493.14735) (xy 8.000746 -494.0427) (xy 8.000746 -495.6937) (xy 8.254746 -495.9477)
				(xy 14.4653 -495.9477) (xy 14.986 -495.427) (xy 14.986 -494.0427) (xy 14.09065 -493.14735)
			)
		)
	)
	(zone
		(net "P12V")
		(layer "F.Cu")
		(hatch none 0.5)
		(connect_pads
			(clearance 0.5)
		)
		(min_thickness 0.25)
		(fill yes
			(thermal_gap 0.5)
			(thermal_bridge_width 0.5)
			(island_removal_mode 0)
		)
		(polygon
			(pts
				(xy 196.342 -497.132102) (xy 196.088 -497.386102) (xy 196.088 -498.221) (xy 195.707 -498.602) (xy 194.056 -498.602)
				(xy 193.929 -498.729) (xy 193.929 -499.11) (xy 194.31 -499.491) (xy 195.453 -499.491) (xy 195.58 -499.618)
				(xy 195.58 -501.958102) (xy 195.961 -502.339102) (xy 199.215756 -502.339102) (xy 199.596756 -501.958102)
				(xy 199.596756 -497.513102) (xy 199.215756 -497.132102)
			)
		)
		(polygon
			(pts
				(xy 195.7578 -499.11) (xy 195.5038 -499.11) (xy 195.5038 -499.364) (xy 195.7578 -499.364)
			)
		)
		(polygon
			(pts
				(xy 194.7164 -499.0592) (xy 194.4624 -499.0592) (xy 194.4624 -499.3132) (xy 194.7164 -499.3132)
			)
		)
	)
	(zone
		(layer "F.Cu")
		(hatch none 0.5)
		(connect_pads
			(clearance 0)
		)
		(min_thickness 0.25)
		(keepout
			(tracks not_allowed)
			(vias allowed)
			(pads allowed)
			(copperpour not_allowed)
			(footprints allowed)
		)
		(placement
			(enabled no)
			(sheetname "")
		)
		(fill
			(thermal_gap 0.5)
			(thermal_bridge_width 0.5)
			(island_removal_mode 0)
		)
		(polygon
			(pts
				(arc
					(start 7.418832 -115.548156)
					(mid 6.848602 -114.945414)
					(end 6.24586 -115.515644)
				)
				(xy 6.24332 -115.515644) (xy 6.236462 -115.767104)
				(arc
					(start 6.533642 -115.767104)
					(mid 6.584361 -115.761577)
					(end 6.632702 -115.74526)
				)
				(arc
					(start 6.632702 -115.74526)
					(mid 6.972356 -115.275766)
					(end 6.759702 -115.814856)
				)
				(arc
					(start 6.759702 -115.814856)
					(mid 6.666276 -115.86891)
					(end 6.561074 -115.893088)
				)
				(xy 6.560058 -115.894104) (xy 6.232906 -115.894104) (xy 6.227318 -116.097304) (xy 6.376162 -116.097304)
				(arc
					(start 6.376924 -116.098066)
					(mid 6.521731 -116.131476)
					(end 6.647688 -116.210334)
				)
				(xy 6.648958 -116.210334)
				(arc
					(start 6.650228 -116.211604)
					(mid 7.014294 -116.664031)
					(end 6.560058 -116.302282)
				)
				(arc
					(start 6.560058 -116.302282)
					(mid 6.461896 -116.244455)
					(end 6.349746 -116.224304)
				)
				(xy 6.223762 -116.224304) (xy 6.21792 -116.441982)
				(arc
					(start 6.22046 -116.441982)
					(mid 6.79069 -117.044724)
					(end 7.393432 -116.474494)
				)
				(xy 7.395972 -116.474494) (xy 7.421372 -115.54841) (xy 7.421118 -115.548156)
			)
		)
	)
	(zone
		(layer "F.Cu")
		(hatch none 0.5)
		(connect_pads
			(clearance 0)
		)
		(min_thickness 0.25)
		(keepout
			(tracks not_allowed)
			(vias allowed)
			(pads allowed)
			(copperpour not_allowed)
			(footprints allowed)
		)
		(placement
			(enabled no)
			(sheetname "")
		)
		(fill
			(thermal_gap 0.5)
			(thermal_bridge_width 0.5)
			(island_removal_mode 0)
		)
		(polygon
			(pts
				(xy 7.841742 -421.363902) (xy 7.850632 -421.355012)
				(arc
					(start 7.634732 -421.349424)
					(mid 7.614065 -421.435976)
					(end 7.607046 -421.524684)
				)
				(xy 7.607046 -421.525192) (xy 7.607046 -421.532558)
				(arc
					(start 7.6073 -421.544242)
					(mid 7.595145 -421.626906)
					(end 7.555484 -421.700452)
				)
				(xy 7.555484 -421.702738) (xy 7.536942 -421.721026) (xy 7.536942 -421.72128)
				(arc
					(start 7.511034 -421.747188)
					(mid 7.057774 -422.110532)
					(end 7.421118 -421.657272)
				)
				(arc
					(start 7.44728 -421.631364)
					(mid 7.472366 -421.592979)
					(end 7.4803 -421.547798)
				)
				(xy 7.480046 -421.533828) (xy 7.480046 -421.533574)
				(arc
					(start 7.480046 -421.52443)
					(mid 7.485973 -421.434521)
					(end 7.503414 -421.346122)
				)
				(xy 7.374382 -421.34282) (xy 7.278878 -421.34028)
				(arc
					(start 7.278878 -421.34282)
					(mid 6.703314 -421.889428)
					(end 7.249922 -422.464992)
				)
				(xy 7.249922 -422.467532) (xy 8.113014 -422.489884) (xy 8.113268 -422.48963)
				(arc
					(start 8.113268 -422.487344)
					(mid 8.688832 -421.940736)
					(end 8.142224 -421.365172)
				)
				(xy 8.142224 -421.362632)
				(arc
					(start 8.003794 -421.359076)
					(mid 7.984975 -421.38152)
					(end 7.968996 -421.406066)
				)
				(xy 7.968996 -421.416734)
				(arc
					(start 7.95782 -421.42791)
					(mid 7.942444 -421.475862)
					(end 7.937246 -421.525954)
				)
				(xy 7.937246 -421.526462) (xy 7.937246 -421.529002) (xy 7.9375 -421.533574)
				(arc
					(start 7.9375 -421.53459)
					(mid 7.937572 -421.565472)
					(end 7.935976 -421.596312)
				)
				(arc
					(start 7.935976 -421.596312)
					(mid 7.941829 -421.637762)
					(end 7.964424 -421.67302)
				)
				(arc
					(start 7.971028 -421.679624)
					(mid 8.334372 -422.132884)
					(end 7.881112 -421.76954)
				)
				(xy 7.874508 -421.762936) (xy 7.855966 -421.744394)
				(arc
					(start 7.855966 -421.741854)
					(mid 7.818274 -421.66859)
					(end 7.809484 -421.58666)
				)
				(arc
					(start 7.809484 -421.58666)
					(mid 7.81063 -421.562925)
					(end 7.8105 -421.539162)
				)
				(xy 7.810246 -421.532304) (xy 7.810246 -421.53078) (xy 7.810246 -421.5257)
				(arc
					(start 7.810246 -421.525446)
					(mid 7.818227 -421.449255)
					(end 7.841742 -421.376348)
				)
			)
		)
	)
	(zone
		(net "GND")
		(layer "F.Cu")
		(hatch none 0.5)
		(connect_pads
			(clearance 0.5)
		)
		(min_thickness 0.25)
		(fill yes
			(thermal_gap 0.5)
			(thermal_bridge_width 0.5)
			(island_removal_mode 0)
		)
		(polygon
			(pts
				(xy 214.248746 -78.7527) (xy 214.121746 -78.8797) (xy 208.279746 -78.8797) (xy 208.152746 -79.0067)
				(xy 208.152746 -80.2767) (xy 208.279746 -80.4037) (xy 219.836746 -80.4037) (xy 220.344746 -79.8957)
				(xy 220.344746 -79.1337) (xy 219.963746 -78.7527)
			)
		)
		(polygon
			(pts
				(xy 218.744546 -79.5147) (xy 218.490546 -79.5147) (xy 218.490546 -79.7687) (xy 218.744546 -79.7687)
			)
		)
		(polygon
			(pts
				(xy 217.880946 -79.5147) (xy 217.626946 -79.5147) (xy 217.626946 -79.7687) (xy 217.880946 -79.7687)
			)
		)
	)
	(zone
		(layer "F.Cu")
		(hatch none 0.5)
		(connect_pads
			(clearance 0)
		)
		(min_thickness 0.25)
		(keepout
			(tracks allowed)
			(vias allowed)
			(pads allowed)
			(copperpour allowed)
			(footprints not_allowed)
		)
		(placement
			(enabled no)
			(sheetname "")
		)
		(fill
			(thermal_gap 0.5)
			(thermal_bridge_width 0.5)
			(island_removal_mode 0)
		)
		(polygon
			(pts
				(arc
					(start 69.000116 -277.999952)
					(mid 65.000124 -273.99996)
					(end 69.000116 -269.999968)
				)
				(arc
					(start 69.000116 -269.999968)
					(mid 73.000108 -273.99996)
					(end 69.000116 -277.999952)
				)
			)
		)
	)
	(zone
		(net "5V_PRE_9")
		(layer "F.Cu")
		(hatch none 0.5)
		(connect_pads
			(clearance 0.5)
		)
		(min_thickness 0.25)
		(fill yes
			(thermal_gap 0.5)
			(thermal_bridge_width 0.5)
			(island_removal_mode 0)
		)
		(polygon
			(pts
				(xy 36.956492 -72.926956) (xy 36.829492 -73.053956) (xy 36.829492 -73.688956) (xy 36.956492 -73.815956)
				(xy 47.370492 -73.815956) (xy 50.418492 -76.863956) (xy 56.641492 -76.863956) (xy 56.895492 -76.609956)
				(xy 56.895492 -74.196956) (xy 56.641492 -73.942956) (xy 50.799492 -73.942956) (xy 49.783492 -72.926956)
			)
		)
	)
	(zone
		(net "P12V_HDD13")
		(layer "F.Cu")
		(hatch none 0.5)
		(connect_pads
			(clearance 0.5)
		)
		(min_thickness 0.25)
		(fill yes
			(thermal_gap 0.5)
			(thermal_bridge_width 0.5)
			(island_removal_mode 0)
		)
		(polygon
			(pts
				(xy 21.005546 -112.6617) (xy 20.548346 -113.1189) (xy 20.548346 -115.1255) (xy 20.751546 -115.3287)
				(xy 25.907746 -115.3287) (xy 26.034746 -115.2017) (xy 26.034746 -113.0427) (xy 25.653746 -112.6617)
			)
		)
	)
	(zone
		(net "P3V3")
		(layer "F.Cu")
		(hatch none 0.5)
		(connect_pads
			(clearance 0.5)
		)
		(min_thickness 0.25)
		(fill yes
			(thermal_gap 0.5)
			(thermal_bridge_width 0.5)
			(island_removal_mode 0)
		)
		(polygon
			(pts
				(xy 208.8642 -439.7248) (xy 208.5848 -440.0042) (xy 208.5848 -446.2018) (xy 207.1878 -447.5988)
				(xy 191.4652 -447.5988) (xy 190.626746 -448.437254) (xy 190.626746 -452.0057) (xy 191.134746 -452.5137)
				(xy 212.9409 -452.5137) (xy 213.233 -452.2216) (xy 213.233 -450.6722) (xy 211.5058 -448.945) (xy 211.5058 -439.8772)
				(xy 211.3534 -439.7248)
			)
		)
		(polygon
			(pts
				(xy 212.115146 -451.8025) (xy 211.861146 -451.8025) (xy 211.861146 -452.0565) (xy 212.115146 -452.0565)
			)
		)
		(polygon
			(pts
				(xy 211.556346 -451.8025) (xy 211.302346 -451.8025) (xy 211.302346 -452.0565) (xy 211.556346 -452.0565)
			)
		)
		(polygon
			(pts
				(xy 209.829146 -451.8025) (xy 209.575146 -451.8025) (xy 209.575146 -452.0565) (xy 209.829146 -452.0565)
			)
		)
		(polygon
			(pts
				(xy 209.270346 -451.8025) (xy 209.016346 -451.8025) (xy 209.016346 -452.0565) (xy 209.270346 -452.0565)
			)
		)
		(polygon
			(pts
				(xy 207.416146 -451.8025) (xy 207.162146 -451.8025) (xy 207.162146 -452.0565) (xy 207.416146 -452.0565)
			)
		)
		(polygon
			(pts
				(xy 206.857346 -451.8025) (xy 206.603346 -451.8025) (xy 206.603346 -452.0565) (xy 206.857346 -452.0565)
			)
		)
	)
	(zone
		(net "GND")
		(layer "F.Cu")
		(hatch none 0.5)
		(connect_pads
			(clearance 0.5)
		)
		(min_thickness 0.25)
		(fill yes
			(thermal_gap 0.5)
			(thermal_bridge_width 0.5)
			(island_removal_mode 0)
		)
		(polygon
			(pts
				(xy 1.016 -0.762) (xy 0.787146 -0.990854) (xy 0.787146 -49.53) (xy 1.168146 -49.911) (xy 5.207 -49.911)
				(xy 5.334 -50.038) (xy 5.334 -52.832) (xy 6.858 -54.356) (xy 6.858 -56.007) (xy 5.588 -57.277) (xy 5.588 -62.23)
				(xy 5.334 -62.484) (xy 1.295146 -62.484) (xy 0.787146 -62.992) (xy 0.787146 -92.8751) (xy 1.650746 -93.7387)
				(xy 5.778246 -93.7387) (xy 6.604 -94.5642) (xy 7.3914 -94.5642) (xy 7.6454 -94.8182) (xy 7.6454 -95.262446)
				(xy 7.175246 -95.7326) (xy 7.175246 -101.6762) (xy 6.222746 -102.6287) (xy 5.968746 -102.6287) (xy 5.587746 -103.0097)
				(xy 5.587746 -103.9241) (xy 6.451346 -104.7877) (xy 8.635746 -104.7877) (xy 9.651746 -105.8037)
				(xy 9.651746 -117.7417) (xy 10.286746 -118.3767) (xy 16.5227 -118.3767) (xy 16.763746 -118.617746)
				(xy 16.763746 -125.222254) (xy 16.51 -125.476) (xy 10.553446 -125.476) (xy 10.159746 -125.8697)
				(xy 9.651746 -126.3777) (xy 9.651746 -134.3787) (xy 10.667746 -135.3947) (xy 15.620746 -135.3947)
				(xy 15.747746 -135.5217) (xy 15.747746 -137.0457) (xy 15.493746 -137.2997) (xy 9.905746 -137.2997)
				(xy 9.651746 -137.5537) (xy 9.651746 -143.3957) (xy 10.032746 -143.7767) (xy 19.557746 -143.7767)
				(xy 22.605746 -146.8247) (xy 22.605746 -154.9527) (xy 22.097746 -155.4607) (xy 22.097746 -163.905946)
				(xy 22.479 -164.2872) (xy 22.479 -168.4274) (xy 22.6568 -168.6052) (xy 22.6568 -169.6212) (xy 22.733 -169.6974)
				(xy 22.733 -186.9186) (xy 22.5806 -186.9186) (xy 22.5806 -187.1726) (xy 28.7782 -193.3702) (xy 28.7782 -193.6242)
				(xy 28.7782 -193.7512) (xy 28.8036 -193.7766) (xy 28.8036 -193.9798) (xy 28.7782 -193.9798) (xy 28.6258 -193.8274)
				(xy 28.4734 -193.675) (xy 21.7678 -186.9694) (xy 21.7678 -186.3598) (xy 21.7678 -169.309796) (xy 21.202396 -169.309796)
				(xy 20.954746 -169.5577) (xy 19.049746 -169.5577) (xy 19.049746 -167.6527) (xy 20.700746 -166.0017)
				(xy 20.700746 -163.119054) (xy 19.1262 -164.6936) (xy 14.3002 -164.6936) (xy 13.9954 -164.3888)
				(xy 13.9954 -163.8554) (xy 15.7988 -162.052) (xy 15.7988 -156.4894) (xy 16.6878 -155.6004) (xy 20.700746 -155.6004)
				(xy 20.700746 -148.4757) (xy 18.033746 -145.8087) (xy 10.159746 -145.8087) (xy 9.651746 -146.3167)
				(xy 9.651746 -166.7637) (xy 11.43 -168.541954) (xy 11.43 -178.4477) (xy 1.777746 -178.4477) (xy 1.269746 -178.9557)
				(xy 1.269746 -195.8467) (xy 3.047746 -197.6247) (xy 9.778746 -197.6247) (xy 13.842746 -201.6887)
				(xy 27.3431 -201.6887) (xy 28.2448 -202.5904) (xy 28.2448 -206.6544) (xy 28.0416 -206.8576) (xy 26.1874 -206.8576)
				(xy 25.0444 -208.0006) (xy 25.0444 -213.5378) (xy 23.6982 -214.884) (xy 19.939 -214.884) (xy 19.3802 -215.4428)
				(xy 15.2908 -215.4428) (xy 12.579604 -218.153996) (xy 8.426196 -218.153996) (xy 7.873746 -218.7067)
				(xy 1.904746 -218.7067) (xy 1.3843 -218.7067) (xy 0.762 -219.329) (xy 0.762 -277.241) (xy 1.397 -277.876)
				(xy 4.191 -277.876) (xy 4.699 -278.384) (xy 4.699 -284.734) (xy 4.064 -285.369) (xy 1.016 -285.369)
				(xy 0.762 -285.623) (xy 0.762 -299.72) (xy 1.0414 -299.9994) (xy 1.524 -299.9994) (xy 4.953 -299.9994)
				(xy 4.953 -299.974) (xy 5.08 -299.847) (xy 5.08 -292.988746) (xy 6.222746 -291.846) (xy 6.222746 -272.2626)
				(xy 5.6642 -271.704054) (xy 5.6642 -270.1036) (xy 15.875 -259.8928) (xy 17.526 -259.8928) (xy 18.014696 -260.381496)
				(xy 20.700746 -257.6957) (xy 21.081746 -257.6957) (xy 21.3106 -257.466846) (xy 21.3106 -254.9398)
				(xy 23.6728 -254.9398) (xy 23.6728 -255.104646) (xy 23.875746 -254.9017) (xy 23.875746 -248.9327)
				(xy 22.732746 -247.7897) (xy 20.446746 -247.7897) (xy 20.192746 -247.5357) (xy 20.192746 -241.1857)
				(xy 20.446746 -240.9317) (xy 22.859746 -240.9317) (xy 22.986746 -240.8047) (xy 22.986746 -240.2967)
				(xy 22.808946 -240.1189) (xy 22.224746 -240.1189) (xy 21.767546 -239.6617) (xy 18.033746 -239.6617)
				(xy 17.398746 -239.0267) (xy 17.398746 -236.1057) (xy 18.160746 -235.3437) (xy 27.812746 -235.3437)
				(xy 28.828746 -234.3277) (xy 28.828746 -193.0019) (xy 22.859746 -187.0329) (xy 22.859746 -157.1117)
				(xy 24.637746 -155.3337) (xy 24.637746 -145.1737) (xy 24.002746 -144.5387) (xy 20.827746 -144.5387)
				(xy 20.446746 -144.1577) (xy 20.446746 -142.7607) (xy 20.954746 -142.2527) (xy 25.526746 -142.2527)
				(xy 26.225246 -142.9512) (xy 26.225246 -153.6827) (xy 26.669746 -154.1272) (xy 27.178 -154.1272)
				(xy 28.0162 -153.289) (xy 28.0162 -141.1097) (xy 27.6352 -140.7287) (xy 20.573746 -140.7287) (xy 19.811746 -139.9667)
				(xy 19.811746 -138.8237) (xy 20.446746 -138.1887) (xy 28.955746 -138.1887) (xy 29.590746 -137.5537)
				(xy 29.590746 -127.6477) (xy 26.923746 -124.9807) (xy 23.621746 -124.9807) (xy 23.113746 -124.4727)
				(xy 20.446746 -124.4727) (xy 20.192746 -124.2187) (xy 20.192746 -120.4849) (xy 20.548346 -120.1293)
				(xy 22.910546 -120.1293) (xy 22.935946 -120.1039) (xy 22.935946 -119.5197) (xy 22.885146 -119.4689)
				(xy 20.548346 -119.4689) (xy 20.243546 -119.1641) (xy 20.243546 -117.8433) (xy 20.497546 -117.5893)
				(xy 22.910546 -117.5893) (xy 22.935946 -117.5639) (xy 22.935946 -116.9543) (xy 22.910546 -116.9289)
				(xy 20.548346 -116.9289) (xy 20.243546 -116.6241) (xy 20.243546 -112.8395) (xy 20.726146 -112.3569)
				(xy 25.501346 -112.3569) (xy 25.780746 -112.0775) (xy 25.780746 -111.1377) (xy 24.434546 -109.7915)
				(xy 24.434546 -59.2455) (xy 21.462746 -56.2737) (xy 10.540746 -56.2737) (xy 9.270746 -55.0037) (xy 9.270746 -53.2257)
				(xy 9.651746 -52.8447) (xy 10.794746 -52.8447) (xy 11.810746 -51.8287) (xy 11.810746 -50.4317) (xy 12.445746 -49.7967)
				(xy 24.002746 -49.7967) (xy 25.526746 -48.2727) (xy 25.526746 -42.3037) (xy 24.891746 -41.6687)
				(xy 20.192746 -41.6687) (xy 19.938746 -41.4147) (xy 19.938746 -22.7457) (xy 19.557746 -22.3647)
				(xy 18.033746 -22.3647) (xy 17.652746 -21.9837) (xy 17.652746 -17.4117) (xy 18.287746 -16.7767)
				(xy 19.684746 -16.7767) (xy 19.938746 -16.5227) (xy 19.938746 -9.9187) (xy 21.589746 -8.2677) (xy 45.211746 -8.2677)
				(xy 45.846746 -7.6327) (xy 45.846746 -4.7117) (xy 46.608746 -3.9497) (xy 53.339746 -3.9497) (xy 56.133746 -6.7437)
				(xy 59.308746 -6.7437) (xy 60.325 -7.759954) (xy 60.325 -18.415) (xy 60.706 -18.796) (xy 61.073792 -18.796)
				(xy 61.080396 -18.802604) (xy 61.340746 -19.0627) (xy 62.864746 -19.0627) (xy 63.753746 -19.9517)
				(xy 63.753746 -26.8097) (xy 60.451746 -30.1117) (xy 50.418746 -30.1117) (xy 49.783746 -30.7467)
				(xy 30.987746 -30.7467) (xy 30.352746 -31.3817) (xy 30.352746 -37.9603) (xy 28.828746 -39.4843)
				(xy 28.828746 -41.5925) (xy 28.841446 -41.6052) (xy 28.841446 -42.3418) (xy 28.828746 -42.3545)
				(xy 28.828746 -49.7967) (xy 29.463746 -50.4317) (xy 39.115746 -50.4317) (xy 40.131746 -51.4477)
				(xy 40.131746 -58.4327) (xy 39.750746 -58.8137) (xy 31.368746 -58.8137) (xy 30.8864 -59.296046)
				(xy 30.8864 -62.865) (xy 41.148 -62.865) (xy 41.529 -63.246) (xy 41.529 -64.643) (xy 39.37 -64.643)
				(xy 38.862 -64.135) (xy 34.163 -64.135) (xy 33.782 -64.516) (xy 30.9245 -64.516) (xy 30.9245 -104.7369)
				(xy 32.4612 -106.2736) (xy 33.870646 -106.2736) (xy 34.226246 -106.6292) (xy 37.401246 -106.6292)
				(xy 38.099746 -107.3277) (xy 38.099746 -108.8517) (xy 38.226746 -108.9787) (xy 46.736 -108.9787)
				(xy 47.6377 -108.077) (xy 52.324 -108.077) (xy 53.847746 -109.600746) (xy 53.847746 -120.7897) (xy 51.561746 -123.0757)
				(xy 51.561746 -126.5047) (xy 50.672746 -127.3937) (xy 47.777146 -127.3937) (xy 47.370746 -127.8001)
				(xy 47.370746 -129.0447) (xy 47.751746 -129.4257) (xy 53.086 -129.4257) (xy 53.4543 -129.794) (xy 54.101746 -129.794)
				(xy 54.101746 -130.1877) (xy 53.085746 -131.2037) (xy 53.085746 -133.2357) (xy 53.212746 -133.3627)
				(xy 53.085746 -133.4897) (xy 47.370746 -133.4897) (xy 47.116746 -133.7437) (xy 47.116746 -134.7597)
				(xy 46.989746 -134.8867) (xy 46.989746 -133.2357) (xy 46.735746 -132.9817) (xy 45.973746 -132.9817)
				(xy 45.338746 -133.6167) (xy 45.338746 -134.5057) (xy 43.941746 -135.9027) (xy 42.798746 -135.9027)
				(xy 40.258746 -133.3627) (xy 40.258746 -132.6007) (xy 39.877746 -132.2197) (xy 39.623746 -132.2197)
				(xy 38.226746 -133.6167) (xy 36.956746 -133.6167) (xy 36.321746 -132.9817) (xy 36.321746 -131.8387)
				(xy 36.194746 -131.7117) (xy 34.924746 -131.7117) (xy 34.924746 -134.6708) (xy 35.2298 -134.6708)
				(xy 36.2966 -135.7376) (xy 36.2966 -138.9126) (xy 36.2458 -138.9634) (xy 35.915346 -138.9634) (xy 34.924746 -139.954)
				(xy 34.924746 -171.9707) (xy 35.826446 -172.8724) (xy 55.118 -172.8724) (xy 55.118 -172.847) (xy 57.531 -170.434)
				(xy 62.103 -170.434) (xy 65.786 -174.117) (xy 65.786 -175.0187) (xy 78.866746 -175.0187) (xy 78.866746 -177.9397)
				(xy 78.104746 -177.1777) (xy 74.421746 -177.1777) (xy 73.532746 -178.0667) (xy 73.532746 -182.0037)
				(xy 75.691746 -184.1627) (xy 87.756746 -184.1627) (xy 117.982746 -153.9367) (xy 141.858746 -153.9367)
				(xy 143.255746 -155.3337) (xy 143.255746 -159.1437) (xy 141.731746 -160.6677) (xy 122.300746 -160.6677)
				(xy 94.741746 -188.2267) (xy 85.724746 -188.2267) (xy 85.597746 -188.3537) (xy 85.597746 -189.7507)
				(xy 84.073746 -191.2747) (xy 83.565746 -191.2747) (xy 82.295746 -192.5447) (xy 82.295746 -193.6877)
				(xy 81.660746 -194.3227) (xy 81.660746 -195.5927) (xy 81.153 -196.100446) (xy 81.153 -196.596) (xy 80.899 -196.85)
				(xy 80.899 -197.739) (xy 81.915 -198.755) (xy 82.169 -198.755) (xy 82.804 -199.39) (xy 82.804 -199.644)
				(xy 82.169 -200.279) (xy 77.724 -200.279) (xy 77.343 -199.898) (xy 77.343 -197.739) (xy 77.1017 -197.4977)
				(xy 63.7667 -197.4977) (xy 61.468 -195.199) (xy 61.468 -192.5447) (xy 61.214 -192.2907) (xy 46.608746 -192.2907)
				(xy 43.052746 -188.7347) (xy 39.242746 -188.7347) (xy 38.734746 -189.2427) (xy 38.734746 -201.5617)
				(xy 40.258746 -203.0857) (xy 44.957746 -203.0857) (xy 46.227746 -204.3557) (xy 46.227746 -211.5947)
				(xy 44.068746 -213.7537) (xy 39.496746 -213.7537) (xy 38.988746 -214.2617) (xy 38.988746 -216.0397)
				(xy 40.004746 -217.0557) (xy 48.640746 -217.0557) (xy 48.767746 -216.9287) (xy 48.767746 -216.0397)
				(xy 48.767746 -215.773254) (xy 48.768 -215.773) (xy 48.768 -215.7222) (xy 48.5902 -215.5444) (xy 48.5902 -215.4936)
				(xy 48.6918 -215.392) (xy 48.895 -215.392) (xy 49.022 -215.519) (xy 53.352446 -215.519) (xy 53.428646 -215.4428)
				(xy 53.9242 -215.4428) (xy 54.101746 -215.620346) (xy 54.101746 -223.393) (xy 54.228746 -223.52)
				(xy 57.15 -223.52) (xy 57.277 -223.647) (xy 56.896 -224.028) (xy 56.896 -227.965) (xy 56.642 -228.219)
				(xy 52.705 -228.219) (xy 51.943 -227.457) (xy 51.943 -224.155) (xy 51.7017 -223.9137) (xy 39.623746 -223.9137)
				(xy 39.242746 -224.2947) (xy 39.242746 -225.3107) (xy 39.496746 -225.5647) (xy 49.0347 -225.5647)
				(xy 53.975 -230.505) (xy 57.277 -230.505) (xy 57.785 -231.013) (xy 57.785 -233.807) (xy 57.15 -234.442)
				(xy 50.927 -234.442) (xy 49.149 -232.664) (xy 46.989746 -232.664) (xy 46.227746 -233.426) (xy 46.227746 -255.5494)
				(xy 43.9674 -257.809746) (xy 43.9674 -269.494) (xy 42.8244 -270.637) (xy 39.5224 -270.637) (xy 39.5224 -273.9644)
				(xy 38.735 -274.7518) (xy 35.687 -274.7518) (xy 35.56 -274.8788) (xy 35.56 -277.495) (xy 33.3502 -279.7048)
				(xy 33.3502 -284.099) (xy 35.3949 -286.1437) (xy 39.623746 -286.1437) (xy 40.004746 -286.5247) (xy 40.004746 -289.9537)
				(xy 35.814 -294.144446) (xy 35.814 -298.577) (xy 35.2933 -299.0977) (xy 25.653746 -299.0977) (xy 24.510746 -300.2407)
				(xy 20.827746 -300.2407) (xy 18.668746 -302.3997) (xy 18.668746 -307.2257) (xy 21.716746 -310.2737)
				(xy 21.716746 -312.1787) (xy 22.351746 -312.8137) (xy 23.494746 -312.8137) (xy 23.494746 -313.7027)
				(xy 23.875746 -314.0837) (xy 33.654746 -314.0837) (xy 33.908746 -313.8297) (xy 33.908746 -312.8137)
				(xy 33.781746 -312.6867) (xy 32.130746 -312.6867) (xy 31.749746 -312.3057) (xy 31.749746 -311.1627)
				(xy 34.924746 -307.9877) (xy 44.449746 -307.9877) (xy 45.338746 -308.8767) (xy 45.338746 -322.072254)
				(xy 44.704 -322.707) (xy 44.704 -323.596) (xy 44.831 -323.723) (xy 45.211746 -323.723) (xy 45.338746 -323.85)
				(xy 45.338746 -326.009) (xy 46.608746 -327.279) (xy 46.608746 -332.4987) (xy 46.227746 -332.8797)
				(xy 38.735 -332.8797) (xy 38.2905 -332.4352) (xy 31.7754 -332.4352) (xy 31.623 -332.5876) (xy 31.623 -332.6003)
				(xy 31.3436 -332.8797) (xy 28.447746 -332.8797) (xy 27.939746 -333.3877) (xy 27.939746 -336.2452)
				(xy 31.623 -339.928454) (xy 31.623 -340.233) (xy 31.6992 -340.3092) (xy 34.8234 -340.3092) (xy 35.8648 -341.3506)
				(xy 35.8648 -342.9762) (xy 35.687 -343.154) (xy 33.9344 -343.154) (xy 33.445196 -343.643204) (xy 33.445196 -343.71915)
				(xy 34.156396 -344.430604) (xy 34.156396 -345.941396) (xy 34.29 -346.075) (xy 35.013646 -346.075)
				(xy 35.318192 -345.770454) (xy 53.754528 -327.334118) (xy 54.755796 -325.597266) (xy 54.815994 -325.484998)
				(xy 193.8782 -65.278) (xy 211.9122 -56.5404) (xy 212.995256 -56.383682) (xy 221.106746 -52.4637)
				(xy 221.614746 -52.2097) (xy 224.916746 -52.2097) (xy 225.297746 -52.5907) (xy 225.297746 -58.6867)
				(xy 225.043746 -58.9407) (xy 215.010746 -58.9407) (xy 196.722746 -67.7037) (xy 191.314578 -77.7367)
				(xy 193.166746 -77.7367) (xy 193.420746 -77.4827) (xy 201.294746 -77.4827) (xy 201.548746 -77.2287)
				(xy 201.548746 -73.0377) (xy 201.294746 -72.7837) (xy 201.548746 -72.5297) (xy 206.755746 -72.5297)
				(xy 207.009746 -72.7837) (xy 207.645 -72.7837) (xy 207.645 -72.771) (xy 207.899 -72.517) (xy 207.899 -71.247)
				(xy 205.105 -68.453) (xy 205.105 -67.056) (xy 206.629 -65.532) (xy 213.487 -65.532) (xy 214.63 -66.675)
				(xy 217.678 -66.675) (xy 217.678 -69.215) (xy 217.678 -70.6628) (xy 217.811096 -70.795896) (xy 218.268296 -70.795896)
				(xy 218.947746 -70.1167) (xy 224.789746 -70.1167) (xy 224.916746 -70.2437) (xy 224.916746 -71.3867)
				(xy 224.789746 -71.5137) (xy 221.360746 -71.5137) (xy 221.106746 -71.7677) (xy 221.106746 -72.4027)
				(xy 221.360746 -72.6567) (xy 224.789746 -72.6567) (xy 225.043746 -72.9107) (xy 225.043746 -76.4667)
				(xy 224.789746 -76.7207) (xy 221.995746 -76.7207) (xy 221.741746 -76.9747) (xy 221.741746 -77.4827)
				(xy 221.868746 -77.6097) (xy 224.662746 -77.6097) (xy 224.916746 -77.8637) (xy 224.916746 -79.0067)
				(xy 224.662746 -79.2607) (xy 221.868746 -79.2607) (xy 221.741746 -79.3877) (xy 221.741746 -80.0227)
				(xy 221.995746 -80.2767) (xy 224.662746 -80.2767) (xy 224.789746 -80.4037) (xy 224.789746 -84.2137)
				(xy 222.122746 -86.8807) (xy 212.9663 -86.8807) (xy 212.598 -87.249) (xy 212.598 -92.329) (xy 211.6963 -93.2307)
				(xy 200.406 -93.2307) (xy 199.2757 -94.361) (xy 191.643 -94.361) (xy 190.246 -92.964) (xy 190.246 -90.17)
				(xy 190.5 -89.916) (xy 190.5 -89.662) (xy 190.119 -89.281) (xy 185.091832 -89.281) (xy 57.276746 -326.4027)
				(xy 57.276746 -326.5297) (xy 57.403746 -326.6567) (xy 60.24626 -323.61124) (xy 63.44158 -319.7352)
				(xy 97.8535 -276.76094) (xy 137.7823 -227.2157) (xy 181.56174 -172.85462) (xy 194.76466 -156.23286)
				(xy 195.19646 -155.78328) (xy 220.973904 -155.720542) (xy 221.487746 -155.2067) (xy 224.662746 -155.2067)
				(xy 225.170746 -155.7147) (xy 225.170746 -161.5567) (xy 224.789746 -161.9377) (xy 195.325746 -161.9377)
				(xy 66.801746 -320.1797) (xy 66.801746 -320.4337) (xy 67.055746 -320.6877) (xy 129.47904 -294.60952)
				(xy 182.11038 -272.97634) (xy 216.12352 -258.87172) (xy 217.07856 -258.46786) (xy 217.74404 -258.318)
				(xy 218.820746 -258.3307) (xy 224.789746 -258.3307) (xy 225.043746 -258.5847) (xy 225.043746 -264.6807)
				(xy 224.789746 -264.9347) (xy 213.105746 -264.9347) (xy 66.293746 -324.2437) (xy 46.227746 -344.3097)
				(xy 46.227746 -351.434146) (xy 46.228 -351.4344) (xy 45.847 -351.8154) (xy 39.356792 -351.8154)
				(xy 29.209746 -361.9627) (xy 28.5496 -361.9627) (xy 26.5684 -363.9439) (xy 26.5684 -364.020354)
				(xy 26.5684 -371.843046) (xy 26.415746 -371.9957) (xy 13.334746 -385.0767) (xy 13.334746 -392.4427)
				(xy 10.032746 -395.7447) (xy 10.032746 -397.6497) (xy 11.804396 -399.421604) (xy 11.811 -399.415)
				(xy 12.319 -399.415) (xy 14.986 -396.748) (xy 14.986 -396.494) (xy 16.129 -395.351) (xy 16.5862 -394.8938)
				(xy 24.4602 -394.8938) (xy 26.2128 -394.8938) (xy 27.686 -396.367) (xy 27.686 -406.4) (xy 27.9527 -406.6667)
				(xy 34.036 -406.6667) (xy 83.082638 -406.6667) (xy 216.026746 -361.2007) (xy 224.789746 -361.2007)
				(xy 225.043746 -361.4547) (xy 225.043746 -367.5507) (xy 224.789746 -367.8047) (xy 211.82584 -367.8047)
				(xy 84.08924 -409.71978) (xy 83.337654 -410.0322) (xy 79.96682 -410.0322) (xy 79.962248 -410.027628)
				(xy 52.645818 -410.027628) (xy 52.450746 -410.2227) (xy 52.450746 -414.147) (xy 54.102 -414.147)
				(xy 54.864 -414.909) (xy 54.864 -421.513) (xy 54.61 -421.767) (xy 49.415446 -421.767) (xy 44.957746 -426.2247)
				(xy 44.957746 -440.3725) (xy 43.992546 -441.3377) (xy 37.337746 -441.3377) (xy 37.210746 -441.4647)
				(xy 29.336746 -441.4647) (xy 29.209746 -441.5917) (xy 29.209746 -442.0362) (xy 19.367246 -442.0362)
				(xy 18.541746 -442.8617) (xy 18.541746 -452.8947) (xy 20.573746 -454.9267) (xy 26.161746 -454.9267)
				(xy 26.161746 -456.0951) (xy 22.961346 -459.2955) (xy 22.961346 -460.6925) (xy 23.469346 -461.2005)
				(xy 32.130746 -461.2005) (xy 35.102546 -458.2287) (xy 67.690746 -458.2287) (xy 74.167746 -464.7057)
				(xy 221.360746 -464.7057) (xy 221.741746 -464.3247) (xy 224.789746 -464.3247) (xy 225.043746 -464.5787)
				(xy 225.043746 -470.6747) (xy 224.789746 -470.9287) (xy 221.360746 -470.9287) (xy 221.106746 -470.6747)
				(xy 214.375746 -470.6747) (xy 211.327746 -467.6267) (xy 71.373746 -467.6267) (xy 66.674746 -462.9277)
				(xy 36.194746 -462.9277) (xy 35.305746 -463.8167) (xy 35.305746 -469.6587) (xy 35.686746 -470.0397)
				(xy 28.536646 -470.0397) (xy 27.812746 -470.7636) (xy 27.812746 -480.9617) (xy 29.082746 -482.2317)
				(xy 34.289746 -482.2317) (xy 34.797746 -481.7237) (xy 53.466746 -481.7237) (xy 54.489096 -480.701096)
				(xy 54.483 -480.695) (xy 54.483 -476.25) (xy 55.753 -474.98) (xy 62.357 -474.98) (xy 64.008 -476.631)
				(xy 64.008 -484.759) (xy 64.135 -484.886) (xy 65.265046 -484.886) (xy 66.039746 -485.6607) (xy 71.373746 -485.6607)
				(xy 72.453246 -486.7402) (xy 72.453246 -489.2802) (xy 73.278746 -490.1057) (xy 82.168746 -490.1057)
				(xy 82.803746 -490.7407) (xy 82.803746 -492.3917) (xy 83.184746 -492.7727) (xy 87.121746 -492.7727)
				(xy 87.756746 -493.4077) (xy 87.756746 -494.8047) (xy 86.994746 -495.5667) (xy 86.4743 -495.5667)
				(xy 85.979 -496.062) (xy 85.979 -497.332) (xy 86.487 -497.84) (xy 86.487 -501.65) (xy 86.106 -502.031)
				(xy 81.546446 -502.031) (xy 80.263746 -503.3137) (xy 64.388746 -503.3137) (xy 64.001396 -502.926604)
				(xy 62.490604 -502.926604) (xy 61.214 -501.65) (xy 61.214 -498.1067) (xy 60.833 -497.7257) (xy 55.244746 -497.7257)
				(xy 54.736746 -498.2337) (xy 51.053746 -498.2337) (xy 49.891442 -497.071396) (xy 36.543996 -497.071396)
				(xy 36.194746 -497.4209) (xy 36.194746 -502.793254) (xy 35.179 -503.809) (xy 30.9118 -503.809) (xy 30.8864 -503.7836)
				(xy 29.4894 -503.7836) (xy 27.1018 -501.396) (xy 26.797 -501.396) (xy 25.006046 -501.396) (xy 24.765 -501.396)
				(xy 24.2316 -500.8626) (xy 13.9954 -500.8626) (xy 13.462 -501.396) (xy 13.462 -501.408192) (xy 12.826746 -502.0437)
				(xy 10.540746 -502.0437) (xy 10.032746 -501.5357) (xy 9.143746 -501.5357) (xy 9.016746 -501.6627)
				(xy 9.016746 -502.9327) (xy 8.762746 -503.1867) (xy 7.746746 -503.1867) (xy 7.492746 -502.9327)
				(xy 7.492746 -502.2977) (xy 6.984746 -501.7897) (xy 2.032 -501.7897) (xy 1.524 -502.2977) (xy 1.524 -504.571)
				(xy 2.159 -505.206) (xy 261.493 -505.206) (xy 261.721346 -504.977654) (xy 261.721346 -443.128654)
				(xy 261.7216 -443.1284) (xy 261.7216 -431.1396) (xy 257.9878 -427.4058) (xy 257.9878 -425.7802)
				(xy 257.5306 -425.323) (xy 247.396 -425.323) (xy 246.761 -424.688) (xy 246.761 -419.354) (xy 247.015 -419.1)
				(xy 251.206 -419.1) (xy 251.841 -418.465) (xy 257.8608 -418.465) (xy 258.0386 -418.2872) (xy 258.064 -418.2872)
				(xy 258.064 -417.8808) (xy 257.8862 -417.703) (xy 247.396 -417.703) (xy 246.761 -417.068) (xy 246.761 -416.052)
				(xy 246.888 -415.925) (xy 251.206 -415.925) (xy 252.476 -414.655) (xy 257.8354 -414.655) (xy 258.064 -414.4264)
				(xy 258.064 -412.8008) (xy 257.8862 -412.623) (xy 250.825 -412.623) (xy 249.6566 -411.4546) (xy 249.6566 -411.099)
				(xy 250.063 -410.6926) (xy 250.063 -409.4226) (xy 250.8504 -408.6352) (xy 257.556 -408.6352) (xy 258.0894 -408.1018)
				(xy 258.0894 -384.7338) (xy 257.8354 -384.4798) (xy 241.3508 -384.4798) (xy 239.903 -383.032) (xy 239.903 -364.3122)
				(xy 241.2492 -362.966) (xy 258.3434 -362.966) (xy 259.1562 -362.1532) (xy 261.1882 -362.1532) (xy 261.62 -361.7214)
				(xy 261.62 -1.016) (xy 261.366 -0.762)
			)
		)
		(polygon
			(pts
				(xy 219.5322 -497.2304) (xy 212.8774 -497.2304) (xy 212.1154 -497.9924) (xy 219.9386 -497.9924)
				(xy 220.091 -497.84) (xy 220.091 -497.7892)
			)
		)
		(polygon
			(pts
				(xy 28.82138 -193.98234) (xy 28.78836 -193.98234) (xy 28.78836 -194.0306) (xy 28.78582 -194.03314)
				(xy 28.82138 -194.03314)
			)
		)
		(polygon
			(pts
				(xy 25.273 -129.794) (xy 24.003 -129.794) (xy 23.749 -130.048) (xy 23.749 -133.35) (xy 24.511 -134.112)
				(xy 26.67 -134.112) (xy 27.051 -133.731) (xy 28.067 -133.731) (xy 28.702 -133.096) (xy 28.702 -131.445)
				(xy 28.321 -131.064) (xy 25.781 -131.064) (xy 25.654 -130.937) (xy 25.654 -130.175)
			)
		)
		(polygon
			(pts
				(arc
					(start 192.894204 -498.395244)
					(mid 192.889825 -498.435904)
					(end 192.901824 -498.475)
				)
				(xy 190.5 -498.475) (xy 190.119 -498.856) (xy 190.119 -500.634) (xy 191.262 -501.777) (xy 194.818 -501.777)
				(xy 195.707 -502.666) (xy 195.834 -502.666) (xy 195.961 -502.539) (xy 195.58 -502.158) (xy 195.453 -502.158)
				(xy 195.326 -502.031) (xy 195.326 -499.745) (xy 195.199 -499.618) (xy 194.31 -499.618) (xy 193.217292 -498.525292)
				(xy 193.311526 -498.525292) (xy 193.725292 -498.111526)
				(arc
					(start 193.725292 -497.8654)
					(mid 193.844473 -497.577673)
					(end 194.1322 -497.458492)
				)
				(xy 194.305936 -497.458492) (xy 194.542664 -497.222018) (xy 194.193922 -497.570506)
				(arc
					(start 194.198494 -497.596668)
					(mid 194.196179 -497.841607)
					(end 194.104768 -498.068854)
				)
				(arc
					(start 194.104768 -498.068854)
					(mid 194.104668 -498.178426)
					(end 194.204082 -498.224302)
				)
				(arc
					(start 194.204082 -498.224302)
					(mid 194.231576 -498.221456)
					(end 194.2592 -498.220492)
				)
				(arc
					(start 194.6148 -498.220492)
					(mid 194.752471 -498.244505)
					(end 194.87388 -498.31371)
				)
				(arc
					(start 194.87388 -498.31371)
					(mid 194.910178 -498.325134)
					(end 194.944238 -498.308122)
				)
				(arc
					(start 194.958208 -498.292882)
					(mid 194.986956 -498.224084)
					(end 194.961002 -498.154198)
				)
				(arc
					(start 194.961002 -498.154198)
					(mid 194.796573 -497.636705)
					(end 195.075302 -497.17071)
				)
				(xy 195.096892 -497.15547) (xy 195.096892 -497.02085) (xy 193.918078 -497.02085) (xy 192.913254 -498.025674)
				(arc
					(start 192.913254 -498.272562)
					(mid 192.908449 -498.334637)
					(end 192.894204 -498.395244)
				)
			)
		)
		(polygon
			(pts
				(xy 191.798956 -492.026702) (xy 191.798956 -491.772702) (xy 191.544956 -491.772702) (xy 191.544956 -492.026702)
			)
		)
		(polygon
			(pts
				(xy 189.191392 -494.957608)
				(arc
					(start 189.111382 -494.877344)
					(mid 189.000598 -494.855308)
					(end 188.9379 -494.949226)
				)
				(arc
					(start 188.9379 -495.569494)
					(mid 188.99318 -495.659921)
					(end 189.098936 -495.652044)
				)
				(arc
					(start 189.098936 -495.652044)
					(mid 189.162381 -495.611729)
					(end 189.23 -495.578892)
				)
				(xy 189.23 -497.078) (xy 189.103 -497.205) (xy 193.167 -497.205) (xy 193.929 -496.443) (xy 197.231 -496.443)
				(xy 198.501 -495.173) (xy 198.501 -493.268) (xy 199.263 -492.506) (xy 199.263 -491.871) (xy 199.136 -491.744)
				(xy 198.628 -491.744) (xy 198.12 -492.252) (xy 198.12 -492.887) (xy 197.104 -492.887) (xy 196.342 -492.125)
				(xy 195.707 -492.76) (xy 195.707 -495.046) (xy 195.199 -495.554) (xy 193.421 -495.554) (xy 193.294 -495.427)
				(xy 193.294 -493.903) (xy 193.548 -493.649) (xy 193.167 -493.268) (xy 191.262 -493.268) (xy 189.572392 -494.957608)
			)
		)
		(polygon
			(pts
				(arc
					(start 209.192368 -275.63826)
					(mid 209.283958 -275.580636)
					(end 209.271616 -275.47316)
				)
				(arc
					(start 209.271616 -275.47316)
					(mid 209.154255 -275.22111)
					(end 209.16646 -274.943316)
				)
				(xy 209.168492 -274.936458) (xy 209.168492 -274.436332)
				(arc
					(start 209.165698 -274.428204)
					(mid 209.148775 -274.362351)
					(end 209.143092 -274.2946)
				)
				(arc
					(start 209.143092 -273.939)
					(mid 209.148483 -273.873236)
					(end 209.164428 -273.809206)
				)
				(arc
					(start 209.164428 -273.809206)
					(mid 209.150572 -273.717649)
					(end 209.068162 -273.675348)
				)
				(xy 208.864708 -273.675348) (xy 208.864708 -274.301966) (xy 208.018888 -275.147786) (xy 208.509616 -275.63826)
			)
		)
		(polygon
			(pts
				(xy 204.851 -276.098) (xy 206.248 -277.495) (xy 207.391 -277.495) (xy 208.153 -276.733) (xy 208.153 -275.336)
				(xy 207.137 -274.32) (xy 205.232 -274.32) (xy 204.851 -274.701)
			)
		)
		(polygon
			(pts
				(xy 195.7578 -499.11) (xy 195.5038 -499.11) (xy 195.5038 -499.364) (xy 195.7578 -499.364)
			)
		)
		(polygon
			(pts
				(xy 194.7164 -499.0592) (xy 194.4624 -499.0592) (xy 194.4624 -499.3132) (xy 194.7164 -499.3132)
			)
		)
		(polygon
			(pts
				(xy 54.8132 -498.7544) (xy 54.5592 -498.7544) (xy 54.5592 -499.0084) (xy 54.8132 -499.0084)
			)
		)
		(polygon
			(pts
				(xy 53.9496 -498.7544) (xy 53.6956 -498.7544) (xy 53.6956 -499.0084) (xy 53.9496 -499.0084)
			)
		)
		(polygon
			(pts
				(xy 220.1418 -498.7036) (xy 219.8878 -498.7036) (xy 219.8878 -498.9576) (xy 220.1418 -498.9576)
			)
		)
		(polygon
			(pts
				(xy 219.2782 -498.7036) (xy 219.0242 -498.7036) (xy 219.0242 -498.9576) (xy 219.2782 -498.9576)
			)
		)
		(polygon
			(pts
				(xy 220.1418 -496.4176) (xy 219.8878 -496.4176) (xy 219.8878 -496.6716) (xy 220.1418 -496.6716)
			)
		)
		(polygon
			(pts
				(xy 219.2782 -496.4176) (xy 219.0242 -496.4176) (xy 219.0242 -496.6716) (xy 219.2782 -496.6716)
			)
		)
		(polygon
			(pts
				(xy 204.06741 -496.231164)
				(arc
					(start 204.03693 -496.24234)
					(mid 203.983386 -496.259176)
					(end 203.928472 -496.270788)
				)
				(xy 203.886054 -496.277646) (xy 203.886054 -497.345208) (xy 204.342238 -497.801392)
				(arc
					(start 205.392782 -497.801392)
					(mid 205.486614 -497.738756)
					(end 205.464664 -497.628164)
				)
			)
		)
		(polygon
			(pts
				(xy 214.375746 -494.1697) (xy 214.121746 -494.1697) (xy 214.121746 -494.4237) (xy 214.375746 -494.4237)
			)
		)
		(polygon
			(pts
				(xy 213.232746 -494.1697) (xy 212.978746 -494.1697) (xy 212.978746 -494.4237) (xy 213.232746 -494.4237)
			)
		)
		(polygon
			(pts
				(arc
					(start 201.799444 -493.611408)
					(mid 201.774528 -493.61079)
					(end 201.74966 -493.609122)
				)
				(xy 201.726038 -493.606836) (xy 201.63282 -493.700308) (xy 201.437494 -493.700308) (xy 201.437494 -494.259108)
				(xy 200.6346 -494.259108) (xy 200.6346 -494.702592) (xy 200.83018 -494.702592)
				(arc
					(start 200.84542 -494.684558)
					(mid 201.169587 -494.487551)
					(end 201.54646 -494.530888)
				)
				(xy 201.55662 -494.535968) (xy 201.888598 -494.535968)
				(arc
					(start 201.903076 -494.510568)
					(mid 201.923142 -494.479226)
					(end 201.946002 -494.449862)
				)
				(arc
					(start 201.946002 -494.449862)
					(mid 201.970391 -494.383822)
					(end 201.946002 -494.317782)
				)
				(arc
					(start 201.946002 -494.317782)
					(mid 201.873868 -494.194626)
					(end 201.84872 -494.05413)
				)
				(xy 201.84872 -493.698022)
				(arc
					(start 201.849736 -493.666272)
					(mid 201.836542 -493.627911)
					(end 201.799444 -493.611408)
				)
			)
		)
		(polygon
			(pts
				(xy 217.245438 -491.477808)
				(arc
					(start 214.650828 -491.477808)
					(mid 214.604134 -491.509202)
					(end 214.615014 -491.564422)
				)
				(xy 214.681054 -491.630208) (xy 214.681054 -493.789208) (xy 215.518238 -494.626392)
				(arc
					(start 217.203782 -494.626392)
					(mid 217.297614 -494.563756)
					(end 217.275664 -494.453164)
				)
				(xy 217.245438 -494.423192)
			)
		)
		(polygon
			(pts
				(arc
					(start 196.208396 -491.259622)
					(mid 196.219576 -491.204186)
					(end 196.172582 -491.172754)
				)
				(xy 194.436238 -491.172754)
				(arc
					(start 194.25412 -491.354872)
					(mid 194.232035 -491.465539)
					(end 194.325748 -491.528354)
				)
				(xy 195.495672 -491.528354)
				(arc
					(start 195.510912 -491.510066)
					(mid 195.783899 -491.326315)
					(end 196.112892 -491.319058)
				)
				(xy 196.14134 -491.326678)
			)
		)
		(polygon
			(pts
				(xy 198.068946 -491.0963) (xy 197.814946 -491.0963) (xy 197.814946 -491.3503) (xy 198.068946 -491.3503)
			)
		)
		(polygon
			(pts
				(xy 218.316556 -490.121702) (xy 218.062556 -490.121702) (xy 218.062556 -490.375702) (xy 218.316556 -490.375702)
			)
		)
		(polygon
			(pts
				(xy 217.452956 -490.121702) (xy 217.198956 -490.121702) (xy 217.198956 -490.375702) (xy 217.452956 -490.375702)
			)
		)
		(polygon
			(pts
				(arc
					(start 207.8609 -491.324392)
					(mid 207.954732 -491.261756)
					(end 207.932782 -491.151164)
				)
				(xy 206.561436 -489.779818) (xy 206.104236 -490.236764) (xy 201.660252 -490.236764)
				(arc
					(start 201.646282 -490.222794)
					(mid 201.535737 -490.200958)
					(end 201.473054 -490.294676)
				)
				(xy 201.473054 -492.264192) (xy 201.437494 -492.299752) (xy 201.437494 -492.429292)
				(arc
					(start 201.444098 -492.429292)
					(mid 201.498937 -492.486565)
					(end 201.57821 -492.48695)
				)
				(arc
					(start 201.57821 -492.48695)
					(mid 202.148916 -492.555624)
					(end 202.385168 -493.079786)
				)
				(xy 202.382882 -493.103408) (xy 202.570842 -493.291368)
				(arc
					(start 202.611736 -493.291368)
					(mid 202.650911 -493.293284)
					(end 202.689714 -493.298988)
				)
				(xy 202.69454 -493.300004) (xy 202.750166 -493.300004) (xy 202.750166 -493.233964)
				(arc
					(start 202.748134 -493.227106)
					(mid 203.01881 -492.555537)
					(end 203.734924 -492.661956)
				)
				(arc
					(start 203.734924 -492.661956)
					(mid 203.846274 -492.686729)
					(end 203.910438 -492.59236)
				)
				(xy 203.910438 -491.757208) (xy 204.062838 -491.604808) (xy 204.062838 -491.514892) (xy 204.152754 -491.514892)
				(xy 204.343254 -491.324392)
			)
		)
		(polygon
			(pts
				(xy 80.060546 -489.3437) (xy 79.806546 -489.3437) (xy 79.806546 -489.5977) (xy 80.060546 -489.5977)
			)
		)
		(polygon
			(pts
				(xy 79.450946 -489.3437) (xy 79.196946 -489.3437) (xy 79.196946 -489.5977) (xy 79.450946 -489.5977)
			)
		)
		(polygon
			(pts
				(xy 199.6948 -488.569) (xy 199.4408 -488.569) (xy 199.4408 -488.823) (xy 199.6948 -488.823)
			)
		)
		(polygon
			(pts
				(xy 199.0852 -488.569) (xy 198.8312 -488.569) (xy 198.8312 -488.823) (xy 199.0852 -488.823)
			)
		)
		(polygon
			(pts
				(xy 193.3448 -488.569) (xy 193.0908 -488.569) (xy 193.0908 -488.823) (xy 193.3448 -488.823)
			)
		)
		(polygon
			(pts
				(xy 192.7352 -488.569) (xy 192.4812 -488.569) (xy 192.4812 -488.823) (xy 192.7352 -488.823)
			)
		)
		(polygon
			(pts
				(xy 218.316556 -487.835702) (xy 218.062556 -487.835702) (xy 218.062556 -488.089702) (xy 218.316556 -488.089702)
			)
		)
		(polygon
			(pts
				(xy 217.452956 -487.835702) (xy 217.198956 -487.835702) (xy 217.198956 -488.089702) (xy 217.452956 -488.089702)
			)
		)
		(polygon
			(pts
				(xy 199.6948 -487.045) (xy 199.4408 -487.045) (xy 199.4408 -487.299) (xy 199.6948 -487.299)
			)
		)
		(polygon
			(pts
				(xy 199.0852 -487.045) (xy 198.8312 -487.045) (xy 198.8312 -487.299) (xy 199.0852 -487.299)
			)
		)
		(polygon
			(pts
				(xy 193.3448 -487.045) (xy 193.0908 -487.045) (xy 193.0908 -487.299) (xy 193.3448 -487.299)
			)
		)
		(polygon
			(pts
				(xy 192.7352 -487.045) (xy 192.4812 -487.045) (xy 192.4812 -487.299) (xy 192.7352 -487.299)
			)
		)
		(polygon
			(pts
				(xy 213.630256 -485.727502) (xy 213.376256 -485.727502) (xy 213.376256 -485.981502) (xy 213.630256 -485.981502)
			)
		)
		(polygon
			(pts
				(xy 64.8208 -484.124) (xy 64.5668 -484.124) (xy 64.5668 -484.378) (xy 64.8208 -484.378)
			)
		)
		(polygon
			(pts
				(xy 213.630256 -482.933502) (xy 213.376256 -482.933502) (xy 213.376256 -483.187502) (xy 213.630256 -483.187502)
			)
		)
		(polygon
			(pts
				(xy 212.487256 -482.933502) (xy 212.233256 -482.933502) (xy 212.233256 -483.187502) (xy 212.487256 -483.187502)
			)
		)
		(polygon
			(pts
				(arc
					(start 204.333348 -483.013004)
					(mid 204.352634 -482.903151)
					(end 204.259434 -482.841808)
				)
				(xy 203.09332 -482.841808)
				(arc
					(start 202.0697 -483.865174)
					(mid 202.047664 -483.975958)
					(end 202.141582 -484.038656)
				)
				(arc
					(start 204.16393 -484.038656)
					(mid 204.252796 -483.985844)
					(end 204.249528 -483.882446)
				)
				(arc
					(start 204.249528 -483.882446)
					(mid 204.142395 -483.433368)
					(end 204.333348 -483.013004)
				)
			)
		)
		(polygon
			(pts
				(xy 207.384396 -481.889308)
				(arc
					(start 201.366628 -481.889308)
					(mid 201.274622 -481.948356)
					(end 201.289412 -482.056694)
				)
				(arc
					(start 201.289412 -482.056694)
					(mid 201.309849 -482.081865)
					(end 201.329036 -482.108002)
				)
				(xy 201.344276 -482.129592) (xy 205.88732 -482.129592)
				(arc
					(start 207.293464 -483.53599)
					(mid 207.404009 -483.557826)
					(end 207.466692 -483.464108)
				)
				(xy 207.466692 -482.829108) (xy 207.895698 -482.400356)
			)
		)
		(polygon
			(pts
				(xy 218.697556 -480.850702) (xy 218.443556 -480.850702) (xy 218.443556 -481.104702) (xy 218.697556 -481.104702)
			)
		)
		(polygon
			(pts
				(arc
					(start 215.188292 -479.639122)
					(mid 215.124955 -479.546514)
					(end 215.015064 -479.568764)
				)
				(xy 214.395304 -480.188778) (xy 214.395304 -480.681792) (xy 214.49157 -480.681792)
				(arc
					(start 214.506048 -480.656646)
					(mid 214.654922 -480.507677)
					(end 214.858346 -480.453192)
				)
				(arc
					(start 215.213946 -480.453192)
					(mid 215.286213 -480.459657)
					(end 215.356186 -480.478846)
				)
				(arc
					(start 215.356186 -480.478846)
					(mid 215.449408 -480.467052)
					(end 215.493092 -480.38385)
				)
				(xy 215.493092 -480.18573)
				(arc
					(start 215.471502 -480.17049)
					(mid 215.26585 -479.938933)
					(end 215.188292 -479.639122)
				)
			)
		)
		(polygon
			(pts
				(xy 219.582746 -474.6117) (xy 215.518746 -474.6117) (xy 215.137746 -474.9927) (xy 215.137746 -475.6277)
				(xy 216.153746 -476.6437) (xy 219.709746 -476.6437) (xy 219.963746 -476.3897) (xy 224.027746 -476.3897)
				(xy 224.281746 -476.6437) (xy 226.313746 -476.6437) (xy 226.694746 -476.2627) (xy 226.694746 -475.5007)
				(xy 226.313746 -475.1197) (xy 223.773746 -475.1197) (xy 223.646746 -474.9927) (xy 219.963746 -474.9927)
			)
		)
		(polygon
			(pts
				(xy 35.305746 -472.1987) (xy 34.416746 -472.1987) (xy 34.035746 -472.5797) (xy 34.035746 -473.8497)
				(xy 33.654746 -474.2307) (xy 31.114746 -474.2307) (xy 30.733746 -474.6117) (xy 30.733746 -476.3897)
				(xy 31.114746 -476.7707) (xy 41.782746 -476.7707) (xy 42.036746 -476.5167) (xy 42.036746 -472.8337)
				(xy 41.655746 -472.4527) (xy 39.115746 -472.4527) (xy 38.734746 -472.8337) (xy 35.940746 -472.8337)
			)
		)
		(polygon
			(pts
				(xy 200.723246 -462.441036) (xy 200.469246 -462.441036) (xy 200.469246 -462.695036) (xy 200.723246 -462.695036)
			)
		)
		(polygon
			(pts
				(xy 199.859646 -462.441036) (xy 199.605646 -462.441036) (xy 199.605646 -462.695036) (xy 199.859646 -462.695036)
			)
		)
		(polygon
			(pts
				(xy 199.453246 -462.441036) (xy 199.199246 -462.441036) (xy 199.199246 -462.695036) (xy 199.453246 -462.695036)
			)
		)
		(polygon
			(pts
				(xy 198.589646 -462.441036) (xy 198.335646 -462.441036) (xy 198.335646 -462.695036) (xy 198.589646 -462.695036)
			)
		)
		(polygon
			(pts
				(xy 197.954646 -461.831436) (xy 197.700646 -461.831436) (xy 197.700646 -462.085436) (xy 197.954646 -462.085436)
			)
		)
		(polygon
			(pts
				(xy 176.593246 -461.679036) (xy 176.339246 -461.679036) (xy 176.339246 -461.933036) (xy 176.593246 -461.933036)
			)
		)
		(polygon
			(pts
				(xy 175.983646 -461.679036) (xy 175.729646 -461.679036) (xy 175.729646 -461.933036) (xy 175.983646 -461.933036)
			)
		)
		(polygon
			(pts
				(xy 178.574446 -460.104236) (xy 178.320446 -460.104236) (xy 178.320446 -460.358236) (xy 178.574446 -460.358236)
			)
		)
		(polygon
			(pts
				(xy 163.994846 -459.215236) (xy 163.740846 -459.215236) (xy 163.740846 -459.469236) (xy 163.994846 -459.469236)
			)
		)
		(polygon
			(pts
				(arc
					(start 181.157372 -458.796644)
					(mid 181.17978 -458.685889)
					(end 181.085998 -458.622908)
				)
				(xy 178.0794 -458.622908)
				(arc
					(start 177.980594 -458.721714)
					(mid 177.969615 -458.77691)
					(end 178.016408 -458.808328)
				)
				(arc
					(start 178.168046 -458.808328)
					(mid 178.235791 -458.81405)
					(end 178.30165 -458.830934)
				)
				(xy 178.309778 -458.833728) (xy 179.631594 -458.833728) (xy 179.684426 -458.88656) (xy 179.700936 -458.8891)
				(xy 179.736496 -458.895958) (xy 179.742338 -458.897228) (xy 180.200554 -458.897228)
				(arc
					(start 180.206396 -458.895958)
					(mid 180.253683 -458.887427)
					(end 180.301646 -458.884528)
				)
				(arc
					(start 180.657246 -458.884528)
					(mid 180.705209 -458.887425)
					(end 180.752496 -458.895958)
				)
				(xy 180.758338 -458.897228) (xy 181.073298 -458.897228)
				(arc
					(start 181.088538 -458.8764)
					(mid 181.121368 -458.835152)
					(end 181.157372 -458.796644)
				)
			)
		)
		(polygon
			(pts
				(xy 199.020938 -458.375004) (xy 198.359522 -458.375004) (xy 198.209154 -458.525118) (xy 198.209154 -459.962504)
				(arc
					(start 198.116698 -459.962504)
					(mid 198.069765 -459.993864)
					(end 198.080884 -460.049118)
				)
				(xy 198.135494 -460.103728) (xy 198.268336 -460.103728)
				(arc
					(start 198.283068 -460.089758)
					(mid 198.346256 -460.040262)
					(end 198.417942 -460.00416)
				)
				(arc
					(start 198.417942 -460.00416)
					(mid 198.644011 -459.889362)
					(end 198.894446 -459.849728)
				)
				(arc
					(start 199.05599 -459.849728)
					(mid 199.137844 -459.808316)
					(end 199.152764 -459.717902)
				)
				(arc
					(start 199.152764 -459.717902)
					(mid 199.128507 -459.430783)
					(end 199.22871 -459.160626)
				)
				(xy 199.236838 -459.147926) (xy 199.236838 -458.915262)
				(arc
					(start 199.212962 -458.900276)
					(mid 199.072147 -458.752456)
					(end 199.020938 -458.554836)
				)
			)
		)
		(polygon
			(pts
				(arc
					(start 203.42225 -457.85913)
					(mid 203.359531 -457.765264)
					(end 203.248768 -457.787248)
				)
				(xy 202.646026 -458.390244) (xy 201.354182 -458.390244) (xy 201.354182 -458.42301) (xy 201.044302 -458.733144)
				(xy 201.013822 -458.733144)
				(arc
					(start 200.999344 -458.75829)
					(mid 200.85047 -458.907259)
					(end 200.647046 -458.961744)
				)
				(xy 200.291446 -458.961744) (xy 200.283318 -458.96149)
				(arc
					(start 200.246488 -459.048612)
					(mid 200.424603 -459.359647)
					(end 200.414128 -459.717902)
				)
				(arc
					(start 200.414128 -459.717902)
					(mid 200.429222 -459.808188)
					(end 200.510902 -459.849728)
				)
				(xy 203.42225 -459.849728)
			)
		)
		(polygon
			(pts
				(xy 176.593246 -456.345036) (xy 176.339246 -456.345036) (xy 176.339246 -456.599036) (xy 176.593246 -456.599036)
			)
		)
		(polygon
			(pts
				(xy 179.311046 -456.268836) (xy 179.057046 -456.268836) (xy 179.057046 -456.522836) (xy 179.311046 -456.522836)
			)
		)
		(polygon
			(pts
				(xy 189.394846 -455.633836) (xy 189.140846 -455.633836) (xy 189.140846 -455.887836) (xy 189.394846 -455.887836)
			)
		)
		(polygon
			(pts
				(xy 162.420046 -454.998836) (xy 162.166046 -454.998836) (xy 162.166046 -455.252836) (xy 162.420046 -455.252836)
			)
		)
		(polygon
			(pts
				(xy 166.941246 -454.948036) (xy 166.687246 -454.948036) (xy 166.687246 -455.202036) (xy 166.941246 -455.202036)
			)
		)
		(polygon
			(pts
				(xy 166.331646 -454.948036) (xy 166.077646 -454.948036) (xy 166.077646 -455.202036) (xy 166.331646 -455.202036)
			)
		)
		(polygon
			(pts
				(xy 213.740746 -454.3425) (xy 213.486746 -454.3425) (xy 213.486746 -454.5965) (xy 213.740746 -454.5965)
			)
		)
		(polygon
			(pts
				(xy 206.552546 -454.3171) (xy 206.298546 -454.3171) (xy 206.298546 -454.5711) (xy 206.552546 -454.5711)
			)
		)
		(polygon
			(pts
				(arc
					(start 43.700192 -454.346564)
					(mid 43.722228 -454.23578)
					(end 43.62831 -454.173082)
				)
				(xy 41.662858 -454.173082) (xy 41.6052 -454.23074) (xy 40.72001 -454.23074)
				(arc
					(start 40.705532 -454.25614)
					(mid 40.556595 -454.404931)
					(end 40.353234 -454.45934)
				)
				(xy 39.997634 -454.45934)
				(arc
					(start 39.967408 -454.458324)
					(mid 39.890844 -454.48526)
					(end 39.858442 -454.55967)
				)
				(xy 39.858442 -454.748392) (xy 43.29811 -454.748392)
			)
		)
		(polygon
			(pts
				(xy 206.552546 -453.7583) (xy 206.298546 -453.7583) (xy 206.298546 -454.0123) (xy 206.552546 -454.0123)
			)
		)
		(polygon
			(pts
				(xy 213.740746 -453.7329) (xy 213.486746 -453.7329) (xy 213.486746 -453.9869) (xy 213.740746 -453.9869)
			)
		)
		(polygon
			(pts
				(xy 212.115146 -451.8025) (xy 211.861146 -451.8025) (xy 211.861146 -452.0565) (xy 212.115146 -452.0565)
			)
		)
		(polygon
			(pts
				(xy 211.556346 -451.8025) (xy 211.302346 -451.8025) (xy 211.302346 -452.0565) (xy 211.556346 -452.0565)
			)
		)
		(polygon
			(pts
				(xy 209.829146 -451.8025) (xy 209.575146 -451.8025) (xy 209.575146 -452.0565) (xy 209.829146 -452.0565)
			)
		)
		(polygon
			(pts
				(xy 209.270346 -451.8025) (xy 209.016346 -451.8025) (xy 209.016346 -452.0565) (xy 209.270346 -452.0565)
			)
		)
		(polygon
			(pts
				(xy 207.416146 -451.8025) (xy 207.162146 -451.8025) (xy 207.162146 -452.0565) (xy 207.416146 -452.0565)
			)
		)
		(polygon
			(pts
				(xy 206.857346 -451.8025) (xy 206.603346 -451.8025) (xy 206.603346 -452.0565) (xy 206.857346 -452.0565)
			)
		)
		(polygon
			(pts
				(xy 49.128172 -450.202554)
				(arc
					(start 48.475392 -450.202554)
					(mid 48.38858 -450.251369)
					(end 48.385222 -450.35089)
				)
				(xy 48.372776 -450.329808) (xy 47.853854 -450.329808)
				(arc
					(start 47.853854 -450.5706)
					(mid 47.734673 -450.858327)
					(end 47.446946 -450.977508)
				)
				(arc
					(start 47.091346 -450.977508)
					(mid 46.956772 -450.954521)
					(end 46.837346 -450.888354)
				)
				(arc
					(start 46.837346 -450.888354)
					(mid 46.717936 -450.954566)
					(end 46.583346 -450.977508)
				)
				(xy 46.31182 -450.977508) (xy 46.28261 -451.006464) (xy 46.28261 -451.229476)
				(arc
					(start 46.30674 -451.244462)
					(mid 46.447386 -451.39234)
					(end 46.49851 -451.589902)
				)
				(xy 46.49851 -451.945502)
				(arc
					(start 46.498256 -451.962774)
					(mid 46.526364 -452.037276)
					(end 46.599602 -452.068692)
				)
				(xy 48.260254 -452.068692) (xy 48.260254 -452.398892) (xy 48.411638 -452.398892) (xy 48.411638 -451.084696)
				(xy 48.932338 -451.084696) (xy 48.932338 -450.904864) (xy 49.11217 -451.084696) (xy 49.427638 -451.084696)
				(xy 49.427638 -450.502274)
			)
		)
		(polygon
			(pts
				(arc
					(start 49.855882 -449.914264)
					(mid 49.746041 -449.892139)
					(end 49.682654 -449.984622)
				)
				(arc
					(start 49.682654 -449.984622)
					(mid 49.672818 -450.087362)
					(end 49.647094 -450.187314)
				)
				(xy 49.644554 -450.195442) (xy 49.644554 -451.084696) (xy 50.165254 -451.084696) (xy 50.165254 -452.398892)
				(xy 50.59426 -452.398892) (xy 50.597054 -452.351394) (xy 50.598324 -452.333614) (xy 50.60061 -452.309992)
				(xy 50.570638 -452.280274) (xy 50.570638 -450.629274)
			)
		)
		(polygon
			(pts
				(xy 232.536746 -449.3387) (xy 225.170746 -449.3387) (xy 224.281746 -450.2277) (xy 224.281746 -452.3867)
				(xy 224.789746 -452.8947) (xy 224.789746 -453.9107) (xy 225.170746 -454.2917) (xy 228.980746 -454.2917)
				(xy 229.234746 -454.5457) (xy 230.250746 -454.5457) (xy 231.393746 -453.4027) (xy 231.901746 -453.4027)
				(xy 232.282746 -453.7837) (xy 233.298746 -452.7677) (xy 233.298746 -450.1007)
			)
		)
		(polygon
			(pts
				(xy 35.357816 -441.915042) (xy 35.103816 -441.915042) (xy 35.103816 -442.169042) (xy 35.357816 -442.169042)
			)
		)
		(polygon
			(pts
				(xy 34.748216 -441.915042) (xy 34.494216 -441.915042) (xy 34.494216 -442.169042) (xy 34.748216 -442.169042)
			)
		)
		(polygon
			(pts
				(xy 31.927546 -441.734702) (xy 31.673546 -441.734702) (xy 31.673546 -441.988702) (xy 31.927546 -441.988702)
			)
		)
		(polygon
			(pts
				(xy 31.317946 -441.734702) (xy 31.063946 -441.734702) (xy 31.063946 -441.988702) (xy 31.317946 -441.988702)
			)
		)
		(polygon
			(pts
				(xy 221.462854 -435.3941) (xy 221.208854 -435.3941) (xy 221.208854 -435.6481) (xy 221.462854 -435.6481)
			)
		)
		(polygon
			(pts
				(xy 220.853254 -435.3941) (xy 220.599254 -435.3941) (xy 220.599254 -435.6481) (xy 220.853254 -435.6481)
			)
		)
		(polygon
			(pts
				(xy 225.425 -434.594) (xy 223.139 -434.594) (xy 222.885 -434.848) (xy 222.885 -436.372) (xy 222.758 -436.499)
				(xy 219.075 -436.499) (xy 218.821 -436.753) (xy 218.821 -437.007) (xy 219.964 -438.15) (xy 219.964 -441.452)
				(xy 219.71 -441.706) (xy 219.837 -441.833) (xy 220.091 -441.833) (xy 222.25 -443.992) (xy 224.282 -443.992)
				(xy 224.282 -444.373) (xy 227.33 -444.373) (xy 229.489 -442.214) (xy 229.489 -436.499) (xy 229.108 -436.118)
				(xy 227.711 -436.118) (xy 227.6221 -436.2069) (xy 227.6094 -436.1942) (xy 227.0252 -436.1942)
			)
		)
		(polygon
			(pts
				(xy 220.599 -432.7652) (xy 213.7664 -432.7652) (xy 212.471 -434.0606) (xy 212.471 -436.7276) (xy 212.4456 -436.753)
				(xy 212.4456 -436.9054) (xy 213.7918 -436.9054) (xy 214.1982 -436.499) (xy 214.1982 -433.6796) (xy 214.6808 -433.197)
				(xy 219.1004 -433.197) (xy 220.472 -434.5686) (xy 220.7514 -434.5686) (xy 221.1324 -434.1876) (xy 221.1324 -433.2986)
			)
		)
		(polygon
			(pts
				(xy 226.3902 -432.5874) (xy 226.1362 -432.5874) (xy 226.1362 -432.8414) (xy 226.3902 -432.8414)
			)
		)
		(polygon
			(pts
				(xy 225.8314 -432.5874) (xy 225.5774 -432.5874) (xy 225.5774 -432.8414) (xy 225.8314 -432.8414)
			)
		)
		(polygon
			(pts
				(xy 226.9744 -432.308) (xy 226.7204 -432.308) (xy 226.7204 -432.562) (xy 226.9744 -432.562)
			)
		)
		(polygon
			(pts
				(xy 45.7708 -432.308) (xy 45.5168 -432.308) (xy 45.5168 -432.562) (xy 45.7708 -432.562)
			)
		)
		(polygon
			(pts
				(xy 225.145854 -430.5427) (xy 224.891854 -430.5427) (xy 224.891854 -430.7967) (xy 225.145854 -430.7967)
			)
		)
		(polygon
			(pts
				(xy 222.859854 -429.6791) (xy 222.605854 -429.6791) (xy 222.605854 -429.9331) (xy 222.859854 -429.9331)
			)
		)
		(polygon
			(pts
				(xy 244.9068 -423.3418) (xy 244.6528 -423.3418) (xy 244.6528 -423.5958) (xy 244.9068 -423.5958)
			)
		)
		(polygon
			(pts
				(xy 244.9068 -422.4782) (xy 244.6528 -422.4782) (xy 244.6528 -422.7322) (xy 244.9068 -422.7322)
			)
		)
		(polygon
			(pts
				(xy 244.9068 -422.0718) (xy 244.6528 -422.0718) (xy 244.6528 -422.3258) (xy 244.9068 -422.3258)
			)
		)
		(polygon
			(pts
				(xy 244.9068 -421.2082) (xy 244.6528 -421.2082) (xy 244.6528 -421.4622) (xy 244.9068 -421.4622)
			)
		)
		(polygon
			(pts
				(xy 82.423 -402.59) (xy 77.216 -402.59) (xy 77.089 -402.717) (xy 77.851 -403.479) (xy 77.851 -404.241)
				(xy 77.216 -404.876) (xy 77.216 -406.146) (xy 77.47 -406.4) (xy 82.804 -406.4) (xy 83.058 -406.146)
				(xy 83.058 -405.257) (xy 82.804 -405.003) (xy 82.804 -403.225) (xy 82.931 -403.098)
			)
		)
		(polygon
			(pts
				(xy 78.7146 -401.6248) (xy 78.4606 -401.6248) (xy 78.4606 -401.8788) (xy 78.7146 -401.8788)
			)
		)
		(polygon
			(pts
				(xy 78.2828 -401.574) (xy 78.0288 -401.574) (xy 78.0288 -401.828) (xy 78.2828 -401.828)
			)
		)
		(polygon
			(pts
				(xy 83.4898 -400.05) (xy 83.2358 -400.05) (xy 83.2358 -400.304) (xy 83.4898 -400.304)
			)
		)
		(polygon
			(pts
				(xy 82.8802 -400.05) (xy 82.6262 -400.05) (xy 82.6262 -400.304) (xy 82.8802 -400.304)
			)
		)
		(polygon
			(pts
				(xy 79.739998 -400.022568)
				(arc
					(start 79.399638 -400.022568)
					(mid 79.311045 -400.074885)
					(end 79.313532 -400.177762)
				)
				(arc
					(start 79.313532 -400.177762)
					(mid 79.307127 -400.165814)
					(end 79.302356 -400.153124)
				)
				(arc
					(start 79.302356 -400.153124)
					(mid 79.244409 -400.088687)
					(end 79.15783 -400.092418)
				)
				(arc
					(start 79.15783 -400.092418)
					(mid 79.065946 -400.127426)
					(end 78.968346 -400.139408)
				)
				(xy 78.612746 -400.139408)
				(arc
					(start 78.590394 -400.138646)
					(mid 78.552719 -400.152409)
					(end 78.5368 -400.189192)
				)
				(xy 78.5368 -400.685)
				(arc
					(start 79.365094 -401.513294)
					(mid 79.42029 -401.524273)
					(end 79.451708 -401.47748)
				)
				(xy 79.451708 -401.536154) (xy 79.524098 -401.536154)
				(arc
					(start 79.539084 -401.52066)
					(mid 79.615746 -401.458282)
					(end 79.7052 -401.416266)
				)
				(xy 79.739998 -401.404582)
			)
		)
		(polygon
			(pts
				(xy 77.774546 -399.7071) (xy 77.520546 -399.7071) (xy 77.520546 -399.9611) (xy 77.774546 -399.9611)
			)
		)
		(polygon
			(pts
				(xy 77.774546 -399.1483) (xy 77.520546 -399.1483) (xy 77.520546 -399.4023) (xy 77.774546 -399.4023)
			)
		)
		(polygon
			(pts
				(xy 196.1388 -396.875) (xy 195.8848 -396.875) (xy 195.8848 -397.129) (xy 196.1388 -397.129)
			)
		)
		(polygon
			(pts
				(xy 195.0974 -396.8242) (xy 194.8434 -396.8242) (xy 194.8434 -397.0782) (xy 195.0974 -397.0782)
			)
		)
		(polygon
			(pts
				(xy 80.518 -395.8336) (xy 77.724 -395.8336) (xy 77.724 -397.129) (xy 80.518 -397.129)
			)
		)
		(polygon
			(pts
				(xy 192.786 -395.224) (xy 191.516 -395.224) (xy 190.246 -396.494) (xy 190.246 -398.272) (xy 191.135 -399.161)
				(xy 195.58 -399.161) (xy 195.961 -399.542) (xy 195.961 -398.018) (xy 195.326 -397.383) (xy 194.564 -397.383)
				(xy 193.167 -395.986) (xy 193.167 -395.605)
			)
		)
		(polygon
			(pts
				(xy 75.8698 -394.7414) (xy 75.6158 -394.7414) (xy 75.6158 -394.9954) (xy 75.8698 -394.9954)
			)
		)
		(polygon
			(pts
				(xy 75.2602 -394.7414) (xy 75.0062 -394.7414) (xy 75.0062 -394.9954) (xy 75.2602 -394.9954)
			)
		)
		(polygon
			(pts
				(xy 220.4466 -394.6144) (xy 220.1926 -394.6144) (xy 220.1926 -394.8684) (xy 220.4466 -394.8684)
			)
		)
		(polygon
			(pts
				(xy 219.583 -394.6144) (xy 219.329 -394.6144) (xy 219.329 -394.8684) (xy 219.583 -394.8684)
			)
		)
		(polygon
			(pts
				(xy 78.307946 -394.4493) (xy 78.053946 -394.4493) (xy 78.053946 -394.7033) (xy 78.307946 -394.7033)
			)
		)
		(polygon
			(pts
				(arc
					(start 195.26758 -394.222478)
					(mid 195.295023 -394.110388)
					(end 195.200016 -394.044932)
				)
				(xy 195.053712 -394.044932) (xy 195.053712 -394.247116) (xy 194.574922 -394.725906)
				(arc
					(start 194.579494 -394.752068)
					(mid 194.587714 -394.921855)
					(end 194.552316 -395.08811)
				)
				(arc
					(start 194.552316 -395.08811)
					(mid 194.565185 -395.180546)
					(end 194.648074 -395.223492)
				)
				(arc
					(start 194.8688 -395.223492)
					(mid 195.006471 -395.247505)
					(end 195.12788 -395.31671)
				)
				(arc
					(start 195.12788 -395.31671)
					(mid 195.164178 -395.328134)
					(end 195.198238 -395.311122)
				)
				(arc
					(start 195.212208 -395.295882)
					(mid 195.240956 -395.227084)
					(end 195.215002 -395.157198)
				)
				(arc
					(start 195.215002 -395.157198)
					(mid 195.047195 -394.67891)
					(end 195.26758 -394.222478)
				)
			)
		)
		(polygon
			(pts
				(xy 61.086746 -393.9667) (xy 60.832746 -393.9667) (xy 60.832746 -394.2207) (xy 61.086746 -394.2207)
			)
		)
		(polygon
			(pts
				(xy 59.943746 -393.9667) (xy 59.689746 -393.9667) (xy 59.689746 -394.2207) (xy 59.943746 -394.2207)
			)
		)
		(polygon
			(pts
				(arc
					(start 82.68208 -393.745974)
					(mid 82.655231 -393.669503)
					(end 82.580988 -393.637008)
				)
				(xy 80.771238 -393.637008) (xy 80.569054 -393.839192) (xy 80.569054 -394.331952) (xy 82.131154 -394.331952)
				(xy 82.131154 -394.484352) (xy 82.676238 -394.484352)
				(arc
					(start 82.676238 -394.4239)
					(mid 82.707124 -394.268446)
					(end 82.79511 -394.136626)
				)
				(arc
					(start 82.79511 -394.136626)
					(mid 82.703536 -393.951443)
					(end 82.68208 -393.745974)
				)
			)
		)
		(polygon
			(pts
				(xy 75.8698 -393.2174) (xy 75.6158 -393.2174) (xy 75.6158 -393.4714) (xy 75.8698 -393.4714)
			)
		)
		(polygon
			(pts
				(xy 75.2602 -393.2174) (xy 75.0062 -393.2174) (xy 75.0062 -393.4714) (xy 75.2602 -393.4714)
			)
		)
		(polygon
			(pts
				(xy 204.216 -392.3538) (xy 201.803 -392.3538) (xy 201.803 -392.7602) (xy 204.216 -392.7602)
			)
		)
		(polygon
			(pts
				(xy 219.583 -392.3284) (xy 219.329 -392.3284) (xy 219.329 -392.5824) (xy 219.583 -392.5824)
			)
		)
		(polygon
			(pts
				(xy 64.8716 -391.5918) (xy 64.6176 -391.5918) (xy 64.6176 -391.8458) (xy 64.8716 -391.8458)
			)
		)
		(polygon
			(pts
				(xy 64.008 -391.5918) (xy 63.754 -391.5918) (xy 63.754 -391.8458) (xy 64.008 -391.8458)
			)
		)
		(polygon
			(pts
				(xy 214.713058 -390.981184) (xy 214.459058 -390.981184) (xy 214.459058 -391.235184) (xy 214.713058 -391.235184)
			)
		)
		(polygon
			(pts
				(xy 213.570058 -390.981184) (xy 213.316058 -390.981184) (xy 213.316058 -391.235184) (xy 213.570058 -391.235184)
			)
		)
		(polygon
			(pts
				(xy 78.993746 -390.5123) (xy 78.739746 -390.5123) (xy 78.739746 -390.7663) (xy 78.993746 -390.7663)
			)
		)
		(polygon
			(pts
				(xy 78.384146 -390.5123) (xy 78.130146 -390.5123) (xy 78.130146 -390.7663) (xy 78.384146 -390.7663)
			)
		)
		(polygon
			(pts
				(xy 55.930546 -390.1567) (xy 55.676546 -390.1567) (xy 55.676546 -390.4107) (xy 55.930546 -390.4107)
			)
		)
		(polygon
			(pts
				(xy 55.066946 -390.1567) (xy 54.812946 -390.1567) (xy 54.812946 -390.4107) (xy 55.066946 -390.4107)
			)
		)
		(polygon
			(pts
				(xy 78.993746 -388.9883) (xy 78.739746 -388.9883) (xy 78.739746 -389.2423) (xy 78.993746 -389.2423)
			)
		)
		(polygon
			(pts
				(xy 78.384146 -388.9883) (xy 78.130146 -388.9883) (xy 78.130146 -389.2423) (xy 78.384146 -389.2423)
			)
		)
		(polygon
			(pts
				(xy 192.691258 -388.542784) (xy 192.437258 -388.542784) (xy 192.437258 -388.796784) (xy 192.691258 -388.796784)
			)
		)
		(polygon
			(pts
				(xy 217.499438 -388.455408)
				(arc
					(start 215.12911 -388.455408)
					(mid 215.035278 -388.518044)
					(end 215.057228 -388.628636)
				)
				(xy 215.316054 -388.887208) (xy 215.316054 -389.776208) (xy 216.788238 -391.248392) (xy 217.487246 -391.248392)
				(xy 217.513408 -391.185908) (xy 217.499438 -391.172192)
			)
		)
		(polygon
			(pts
				(arc
					(start 202.408282 -388.141464)
					(mid 202.297737 -388.119628)
					(end 202.235054 -388.213346)
				)
				(xy 202.235054 -388.759192) (xy 201.88301 -389.111236) (xy 201.88301 -390.878822)
				(arc
					(start 201.912982 -390.892284)
					(mid 202.007303 -390.945137)
					(end 202.090274 -391.014458)
				)
				(xy 202.090528 -391.014458) (xy 202.126342 -391.050526) (xy 202.229466 -390.947148)
				(arc
					(start 202.229466 -390.701022)
					(mid 202.348482 -390.413564)
					(end 202.635866 -390.294368)
				)
				(xy 202.991974 -390.294368)
				(arc
					(start 203.0222 -390.295384)
					(mid 203.098764 -390.268448)
					(end 203.131166 -390.194038)
				)
				(xy 203.131166 -388.864348)
			)
		)
		(polygon
			(pts
				(xy 55.930546 -387.8707) (xy 55.676546 -387.8707) (xy 55.676546 -388.1247) (xy 55.930546 -388.1247)
			)
		)
		(polygon
			(pts
				(xy 55.066946 -387.8707) (xy 54.812946 -387.8707) (xy 54.812946 -388.1247) (xy 55.066946 -388.1247)
			)
		)
		(polygon
			(pts
				(arc
					(start 196.954902 -387.69544)
					(mid 196.956756 -387.592944)
					(end 196.868288 -387.541008)
				)
				(xy 195.071238 -387.541008) (xy 194.996054 -387.616192) (xy 194.996054 -388.425436) (xy 196.186044 -388.425436)
				(arc
					(start 196.199252 -388.39521)
					(mid 196.437593 -388.128377)
					(end 196.786754 -388.050278)
				)
				(xy 196.810376 -388.052564) (xy 196.895466 -387.96722)
				(arc
					(start 196.895466 -387.907022)
					(mid 196.910651 -387.797152)
					(end 196.954902 -387.69544)
				)
			)
		)
		(polygon
			(pts
				(xy 217.583258 -387.044184) (xy 217.329258 -387.044184) (xy 217.329258 -387.298184) (xy 217.583258 -387.298184)
			)
		)
		(polygon
			(pts
				(xy 60.9854 -386.715) (xy 60.2996 -386.715) (xy 60.2996 -388.7724) (xy 60.9854 -388.7724)
			)
		)
		(polygon
			(pts
				(xy 207.8736 -385.7498) (xy 207.0608 -385.7498) (xy 207.0608 -386.6388) (xy 207.2132 -386.6388)
				(xy 207.2132 -387.434582) (xy 206.42961 -386.651246)
				(arc
					(start 206.42961 -386.566664)
					(mid 206.366974 -386.472832)
					(end 206.256382 -386.494782)
				)
				(xy 205.801722 -386.949442)
				(arc
					(start 203.043282 -386.949442)
					(mid 202.949621 -387.012279)
					(end 202.971654 -387.122924)
				)
				(xy 204.249782 -388.401052)
				(arc
					(start 204.249782 -389.06069)
					(mid 204.281176 -389.107384)
					(end 204.336396 -389.096504)
				)
				(xy 204.360526 -389.07212) (xy 204.360526 -388.963408) (xy 204.469238 -388.963408) (xy 205.232254 -388.200392)
				(arc
					(start 207.7339 -388.200392)
					(mid 207.827732 -388.137756)
					(end 207.805782 -388.027164)
				)
				(xy 207.255618 -387.477) (xy 207.8736 -387.477)
			)
		)
		(polygon
			(pts
				(xy 59.6392 -385.6736) (xy 59.3852 -385.6736) (xy 59.3852 -385.9276) (xy 59.6392 -385.9276)
			)
		)
		(polygon
			(pts
				(xy 193.9798 -385.445) (xy 193.7258 -385.445) (xy 193.7258 -385.699) (xy 193.9798 -385.699)
			)
		)
		(polygon
			(pts
				(xy 193.3702 -385.445) (xy 193.1162 -385.445) (xy 193.1162 -385.699) (xy 193.3702 -385.699)
			)
		)
		(polygon
			(pts
				(xy 199.3646 -385.3688) (xy 199.1106 -385.3688) (xy 199.1106 -385.6228) (xy 199.3646 -385.6228)
			)
		)
		(polygon
			(pts
				(xy 198.755 -385.3688) (xy 198.501 -385.3688) (xy 198.501 -385.6228) (xy 198.755 -385.6228)
			)
		)
		(polygon
			(pts
				(xy 67.2846 -385.2164) (xy 66.4718 -385.2164) (xy 66.4718 -388.6454) (xy 67.2846 -388.6454)
			)
		)
		(polygon
			(pts
				(arc
					(start 29.197046 -384.915156)
					(mid 29.127196 -384.887303)
					(end 29.057346 -384.915156)
				)
				(arc
					(start 29.057346 -384.915156)
					(mid 29.021017 -384.94568)
					(end 28.9814 -384.971798)
				)
				(xy 28.956 -384.986276)
				(arc
					(start 28.956 -390.6901)
					(mid 29.018719 -390.783966)
					(end 29.129482 -390.761982)
				)
				(xy 29.285692 -390.605772) (xy 29.285692 -384.979926)
				(arc
					(start 29.261562 -384.96494)
					(mid 29.228043 -384.94168)
					(end 29.197046 -384.915156)
				)
			)
		)
		(polygon
			(pts
				(xy 218.446858 -384.758184) (xy 218.192858 -384.758184) (xy 218.192858 -385.012184) (xy 218.446858 -385.012184)
			)
		)
		(polygon
			(pts
				(xy 217.583258 -384.758184) (xy 217.329258 -384.758184) (xy 217.329258 -385.012184) (xy 217.583258 -385.012184)
			)
		)
		(polygon
			(pts
				(xy 193.9798 -383.921) (xy 193.7258 -383.921) (xy 193.7258 -384.175) (xy 193.9798 -384.175)
			)
		)
		(polygon
			(pts
				(xy 193.3702 -383.921) (xy 193.1162 -383.921) (xy 193.1162 -384.175) (xy 193.3702 -384.175)
			)
		)
		(polygon
			(pts
				(xy 199.3646 -383.8448) (xy 199.1106 -383.8448) (xy 199.1106 -384.0988) (xy 199.3646 -384.0988)
			)
		)
		(polygon
			(pts
				(xy 198.755 -383.8448) (xy 198.501 -383.8448) (xy 198.501 -384.0988) (xy 198.755 -384.0988)
			)
		)
		(polygon
			(pts
				(xy 212.4964 -383.3622) (xy 212.0646 -383.3622) (xy 211.963 -383.4638) (xy 211.963 -385.4704) (xy 211.7344 -385.699)
				(xy 211.7344 -385.7752) (xy 211.836 -385.8768) (xy 212.725 -385.8768) (xy 212.9282 -385.6736) (xy 212.9282 -383.794)
			)
		)
		(polygon
			(pts
				(xy 60.7822 -382.8796) (xy 60.5282 -382.8796) (xy 60.5282 -383.1336) (xy 60.7822 -383.1336)
			)
		)
		(polygon
			(pts
				(xy 59.6392 -382.8796) (xy 59.3852 -382.8796) (xy 59.3852 -383.1336) (xy 59.6392 -383.1336)
			)
		)
		(polygon
			(pts
				(xy 213.570058 -382.675384) (xy 213.316058 -382.675384) (xy 213.316058 -382.929384) (xy 213.570058 -382.929384)
			)
		)
		(polygon
			(pts
				(arc
					(start 63.495936 -382.650492)
					(mid 63.385391 -382.628656)
					(end 63.322708 -382.722374)
				)
				(xy 63.322708 -383.691892) (xy 65.392554 -383.691892) (xy 65.392554 -383.958592) (xy 65.93332 -383.958592)
				(xy 66.471038 -384.496564)
				(arc
					(start 66.49466 -384.494278)
					(mid 66.744942 -384.526227)
					(end 66.958464 -384.660648)
				)
				(arc
					(start 66.958464 -384.660648)
					(mid 67.06916 -384.682362)
					(end 67.131692 -384.588512)
				)
				(xy 67.131692 -383.311908) (xy 64.157352 -383.311908)
			)
		)
		(polygon
			(pts
				(xy 54.939946 -380.6317) (xy 54.685946 -380.6317) (xy 54.685946 -380.8857) (xy 54.939946 -380.8857)
			)
		)
		(polygon
			(pts
				(xy 213.570058 -379.881384) (xy 213.316058 -379.881384) (xy 213.316058 -380.135384) (xy 213.570058 -380.135384)
			)
		)
		(polygon
			(pts
				(xy 212.427058 -379.881384) (xy 212.173058 -379.881384) (xy 212.173058 -380.135384) (xy 212.427058 -380.135384)
			)
		)
		(polygon
			(pts
				(arc
					(start 207.471518 -379.421136)
					(mid 207.493554 -379.310352)
					(end 207.399636 -379.247654)
				)
				(arc
					(start 205.993492 -379.247654)
					(mid 205.899626 -379.310373)
					(end 205.92161 -379.421136)
				)
				(arc
					(start 207.29321 -380.792736)
					(mid 207.403994 -380.814772)
					(end 207.466692 -380.720854)
				)
				(xy 207.466692 -379.425962)
			)
		)
		(polygon
			(pts
				(arc
					(start 30.067758 -377.82373)
					(mid 29.990939 -377.850379)
					(end 29.958284 -377.924822)
				)
				(xy 29.958284 -378.24918) (xy 28.53055 -378.24918) (xy 28.53055 -378.385324)
				(arc
					(start 28.41371 -378.502164)
					(mid 28.391674 -378.612948)
					(end 28.485592 -378.675646)
				)
				(xy 30.044898 -378.675646) (xy 30.631638 -378.088652) (xy 30.631638 -377.825508) (xy 30.111446 -377.825508)
			)
		)
		(polygon
			(pts
				(xy 218.573858 -377.773184) (xy 218.319858 -377.773184) (xy 218.319858 -378.027184) (xy 218.573858 -378.027184)
			)
		)
		(polygon
			(pts
				(xy 208.000092 -376.428508) (xy 207.747108 -376.428508) (xy 207.747108 -377.231148)
				(arc
					(start 207.593946 -377.231148)
					(mid 207.512907 -377.271468)
					(end 207.496156 -377.360434)
				)
				(arc
					(start 207.496156 -377.360434)
					(mid 207.495972 -377.680611)
					(end 207.327246 -377.952762)
				)
				(arc
					(start 207.327246 -377.952762)
					(mid 207.3011 -378.064361)
					(end 207.395572 -378.129292)
				)
				(xy 208.304892 -378.129292) (xy 208.304892 -377.231148) (xy 208.000092 -377.231148)
			)
		)
		(polygon
			(pts
				(xy 31.622746 -375.9327) (xy 31.368746 -375.9327) (xy 31.368746 -376.1867) (xy 31.622746 -376.1867)
			)
		)
		(polygon
			(pts
				(xy 31.013146 -375.9327) (xy 30.759146 -375.9327) (xy 30.759146 -376.1867) (xy 31.013146 -376.1867)
			)
		)
		(polygon
			(pts
				(xy 216.0524 -375.8184) (xy 210.693 -375.8184) (xy 209.677 -376.8344) (xy 209.677 -378.0536) (xy 210.1342 -378.5108)
				(xy 216.1032 -378.5108) (xy 216.535 -378.079) (xy 216.535 -376.301)
			)
		)
		(polygon
			(pts
				(xy 30.619446 -375.0691) (xy 30.365446 -375.0691) (xy 30.365446 -375.3231) (xy 30.619446 -375.3231)
			)
		)
		(polygon
			(pts
				(xy 25.387046 -375.0691) (xy 25.133046 -375.0691) (xy 25.133046 -375.3231) (xy 25.387046 -375.3231)
			)
		)
		(polygon
			(pts
				(xy 30.619446 -374.5103) (xy 30.365446 -374.5103) (xy 30.365446 -374.7643) (xy 30.619446 -374.7643)
			)
		)
		(polygon
			(pts
				(xy 62.484 -372.364) (xy 57.785 -372.364) (xy 56.388 -373.761) (xy 56.388 -381.381) (xy 56.642 -381.635)
				(xy 61.722 -381.635) (xy 62.484 -380.873)
			)
		)
		(polygon
			(pts
				(xy 226.694746 -369.4557) (xy 222.630746 -369.4557) (xy 222.376746 -369.7097) (xy 222.376746 -371.1067)
				(xy 222.630746 -371.3607) (xy 226.694746 -371.3607) (xy 226.821746 -371.2337) (xy 226.821746 -369.5827)
			)
		)
		(polygon
			(pts
				(xy 36.575746 -369.2017) (xy 36.194746 -369.2017) (xy 35.686746 -369.7097) (xy 35.686746 -371.3607)
				(xy 35.407346 -371.6401) (xy 30.784546 -371.6401) (xy 30.632146 -371.7925) (xy 30.632146 -372.0973)
				(xy 30.606746 -372.1227) (xy 30.606746 -374.2817) (xy 31.114746 -374.7897) (xy 32.892746 -374.7897)
				(xy 33.908746 -373.7737) (xy 41.782746 -373.7737) (xy 42.036746 -373.5197) (xy 42.036746 -369.8367)
				(xy 41.655746 -369.4557) (xy 38.861746 -369.4557) (xy 38.734746 -369.5827) (xy 36.956746 -369.5827)
			)
		)
		(polygon
			(pts
				(xy 33.273746 -366.4077) (xy 31.749746 -366.4077) (xy 31.241746 -366.9157) (xy 31.241746 -367.0427)
				(xy 31.495746 -367.2967) (xy 31.495746 -367.4237) (xy 32.003746 -367.9317) (xy 32.892746 -367.9317)
				(xy 33.273746 -367.5507)
			)
		)
		(polygon
			(pts
				(xy 223.724216 -349.491808) (xy 222.460566 -349.491808)
				(arc
					(start 222.460566 -349.629984)
					(mid 222.435347 -349.770753)
					(end 222.36303 -349.894144)
				)
				(arc
					(start 222.36303 -349.894144)
					(mid 222.338641 -349.960184)
					(end 222.36303 -350.026224)
				)
				(arc
					(start 222.36303 -350.026224)
					(mid 222.410235 -350.094655)
					(end 222.442532 -350.171258)
				)
				(xy 222.453708 -350.207072) (xy 222.962216 -350.207072)
				(arc
					(start 222.977456 -350.185482)
					(mid 223.519746 -349.902321)
					(end 224.062036 -350.185482)
				)
				(xy 224.077276 -350.207072)
				(arc
					(start 224.60458 -350.207072)
					(mid 224.698412 -350.144436)
					(end 224.676462 -350.033844)
				)
				(xy 224.42424 -349.781622)
				(arc
					(start 224.398078 -349.786194)
					(mid 224.028843 -349.746204)
					(end 223.739456 -349.513398)
				)
			)
		)
		(polygon
			(pts
				(xy 52.528216 -347.459808) (xy 52.04587 -347.459808)
				(arc
					(start 52.0446 -347.509084)
					(mid 51.921451 -347.789168)
					(end 51.637946 -347.904308)
				)
				(arc
					(start 51.282346 -347.904308)
					(mid 51.147772 -347.881321)
					(end 51.028346 -347.815154)
				)
				(arc
					(start 51.028346 -347.815154)
					(mid 50.908936 -347.881366)
					(end 50.774346 -347.904308)
				)
				(xy 50.50282 -347.904308) (xy 50.001678 -348.405196)
				(arc
					(start 50.012854 -348.43593)
					(mid 50.0318 -348.505289)
					(end 50.038254 -348.5769)
				)
				(xy 50.038254 -348.9325) (xy 50.03673 -348.966028) (xy 50.036476 -348.96806) (xy 50.036476 -349.020892)
				(xy 51.816254 -349.020892) (xy 51.816254 -349.351092) (xy 51.967638 -349.351092) (xy 51.967638 -348.036896)
				(xy 52.729638 -348.036896) (xy 52.729638 -347.66123)
				(arc
					(start 52.708048 -347.64599)
					(mid 52.618448 -347.570998)
					(end 52.543456 -347.481398)
				)
			)
		)
		(polygon
			(pts
				(xy 228.579172 -346.697808) (xy 227.125276 -346.697808)
				(arc
					(start 227.110036 -346.719398)
					(mid 227.066772 -346.775068)
					(end 227.017834 -346.825824)
				)
				(arc
					(start 227.017834 -346.825824)
					(mid 226.994037 -346.859565)
					(end 226.985576 -346.899992)
				)
				(arc
					(start 226.985576 -346.900246)
					(mid 227.015334 -346.971834)
					(end 227.086922 -347.001592)
				)
				(xy 228.453442 -347.001592)
				(arc
					(start 229.08641 -347.634814)
					(mid 229.196955 -347.65665)
					(end 229.259638 -347.562932)
				)
				(xy 229.259638 -347.378274)
			)
		)
		(polygon
			(pts
				(xy 226.010216 -346.697808)
				(arc
					(start 224.165922 -346.697808)
					(mid 224.071623 -346.762229)
					(end 224.096834 -346.873576)
				)
				(arc
					(start 224.096834 -346.873576)
					(mid 224.145783 -346.924322)
					(end 224.189036 -346.980002)
				)
				(xy 224.204276 -347.001592)
				(arc
					(start 226.04857 -347.001592)
					(mid 226.142869 -346.937171)
					(end 226.117658 -346.825824)
				)
				(arc
					(start 226.117658 -346.825824)
					(mid 226.068709 -346.775078)
					(end 226.025456 -346.719398)
				)
			)
		)
		(polygon
			(pts
				(xy 220.6752 -346.2274) (xy 215.9254 -346.2274) (xy 215.9254 -348.5388) (xy 219.4814 -348.5388)
				(arc
					(start 219.4814 -348.716854)
					(mid 219.450651 -348.871976)
					(end 219.363036 -349.00362)
				)
				(arc
					(start 219.363036 -349.00362)
					(mid 219.333606 -349.070935)
					(end 219.357194 -349.140526)
				)
				(arc
					(start 219.357194 -349.140526)
					(mid 219.384179 -349.175125)
					(end 219.408502 -349.211646)
				)
				(arc
					(start 219.408502 -349.211646)
					(mid 219.500573 -349.260001)
					(end 219.58681 -349.201994)
				)
				(arc
					(start 219.58681 -349.201994)
					(mid 219.875773 -348.918731)
					(end 220.279468 -348.890844)
				)
				(xy 220.286326 -348.892876) (xy 220.692726 -348.892876)
				(arc
					(start 220.700854 -348.890082)
					(mid 220.766707 -348.873159)
					(end 220.834458 -348.867476)
				)
				(arc
					(start 221.190058 -348.867476)
					(mid 221.324632 -348.890463)
					(end 221.444058 -348.95663)
				)
				(arc
					(start 221.444058 -348.95663)
					(mid 221.563468 -348.890418)
					(end 221.698058 -348.867476)
				)
				(xy 221.969584 -348.867476) (xy 222.057468 -348.779592)
				(arc
					(start 222.411544 -348.779592)
					(mid 222.446149 -348.688294)
					(end 222.458026 -348.591378)
				)
				(arc
					(start 222.458026 -348.591378)
					(mid 222.430923 -348.737099)
					(end 222.353378 -348.863412)
				)
				(arc
					(start 222.353378 -348.863412)
					(mid 222.327206 -348.931843)
					(end 222.353886 -349.000064)
				)
				(arc
					(start 222.353886 -349.000064)
					(mid 222.432872 -349.127245)
					(end 222.460566 -349.274384)
				)
				(xy 222.460566 -349.394272) (xy 226.006914 -349.394272) (xy 226.006914 -349.140272) (xy 228.751638 -349.140272)
				(xy 228.751638 -348.307152) (xy 228.158294 -347.713808) (xy 224.204276 -347.713808)
				(arc
					(start 224.189036 -347.735398)
					(mid 223.646746 -348.018559)
					(end 223.104456 -347.735398)
				)
				(xy 223.089216 -347.713808) (xy 222.337122 -347.713808)
				(arc
					(start 222.322644 -347.738954)
					(mid 222.308982 -347.761002)
					(end 222.293942 -347.782134)
				)
				(arc
					(start 222.293942 -347.782134)
					(mid 222.273082 -347.846019)
					(end 222.296736 -347.90888)
				)
				(arc
					(start 222.296736 -347.90888)
					(mid 222.237604 -347.87712)
					(end 222.171514 -347.889068)
				)
				(arc
					(start 222.171514 -347.889068)
					(mid 222.074398 -347.928821)
					(end 221.970346 -347.942408)
				)
				(arc
					(start 221.614746 -347.942408)
					(mid 221.480172 -347.919421)
					(end 221.360746 -347.853254)
				)
				(arc
					(start 221.360746 -347.853254)
					(mid 221.241336 -347.919466)
					(end 221.106746 -347.942408)
				)
				(arc
					(start 220.750638 -347.942408)
					(mid 220.712753 -347.940616)
					(end 220.6752 -347.935296)
				)
			)
		)
		(polygon
			(pts
				(xy 29.040074 -335.982056) (xy 27.940254 -335.982056) (xy 27.940254 -336.244946) (xy 28.613862 -336.918554)
				(arc
					(start 28.631642 -336.920332)
					(mid 28.760803 -336.944611)
					(end 28.882594 -336.993992)
				)
				(arc
					(start 28.882594 -336.993992)
					(mid 28.982584 -336.991171)
					(end 29.031692 -336.904076)
				)
				(xy 29.031692 -336.822034)
				(arc
					(start 29.028644 -336.813906)
					(mid 29.011845 -336.748043)
					(end 29.006292 -336.680302)
				)
				(arc
					(start 29.006292 -336.324194)
					(mid 29.029199 -336.189891)
					(end 29.095192 -336.070702)
				)
				(arc
					(start 29.095192 -336.070702)
					(mid 29.07346 -336.04077)
					(end 29.054552 -336.00898)
				)
			)
		)
		(polygon
			(pts
				(xy 34.213546 -333.022702) (xy 33.959546 -333.022702) (xy 33.959546 -333.276702) (xy 34.213546 -333.276702)
			)
		)
		(polygon
			(pts
				(xy 33.603946 -333.022702) (xy 33.349946 -333.022702) (xy 33.349946 -333.276702) (xy 33.603946 -333.276702)
			)
		)
		(polygon
			(pts
				(xy 36.669218 -332.93304) (xy 36.415218 -332.93304) (xy 36.415218 -333.18704) (xy 36.669218 -333.18704)
			)
		)
		(polygon
			(pts
				(xy 36.059618 -332.93304) (xy 35.805618 -332.93304) (xy 35.805618 -333.18704) (xy 36.059618 -333.18704)
			)
		)
		(polygon
			(pts
				(xy 45.5168 -322.961) (xy 45.2628 -322.961) (xy 45.2628 -323.215) (xy 45.5168 -323.215)
			)
		)
		(polygon
			(pts
				(xy 26.974546 -313.1947) (xy 26.720546 -313.1947) (xy 26.720546 -313.4487) (xy 26.974546 -313.4487)
			)
		)
		(polygon
			(pts
				(xy 26.110946 -313.1947) (xy 25.856946 -313.1947) (xy 25.856946 -313.4487) (xy 26.110946 -313.4487)
			)
		)
		(polygon
			(pts
				(xy 37.211 -303.022) (xy 32.131 -303.022) (xy 32.004 -303.149) (xy 32.004 -305.308) (xy 32.385 -305.689)
				(xy 34.036 -305.689) (xy 34.036 -305.816) (xy 34.544 -306.324) (xy 37.084 -306.324) (xy 37.465508 -305.942492)
				(arc
					(start 37.7698 -305.942492)
					(mid 38.057527 -306.061673)
					(end 38.176708 -306.3494)
				)
				(arc
					(start 38.176708 -306.398676)
					(mid 38.224182 -306.484404)
					(end 38.321996 -306.490116)
				)
				(arc
					(start 38.321996 -306.490116)
					(mid 38.350162 -306.477387)
					(end 38.378892 -306.465986)
				)
				(xy 38.378892 -305.455574) (xy 37.846 -304.922682) (xy 37.846 -303.657)
			)
		)
		(polygon
			(pts
				(xy 28.935172 -303.009808) (xy 27.653996 -303.009808) (xy 27.653996 -303.076102)
				(arc
					(start 27.662632 -303.088802)
					(mid 27.677134 -303.111466)
					(end 27.690572 -303.134776)
				)
				(xy 27.694128 -303.141126) (xy 28.372054 -303.819052) (xy 28.372054 -304.07737)
				(arc
					(start 28.374848 -304.085498)
					(mid 28.391771 -304.151351)
					(end 28.397454 -304.219102)
				)
				(arc
					(start 28.397454 -304.574702)
					(mid 28.374467 -304.709276)
					(end 28.3083 -304.828702)
				)
				(arc
					(start 28.3083 -304.828702)
					(mid 28.330032 -304.858634)
					(end 28.34894 -304.890424)
				)
				(xy 28.363418 -304.917348) (xy 29.61767 -304.917348) (xy 29.869638 -304.665126) (xy 29.869638 -303.944274)
			)
		)
		(polygon
			(pts
				(xy 35.2552 -300.0756) (xy 35.0012 -300.0756) (xy 35.0012 -300.3296) (xy 35.2552 -300.3296)
			)
		)
		(polygon
			(pts
				(xy 34.3916 -300.0756) (xy 34.1376 -300.0756) (xy 34.1376 -300.3296) (xy 34.3916 -300.3296)
			)
		)
		(polygon
			(pts
				(xy 195.2498 -294.513) (xy 194.9958 -294.513) (xy 194.9958 -294.767) (xy 195.2498 -294.767)
			)
		)
		(polygon
			(pts
				(xy 194.6402 -294.513) (xy 194.3862 -294.513) (xy 194.3862 -294.767) (xy 194.6402 -294.767)
			)
		)
		(polygon
			(pts
				(xy 194.2084 -294.4622) (xy 193.9544 -294.4622) (xy 193.9544 -294.7162) (xy 194.2084 -294.7162)
			)
		)
		(polygon
			(pts
				(xy 192.278 -293.243) (xy 190.627 -293.243) (xy 189.611 -294.259) (xy 189.611 -295.783) (xy 190.5 -296.672)
				(xy 194.818 -296.672) (xy 195.199 -297.053) (xy 195.326 -296.926) (xy 195.326 -295.656) (xy 194.945 -295.275)
				(xy 193.675 -295.275) (xy 192.278 -293.878)
			)
		)
		(polygon
			(pts
				(xy 219.743782 -292.199568) (xy 219.489782 -292.199568) (xy 219.489782 -292.453568) (xy 219.743782 -292.453568)
			)
		)
		(polygon
			(pts
				(xy 218.880182 -292.199568) (xy 218.626182 -292.199568) (xy 218.626182 -292.453568) (xy 218.880182 -292.453568)
			)
		)
		(polygon
			(pts
				(xy 195.223892 -291.595048) (xy 194.919854 -291.595048) (xy 194.919854 -291.747448) (xy 194.4624 -291.747448)
				(xy 194.4624 -292.04412) (xy 194.193414 -292.313106)
				(arc
					(start 194.197986 -292.339268)
					(mid 194.199937 -292.560974)
					(end 194.12839 -292.770814)
				)
				(arc
					(start 194.12839 -292.770814)
					(mid 194.120583 -292.848606)
					(end 194.1703 -292.90899)
				)
				(arc
					(start 194.1703 -292.90899)
					(mid 194.205751 -292.930109)
					(end 194.23888 -292.95471)
				)
				(arc
					(start 194.23888 -292.95471)
					(mid 194.275178 -292.966134)
					(end 194.309238 -292.949122)
				)
				(arc
					(start 194.309238 -292.949122)
					(mid 194.447087 -292.846937)
					(end 194.6148 -292.810692)
				)
				(arc
					(start 194.905376 -292.810692)
					(mid 194.992335 -292.761634)
					(end 194.995292 -292.661848)
				)
				(arc
					(start 194.995292 -292.661848)
					(mid 194.94117 -292.185033)
					(end 195.223892 -291.797232)
				)
			)
		)
		(polygon
			(pts
				(xy 212.1154 -291.1602) (xy 205.0796 -291.1602) (xy 205.0796 -291.6682) (xy 212.1154 -291.6682)
			)
		)
		(polygon
			(pts
				(xy 213.994746 -288.1757) (xy 213.740746 -288.1757) (xy 213.740746 -288.4297) (xy 213.994746 -288.4297)
			)
		)
		(polygon
			(pts
				(xy 212.851746 -288.1757) (xy 212.597746 -288.1757) (xy 212.597746 -288.4297) (xy 212.851746 -288.4297)
			)
		)
		(polygon
			(pts
				(arc
					(start 221.339664 -287.892236)
					(mid 221.3615 -287.781691)
					(end 221.267782 -287.719008)
				)
				(xy 220.344238 -287.719008)
				(arc
					(start 219.603828 -288.459164)
					(mid 219.581992 -288.569709)
					(end 219.67571 -288.632392)
				)
				(xy 220.599254 -288.632392)
			)
		)
		(polygon
			(pts
				(xy 189.52464 -287.424622)
				(arc
					(start 189.498478 -287.429194)
					(mid 189.407665 -287.439056)
					(end 189.31636 -287.436306)
				)
				(arc
					(start 189.31636 -287.436306)
					(mid 189.238044 -287.462049)
					(end 189.2046 -287.537398)
				)
				(arc
					(start 189.2046 -289.579304)
					(mid 189.259024 -289.669034)
					(end 189.363858 -289.66287)
				)
				(arc
					(start 189.363858 -289.66287)
					(mid 189.751287 -289.546908)
					(end 190.133732 -289.678364)
				)
				(arc
					(start 190.133732 -289.678364)
					(mid 190.240129 -289.687958)
					(end 190.296292 -289.597084)
				)
				(xy 190.296292 -289.555174) (xy 190.292228 -289.55111)
				(arc
					(start 190.292228 -287.910524)
					(mid 190.190395 -287.833969)
					(end 190.117222 -287.729676)
				)
				(xy 189.82944 -287.729676)
			)
		)
		(polygon
			(pts
				(xy 192.273428 -286.830008)
				(arc
					(start 192.136522 -286.830008)
					(mid 192.048013 -286.881721)
					(end 192.049654 -286.984186)
				)
				(arc
					(start 192.049654 -286.984186)
					(mid 192.093753 -287.085658)
					(end 192.108836 -287.19526)
				)
				(arc
					(start 192.108836 -287.551368)
					(mid 192.05767 -287.748907)
					(end 191.917066 -287.896808)
				)
				(xy 191.892936 -287.911794) (xy 191.892936 -287.97123)
				(arc
					(start 191.91605 -287.986216)
					(mid 192.01477 -288.065303)
					(end 192.096644 -288.16173)
				)
				(xy 192.111884 -288.18332) (xy 192.655444 -288.18332) (xy 192.832228 -288.00679) (xy 192.832228 -287.897316)
				(xy 192.273428 -287.897316)
			)
		)
		(polygon
			(pts
				(xy 55.8292 -286.766) (xy 55.5752 -286.766) (xy 55.5752 -287.02) (xy 55.8292 -287.02)
			)
		)
		(polygon
			(pts
				(xy 54.9656 -286.766) (xy 54.7116 -286.766) (xy 54.7116 -287.02) (xy 54.9656 -287.02)
			)
		)
		(polygon
			(pts
				(arc
					(start 201.229722 -286.234632)
					(mid 201.119177 -286.212796)
					(end 201.056494 -286.306514)
				)
				(arc
					(start 201.056494 -287.840674)
					(mid 201.088905 -287.915074)
					(end 201.16546 -287.94202)
				)
				(arc
					(start 201.16546 -287.94202)
					(mid 201.290289 -287.94648)
					(end 201.411332 -287.977326)
				)
				(arc
					(start 201.411332 -287.977326)
					(mid 201.504658 -287.965459)
					(end 201.548238 -287.882076)
				)
				(arc
					(start 201.548238 -287.6169)
					(mid 201.667419 -287.329173)
					(end 201.955146 -287.209992)
				)
				(arc
					(start 201.959972 -287.209992)
					(mid 202.053804 -287.147356)
					(end 202.031854 -287.036764)
				)
			)
		)
		(polygon
			(pts
				(xy 191.930782 -285.697168) (xy 191.676782 -285.697168) (xy 191.676782 -285.951168) (xy 191.930782 -285.951168)
			)
		)
		(polygon
			(pts
				(arc
					(start 217.044778 -285.456122)
					(mid 217.055684 -285.400891)
					(end 217.008964 -285.369508)
				)
				(arc
					(start 214.65921 -285.369508)
					(mid 214.565378 -285.432144)
					(end 214.587328 -285.542736)
				)
				(xy 215.570054 -286.525208) (xy 215.570054 -288.430208) (xy 215.772238 -288.632392) (xy 217.118438 -288.632392)
				(xy 217.118438 -288.556192) (xy 216.991438 -288.429192) (xy 216.991438 -285.509208)
			)
		)
		(polygon
			(pts
				(arc
					(start 195.587366 -285.333186)
					(mid 195.588955 -285.23075)
					(end 195.500498 -285.179008)
				)
				(xy 194.563238 -285.179008)
				(arc
					(start 194.335654 -285.406338)
					(mid 194.313569 -285.517005)
					(end 194.407282 -285.57982)
				)
				(xy 195.504054 -285.57982)
				(arc
					(start 195.51142 -285.537656)
					(mid 195.539782 -285.431852)
					(end 195.587366 -285.333186)
				)
			)
		)
		(polygon
			(pts
				(xy 198.195946 -284.9753) (xy 197.941946 -284.9753) (xy 197.941946 -285.2293) (xy 198.195946 -285.2293)
			)
		)
		(polygon
			(pts
				(xy 200.039732 -284.925008) (xy 199.75576 -284.925008) (xy 199.75576 -286.562292) (xy 200.039732 -286.562292)
			)
		)
		(polygon
			(pts
				(arc
					(start 189.378082 -284.945582)
					(mid 189.267537 -284.923746)
					(end 189.204854 -285.017464)
				)
				(arc
					(start 189.204854 -286.020002)
					(mid 189.238205 -286.095266)
					(end 189.31636 -286.121094)
				)
				(arc
					(start 189.31636 -286.121094)
					(mid 189.407666 -286.11834)
					(end 189.498478 -286.128206)
				)
				(xy 189.52464 -286.132778) (xy 189.909704 -285.74746) (xy 190.116206 -285.74746)
				(arc
					(start 190.130684 -285.722314)
					(mid 190.172141 -285.663308)
					(end 190.223394 -285.612586)
				)
				(arc
					(start 190.223394 -285.612586)
					(mid 190.253832 -285.500029)
					(end 190.15837 -285.433008)
				)
				(xy 189.865254 -285.433008)
			)
		)
		(polygon
			(pts
				(xy 217.813382 -284.198568) (xy 217.559382 -284.198568) (xy 217.559382 -284.452568) (xy 217.813382 -284.452568)
			)
		)
		(polygon
			(pts
				(xy 216.949782 -284.198568) (xy 216.695782 -284.198568) (xy 216.695782 -284.452568) (xy 216.949782 -284.452568)
			)
		)
		(polygon
			(pts
				(arc
					(start 206.980282 -283.90342)
					(mid 206.869498 -283.881384)
					(end 206.8068 -283.975302)
				)
				(xy 206.8068 -283.984192) (xy 206.650082 -284.141164) (xy 206.119222 -284.672024) (xy 205.10627 -284.672024)
				(xy 205.105254 -284.671008) (xy 202.184254 -284.671008)
				(arc
					(start 202.154282 -284.640782)
					(mid 202.043737 -284.618946)
					(end 201.981054 -284.712664)
				)
				(xy 201.981054 -285.404052)
				(arc
					(start 203.48321 -286.906208)
					(mid 203.593755 -286.928044)
					(end 203.656438 -286.834326)
				)
				(xy 203.656438 -285.636208) (xy 204.089254 -285.203392)
				(arc
					(start 207.4672 -285.203392)
					(mid 207.561032 -285.140756)
					(end 207.539082 -285.030164)
				)
				(arc
					(start 207.539082 -285.030164)
					(mid 207.56107 -285.063026)
					(end 207.5688 -285.101792)
				)
				(arc
					(start 207.5688 -285.102046)
					(mid 207.598558 -285.173634)
					(end 207.670146 -285.203392)
				)
				(arc
					(start 208.035144 -285.203392)
					(mid 208.128976 -285.140756)
					(end 208.107026 -285.030164)
				)
			)
		)
		(polygon
			(pts
				(xy 198.1708 -282.321) (xy 197.9168 -282.321) (xy 197.9168 -282.575) (xy 198.1708 -282.575)
			)
		)
		(polygon
			(pts
				(xy 197.5612 -282.321) (xy 197.3072 -282.321) (xy 197.3072 -282.575) (xy 197.5612 -282.575)
			)
		)
		(polygon
			(pts
				(xy 193.5988 -282.321) (xy 193.3448 -282.321) (xy 193.3448 -282.575) (xy 193.5988 -282.575)
			)
		)
		(polygon
			(pts
				(xy 192.9892 -282.321) (xy 192.7352 -282.321) (xy 192.7352 -282.575) (xy 192.9892 -282.575)
			)
		)
		(polygon
			(pts
				(xy 217.813382 -281.912568) (xy 217.559382 -281.912568) (xy 217.559382 -282.166568) (xy 217.813382 -282.166568)
			)
		)
		(polygon
			(pts
				(xy 216.949782 -281.912568) (xy 216.695782 -281.912568) (xy 216.695782 -282.166568) (xy 216.949782 -282.166568)
			)
		)
		(polygon
			(pts
				(xy 198.1708 -280.797) (xy 197.9168 -280.797) (xy 197.9168 -281.051) (xy 198.1708 -281.051)
			)
		)
		(polygon
			(pts
				(xy 197.5612 -280.797) (xy 197.3072 -280.797) (xy 197.3072 -281.051) (xy 197.5612 -281.051)
			)
		)
		(polygon
			(pts
				(xy 193.5988 -280.797) (xy 193.3448 -280.797) (xy 193.3448 -281.051) (xy 193.5988 -281.051)
			)
		)
		(polygon
			(pts
				(xy 192.9892 -280.797) (xy 192.7352 -280.797) (xy 192.7352 -281.051) (xy 192.9892 -281.051)
			)
		)
		(polygon
			(pts
				(xy 213.127082 -279.829768) (xy 212.873082 -279.829768) (xy 212.873082 -280.083768) (xy 213.127082 -280.083768)
			)
		)
		(polygon
			(pts
				(xy 56.4388 -275.5392) (xy 56.1848 -275.5392) (xy 56.1848 -275.7932) (xy 56.4388 -275.7932)
			)
		)
		(polygon
			(pts
				(xy 218.067382 -274.927568) (xy 217.813382 -274.927568) (xy 217.813382 -275.181568) (xy 218.067382 -275.181568)
			)
		)
		(polygon
			(pts
				(arc
					(start 215.758522 -272.988024)
					(mid 215.670397 -272.943484)
					(end 215.586056 -272.994882)
				)
				(arc
					(start 215.586056 -272.994882)
					(mid 215.475598 -273.139146)
					(end 215.330024 -273.247866)
				)
				(arc
					(start 215.330024 -273.247866)
					(mid 215.277675 -273.334827)
					(end 215.326722 -273.423634)
				)
				(arc
					(start 215.326722 -273.423634)
					(mid 215.589372 -273.720788)
					(end 215.63457 -274.114768)
				)
				(xy 215.633808 -274.119594) (xy 215.633808 -274.594574) (xy 215.657684 -274.60956) (xy 215.675718 -274.621498)
				(xy 215.688926 -274.630642) (xy 215.755728 -274.630642)
				(arc
					(start 215.755728 -274.394168)
					(mid 215.805872 -274.19848)
					(end 215.943942 -274.051014)
				)
				(arc
					(start 215.943942 -274.051014)
					(mid 215.96526 -274.022371)
					(end 215.962484 -273.986752)
				)
				(arc
					(start 215.962484 -273.986752)
					(mid 215.912711 -273.66432)
					(end 216.04351 -273.365468)
				)
				(arc
					(start 216.04351 -273.365468)
					(mid 216.064916 -273.279672)
					(end 216.010998 -273.209512)
				)
				(arc
					(start 216.010998 -273.209512)
					(mid 215.870466 -273.115064)
					(end 215.758522 -272.988024)
				)
			)
		)
		(polygon
			(pts
				(xy 208.0514 -271.3736) (xy 206.6798 -271.3736) (xy 206.6798 -272.542) (xy 208.0514 -272.542)
			)
		)
		(polygon
			(pts
				(arc
					(start 62.45479 -271.385792)
					(mid 62.344123 -271.363707)
					(end 62.281308 -271.45742)
				)
				(xy 62.281308 -272.08988) (xy 63.221108 -273.029426) (xy 63.221108 -273.407124)
				(arc
					(start 63.246254 -273.421602)
					(mid 63.395223 -273.570476)
					(end 63.449708 -273.7739)
				)
				(arc
					(start 63.449708 -274.1295)
					(mid 63.426721 -274.264074)
					(end 63.360554 -274.3835)
				)
				(arc
					(start 63.360554 -274.3835)
					(mid 63.426766 -274.50291)
					(end 63.449708 -274.6375)
				)
				(arc
					(start 63.449708 -274.9931)
					(mid 63.443986 -275.060845)
					(end 63.427102 -275.126704)
				)
				(xy 63.424308 -275.134832) (xy 63.424308 -275.546058)
				(arc
					(start 63.42634 -275.552916)
					(mid 63.380041 -275.994054)
					(end 63.037466 -276.2758)
				)
				(arc
					(start 63.037466 -276.2758)
					(mid 62.968867 -276.348403)
					(end 62.995556 -276.44471)
				)
				(arc
					(start 67.527424 -280.976578)
					(mid 67.582894 -280.987684)
					(end 67.614292 -280.940764)
				)
				(xy 67.614292 -280.912062) (xy 64.009524 -277.307294) (xy 64.009524 -272.940272)
			)
		)
		(polygon
			(pts
				(xy 61.4426 -270.6878) (xy 58.6486 -270.6878) (xy 57.7596 -271.5768) (xy 57.7596 -272.9738) (xy 58.166 -273.3802)
				(xy 61.8998 -273.3802) (xy 62.1538 -273.1262) (xy 62.1538 -271.399)
			)
		)
		(polygon
			(pts
				(xy 222.631 -268.732) (xy 216.535 -268.732) (xy 216.281 -268.986) (xy 214.63 -268.986) (xy 214.376 -269.24)
				(xy 214.376 -270.383) (xy 215.011 -271.018) (xy 218.694 -271.018) (xy 219.075 -270.637) (xy 226.568 -270.637)
				(xy 226.822 -270.383) (xy 226.822 -269.113) (xy 226.695 -268.986) (xy 224.155 -268.986) (xy 223.901 -269.24)
				(xy 223.139 -269.24)
			)
		)
		(polygon
			(pts
				(arc
					(start 19.079464 -257.807714)
					(mid 19.024268 -257.796735)
					(end 18.99285 -257.843528)
				)
				(xy 18.99285 -258.850892) (xy 19.156426 -258.850892)
				(arc
					(start 20.03425 -257.973322)
					(mid 20.04543 -257.917886)
					(end 19.998436 -257.886454)
				)
				(arc
					(start 19.9644 -257.886454)
					(mid 19.896666 -257.880859)
					(end 19.830796 -257.864102)
				)
				(xy 19.822668 -257.861308) (xy 19.133058 -257.861308)
			)
		)
		(polygon
			(pts
				(xy 23.875238 -251.887736) (xy 23.801324 -251.887736)
				(arc
					(start 23.786084 -251.90577)
					(mid 23.752753 -251.942035)
					(end 23.716488 -251.975366)
				)
				(xy 23.698708 -251.990606) (xy 23.698708 -254.12192)
				(arc
					(start 23.054056 -254.766318)
					(mid 23.03019 -254.872352)
					(end 23.115778 -254.939292)
				)
				(xy 23.673308 -254.939292)
				(arc
					(start 23.673308 -254.989076)
					(mid 23.704129 -255.028876)
					(end 23.75408 -255.022604)
				)
				(xy 23.875238 -254.901446)
			)
		)
		(polygon
			(pts
				(xy 48.603916 -244.843808) (xy 48.108108 -244.843808)
				(arc
					(start 48.09998 -244.884448)
					(mid 47.959082 -245.119643)
					(end 47.700946 -245.212108)
				)
				(arc
					(start 47.345346 -245.212108)
					(mid 47.210772 -245.189121)
					(end 47.091346 -245.122954)
				)
				(arc
					(start 47.091346 -245.122954)
					(mid 46.978724 -245.186564)
					(end 46.851824 -245.2116)
				)
				(xy 46.832012 -245.212362)
				(arc
					(start 46.56201 -245.482364)
					(mid 46.540174 -245.592909)
					(end 46.633892 -245.655592)
				)
				(xy 48.02632 -245.655592)
				(arc
					(start 48.11141 -245.740936)
					(mid 48.221955 -245.762772)
					(end 48.284638 -245.669054)
				)
				(xy 48.284638 -245.243096) (xy 48.805338 -245.243096) (xy 48.805338 -245.04523)
				(arc
					(start 48.783748 -245.02999)
					(mid 48.694148 -244.954998)
					(end 48.619156 -244.865398)
				)
			)
		)
		(polygon
			(pts
				(xy 233.642916 -244.462808) (xy 233.400854 -244.462808)
				(arc
					(start 233.400854 -244.5512)
					(mid 233.281673 -244.838927)
					(end 232.993946 -244.958108)
				)
				(arc
					(start 232.638346 -244.958108)
					(mid 232.503772 -244.935121)
					(end 232.384346 -244.868954)
				)
				(arc
					(start 232.384346 -244.868954)
					(mid 232.264936 -244.935166)
					(end 232.130346 -244.958108)
				)
				(xy 231.85882 -244.958108) (xy 231.35209 -245.464838)
				(arc
					(start 231.35209 -245.641368)
					(mid 231.326871 -245.782137)
					(end 231.254554 -245.905528)
				)
				(arc
					(start 231.254554 -245.905528)
					(mid 231.230165 -245.971568)
					(end 231.254554 -246.037608)
				)
				(arc
					(start 231.254554 -246.037608)
					(mid 231.277399 -246.066984)
					(end 231.29748 -246.098314)
				)
				(xy 231.311958 -246.12346) (xy 231.418638 -246.12346) (xy 231.418638 -245.973092) (xy 233.172254 -245.973092)
				(xy 233.172254 -246.303292) (xy 233.323638 -246.303292) (xy 233.323638 -244.989096) (xy 233.844338 -244.989096)
				(xy 233.844338 -244.66423)
				(arc
					(start 233.822748 -244.64899)
					(mid 233.733148 -244.573998)
					(end 233.658156 -244.484398)
				)
			)
		)
		(polygon
			(pts
				(xy 231.017572 -243.954808)
				(arc
					(start 230.822754 -243.954808)
					(mid 230.738008 -244.000751)
					(end 230.72979 -244.096794)
				)
				(arc
					(start 230.72979 -244.096794)
					(mid 230.78244 -244.415996)
					(end 230.677212 -244.721888)
				)
				(arc
					(start 230.677212 -244.721888)
					(mid 230.673061 -244.825659)
					(end 230.762302 -244.87886)
				)
				(xy 230.930704 -244.87886) (xy 231.368092 -244.441726) (xy 231.368092 -244.305074)
			)
		)
		(polygon
			(pts
				(xy 60.3758 -231.775) (xy 60.1218 -231.775) (xy 60.1218 -232.029) (xy 60.3758 -232.029)
			)
		)
		(polygon
			(pts
				(xy 55.2704 -228.9048) (xy 55.0164 -228.9048) (xy 55.0164 -229.1588) (xy 55.2704 -229.1588)
			)
		)
		(polygon
			(pts
				(xy 41.833546 -224.564702) (xy 41.579546 -224.564702) (xy 41.579546 -224.818702) (xy 41.833546 -224.818702)
			)
		)
		(polygon
			(pts
				(xy 40.969946 -224.564702) (xy 40.715946 -224.564702) (xy 40.715946 -224.818702) (xy 40.969946 -224.818702)
			)
		)
		(polygon
			(pts
				(xy 41.960546 -216.055702) (xy 41.706546 -216.055702) (xy 41.706546 -216.309702) (xy 41.960546 -216.309702)
			)
		)
		(polygon
			(pts
				(xy 41.096946 -216.055702) (xy 40.842946 -216.055702) (xy 40.842946 -216.309702) (xy 41.096946 -216.309702)
			)
		)
		(polygon
			(pts
				(arc
					(start 52.145692 -209.61985)
					(mid 52.102017 -209.536634)
					(end 52.008786 -209.524854)
				)
				(arc
					(start 52.008786 -209.524854)
					(mid 51.93894 -209.544032)
					(end 51.8668 -209.550508)
				)
				(xy 51.839622 -209.550508) (xy 51.544982 -209.844894) (xy 51.549554 -209.844894) (xy 51.549554 -211.022692)
				(xy 52.145692 -211.022692)
			)
		)
		(polygon
			(pts
				(xy 55.245 -205.105) (xy 50.8 -205.105) (xy 50.419 -205.486) (xy 50.8 -205.867) (xy 50.8 -207.391)
				(xy 51.308 -207.899) (xy 54.229 -207.899) (xy 55.753 -206.375) (xy 55.753 -205.613)
			)
		)
		(polygon
			(pts
				(xy 55.066946 -192.7987) (xy 54.812946 -192.7987) (xy 54.812946 -193.0527) (xy 55.066946 -193.0527)
			)
		)
		(polygon
			(pts
				(xy 54.203346 -192.7987) (xy 53.949346 -192.7987) (xy 53.949346 -193.0527) (xy 54.203346 -193.0527)
			)
		)
		(polygon
			(pts
				(xy 219.734384 -189.885828) (xy 219.480384 -189.885828) (xy 219.480384 -190.139828) (xy 219.734384 -190.139828)
			)
		)
		(polygon
			(pts
				(xy 218.870784 -189.885828) (xy 218.616784 -189.885828) (xy 218.616784 -190.139828) (xy 218.870784 -190.139828)
			)
		)
		(polygon
			(pts
				(xy 78.917546 -183.6547) (xy 78.663546 -183.6547) (xy 78.663546 -183.9087) (xy 78.917546 -183.9087)
			)
		)
		(polygon
			(pts
				(xy 78.307946 -183.6547) (xy 78.053946 -183.6547) (xy 78.053946 -183.9087) (xy 78.307946 -183.9087)
			)
		)
		(polygon
			(pts
				(xy 205.5622 -174.117) (xy 205.3082 -174.117) (xy 205.3082 -174.371) (xy 205.5622 -174.371)
			)
		)
		(polygon
			(pts
				(xy 224.789746 -172.9867) (xy 212.597746 -172.9867) (xy 211.454746 -174.1297) (xy 211.454746 -175.3997)
				(xy 211.200746 -175.6537) (xy 206.882746 -175.6537) (xy 206.374746 -175.1457) (xy 191.007746 -175.1457)
				(xy 188.594746 -177.5587) (xy 188.594746 -188.6077) (xy 191.128396 -191.141604) (xy 191.008 -191.262)
				(xy 191.008 -193.929) (xy 191.262 -194.183) (xy 194.944746 -194.183) (xy 194.944746 -194.1957) (xy 195.706746 -194.9577)
				(xy 199.389746 -194.9577) (xy 199.897746 -194.4497) (xy 199.897746 -189.3697) (xy 197.738746 -187.2107)
				(xy 197.738746 -185.9407) (xy 199.135746 -184.5437) (xy 199.516746 -184.5437) (xy 200.405746 -185.4327)
				(xy 200.405746 -187.3377) (xy 200.786746 -187.7187) (xy 200.786746 -193.0527) (xy 201.548746 -193.8147)
				(xy 209.422746 -193.8147) (xy 209.930746 -193.3067) (xy 209.930746 -189.1157) (xy 210.057746 -188.9887)
				(xy 223.138746 -188.9887) (xy 224.916746 -187.2107) (xy 224.916746 -183.4007) (xy 224.662746 -183.1467)
				(xy 220.852746 -183.1467) (xy 220.725746 -183.0197) (xy 220.725746 -182.3847) (xy 220.852746 -182.2577)
				(xy 224.789746 -182.2577) (xy 224.916746 -182.1307) (xy 224.916746 -180.8607) (xy 224.789746 -180.7337)
				(xy 220.852746 -180.7337) (xy 220.725746 -180.6067) (xy 220.725746 -179.9717) (xy 220.852746 -179.8447)
				(xy 224.662746 -179.8447) (xy 224.916746 -179.5907) (xy 224.916746 -175.9077) (xy 224.662746 -175.6537)
				(xy 220.979746 -175.6537) (xy 220.725746 -175.3997) (xy 220.725746 -174.7647) (xy 220.979746 -174.5107)
				(xy 224.789746 -174.5107) (xy 225.043746 -174.2567) (xy 225.043746 -173.2407)
			)
		)
		(polygon
			(pts
				(xy 218.159584 -171.928028) (xy 217.905584 -171.928028) (xy 217.905584 -172.182028) (xy 218.159584 -172.182028)
			)
		)
		(polygon
			(pts
				(arc
					(start 13.207492 -157.29331)
					(mid 13.144856 -157.199478)
					(end 13.034264 -157.221428)
				)
				(xy 11.428222 -158.82747)
				(arc
					(start 11.430508 -158.851092)
					(mid 11.209356 -159.364089)
					(end 10.658602 -159.45739)
				)
				(arc
					(start 10.658602 -159.45739)
					(mid 10.621531 -159.458981)
					(end 10.595356 -159.48533)
				)
				(arc
					(start 10.595356 -159.48533)
					(mid 10.259815 -159.802841)
					(end 9.798558 -159.777684)
				)
				(arc
					(start 9.798558 -159.777684)
					(mid 9.704249 -159.779721)
					(end 9.652254 -159.858456)
				)
				(arc
					(start 9.652254 -160.30956)
					(mid 9.68379 -160.373459)
					(end 9.749536 -160.401)
				)
				(arc
					(start 9.749536 -160.401)
					(mid 10.045564 -160.494104)
					(end 10.252202 -160.725612)
				)
				(arc
					(start 10.252202 -160.725612)
					(mid 10.279791 -160.750531)
					(end 10.316972 -160.749996)
				)
				(arc
					(start 10.356596 -160.735264)
					(mid 10.415418 -160.684471)
					(end 10.421112 -160.606994)
				)
				(arc
					(start 10.421112 -160.606994)
					(mid 10.783802 -159.796075)
					(end 11.626088 -160.078928)
				)
				(arc
					(start 11.626088 -160.078928)
					(mid 11.655876 -160.102951)
					(end 11.693906 -160.099248)
				)
				(arc
					(start 11.693906 -160.099248)
					(mid 12.202218 -160.084193)
					(end 12.530074 -160.472882)
				)
				(arc
					(start 12.530074 -160.472882)
					(mid 12.601555 -160.545591)
					(end 12.700254 -160.519618)
				)
				(xy 12.919964 -160.299908)
				(arc
					(start 12.914884 -160.273238)
					(mid 12.951123 -159.898726)
					(end 13.185902 -159.60471)
				)
				(xy 13.207492 -159.58947)
			)
		)
		(polygon
			(pts
				(arc
					(start 9.825228 -151.51481)
					(mid 9.719194 -151.490944)
					(end 9.652254 -151.576532)
				)
				(arc
					(start 9.652254 -154.748992)
					(mid 10.145556 -155.020594)
					(end 10.180828 -155.58262)
				)
				(arc
					(start 10.180828 -155.58262)
					(mid 10.179443 -155.665899)
					(end 10.240772 -155.72232)
				)
				(arc
					(start 10.240772 -155.72232)
					(mid 10.39556 -155.797209)
					(end 10.52576 -155.909518)
				)
				(arc
					(start 10.52576 -155.909518)
					(mid 10.58801 -155.942677)
					(end 10.656824 -155.927298)
				)
				(arc
					(start 10.656824 -155.927298)
					(mid 10.616897 -155.985475)
					(end 10.624566 -156.055568)
				)
				(arc
					(start 10.624566 -156.055568)
					(mid 10.667775 -156.16651)
					(end 10.690352 -156.283406)
				)
				(arc
					(start 10.690352 -156.283406)
					(mid 10.722073 -156.347478)
					(end 10.788142 -156.374846)
				)
				(arc
					(start 10.788142 -156.374846)
					(mid 10.827829 -156.384439)
					(end 10.860532 -156.408882)
				)
				(arc
					(start 10.860532 -156.408882)
					(mid 10.756562 -156.378735)
					(end 10.68451 -156.459428)
				)
				(arc
					(start 10.68451 -156.459428)
					(mid 10.357991 -156.925072)
					(end 9.790684 -156.964634)
				)
				(arc
					(start 9.790684 -156.964634)
					(mid 9.700489 -156.972356)
					(end 9.652254 -157.048962)
				)
				(arc
					(start 9.652254 -157.96006)
					(mid 9.686614 -158.026513)
					(end 9.757156 -158.0515)
				)
				(arc
					(start 9.757156 -158.0515)
					(mid 10.176292 -158.207083)
					(end 10.362946 -158.613348)
				)
				(arc
					(start 10.362946 -158.613348)
					(mid 10.377803 -158.647513)
					(end 10.411968 -158.66237)
				)
				(xy 10.442702 -158.664148) (xy 10.466324 -158.666434) (xy 10.598912 -158.533592) (xy 11.175238 -158.533592)
				(arc
					(start 11.175238 -158.2039)
					(mid 11.190223 -158.094743)
					(end 11.233912 -157.993588)
				)
				(xy 11.254486 -157.959552) (xy 10.997438 -157.702758)
				(arc
					(start 10.997438 -157.291024)
					(mid 11.060275 -157.384685)
					(end 11.17092 -157.362652)
				)
				(xy 12.124436 -156.408882) (xy 12.223496 -156.309822)
				(arc
					(start 12.223496 -155.955746)
					(mid 12.192379 -155.882824)
					(end 12.11834 -155.8544)
				)
				(arc
					(start 12.11834 -155.8544)
					(mid 11.62158 -155.610372)
					(end 11.550904 -155.061412)
				)
				(arc
					(start 11.550904 -155.061412)
					(mid 11.545615 -154.977171)
					(end 11.478514 -154.92603)
				)
				(arc
					(start 11.478514 -154.92603)
					(mid 11.362496 -154.886371)
					(end 11.25728 -154.823414)
				)
				(arc
					(start 11.25728 -154.823414)
					(mid 11.219616 -154.813765)
					(end 11.18616 -154.833574)
				)
				(arc
					(start 11.18616 -154.833574)
					(mid 11.12005 -154.907397)
					(end 11.042396 -154.968956)
				)
				(arc
					(start 11.042396 -154.968956)
					(mid 11.021105 -154.999315)
					(end 11.02614 -155.036012)
				)
				(arc
					(start 11.02614 -155.036012)
					(mid 11.060109 -155.534023)
					(end 10.69721 -155.876752)
				)
				(arc
					(start 10.701782 -155.858972)
					(mid 10.795189 -155.615041)
					(end 10.975848 -155.42641)
				)
				(xy 10.997438 -155.41117) (xy 10.997438 -152.687274)
			)
		)
		(polygon
			(pts
				(arc
					(start 9.825228 -149.53361)
					(mid 9.719194 -149.509744)
					(end 9.652254 -149.595332)
				)
				(xy 9.652254 -149.74443)
				(arc
					(start 11.81735 -151.909526)
					(mid 11.924227 -151.933087)
					(end 11.990578 -151.846026)
				)
				(arc
					(start 11.990578 -151.846026)
					(mid 11.99634 -151.796487)
					(end 12.005564 -151.747474)
				)
				(xy 12.011914 -151.720296)
			)
		)
		(polygon
			(pts
				(xy 226.006914 -144.919192) (xy 225.795078 -144.919192)
				(arc
					(start 225.791014 -144.965166)
					(mid 225.66005 -145.228423)
					(end 225.385884 -145.334736)
				)
				(arc
					(start 225.030284 -145.334736)
					(mid 224.990723 -145.332709)
					(end 224.951544 -145.326862)
				)
				(xy 224.946718 -145.325846) (xy 224.890838 -145.325846) (xy 224.890838 -145.460212) (xy 229.36073 -145.460212)
				(xy 229.36073 -145.28292)
				(arc
					(start 229.359206 -145.277078)
					(mid 229.350793 -145.229784)
					(end 229.34803 -145.181828)
				)
				(xy 229.34803 -144.919192) (xy 228.99243 -144.919192) (xy 228.99243 -145.173192) (xy 226.006914 -145.173192)
			)
		)
		(polygon
			(pts
				(xy 41.00703 -144.919192) (xy 40.762936 -144.919192) (xy 40.632634 -145.04924)
				(arc
					(start 40.629332 -145.06321)
					(mid 40.486088 -145.289305)
					(end 40.233346 -145.377408)
				)
				(arc
					(start 39.877746 -145.377408)
					(mid 39.849609 -145.376346)
					(end 39.821612 -145.373344)
				)
				(xy 39.818056 -145.372836) (xy 39.763954 -145.372836) (xy 39.763954 -145.452338) (xy 39.980108 -145.668492)
				(xy 43.699684 -145.668492) (xy 44.331382 -145.036794) (xy 44.334684 -145.023332) (xy 44.34586 -144.986756)
				(xy 44.348654 -144.978628) (xy 44.348654 -144.919192) (xy 43.992546 -144.919192) (xy 43.992546 -145.173192)
				(xy 41.00703 -145.173192)
			)
		)
		(polygon
			(pts
				(xy 223.77273 -144.293336) (xy 223.063054 -144.293336) (xy 223.063054 -145.217896) (xy 223.305116 -145.460212)
				(xy 223.669098 -145.460212) (xy 223.77273 -145.35658) (xy 223.77273 -145.02892)
				(arc
					(start 223.771206 -145.023078)
					(mid 223.762793 -144.975784)
					(end 223.76003 -144.927828)
				)
				(arc
					(start 223.76003 -144.572228)
					(mid 223.762807 -144.524274)
					(end 223.771206 -144.476978)
				)
				(xy 223.77273 -144.471136)
			)
		)
		(polygon
			(pts
				(xy 235.1024 -141.8336) (xy 230.886 -141.8336) (xy 230.886 -143.891) (xy 235.1024 -143.891)
			)
		)
		(polygon
			(pts
				(arc
					(start 40.793924 -141.866112)
					(mid 40.709075 -141.811076)
					(end 40.618664 -141.85646)
				)
				(arc
					(start 40.618664 -141.85646)
					(mid 40.540625 -141.952867)
					(end 40.445944 -142.03299)
				)
				(xy 40.424354 -142.04823) (xy 40.424354 -142.222474)
				(arc
					(start 40.44823 -142.23746)
					(mid 40.589045 -142.38528)
					(end 40.640254 -142.5829)
				)
				(arc
					(start 40.640254 -142.9385)
					(mid 40.615035 -143.079269)
					(end 40.542718 -143.20266)
				)
				(arc
					(start 40.542718 -143.20266)
					(mid 40.518329 -143.2687)
					(end 40.542718 -143.33474)
				)
				(arc
					(start 40.542718 -143.33474)
					(mid 40.557351 -143.352874)
					(end 40.570912 -143.371824)
				)
				(xy 40.585898 -143.394176) (xy 41.00703 -143.394176) (xy 41.00703 -143.140176) (xy 42.04843 -143.140176)
				(xy 42.04843 -142.928594)
				(arc
					(start 42.027856 -142.913354)
					(mid 41.817452 -142.656192)
					(end 41.75887 -142.329154)
				)
				(arc
					(start 41.75887 -142.329154)
					(mid 41.721416 -142.242497)
					(end 41.628822 -142.223998)
				)
				(arc
					(start 41.628822 -142.223998)
					(mid 41.146809 -142.195631)
					(end 40.793924 -141.866112)
				)
			)
		)
		(polygon
			(pts
				(xy 49.021746 -141.7447) (xy 46.227746 -141.7447) (xy 45.211746 -142.7607) (xy 45.211746 -143.3957)
				(xy 45.592746 -143.7767) (xy 48.767746 -143.7767) (xy 49.529746 -143.0147) (xy 49.529746 -142.2527)
			)
		)
		(polygon
			(pts
				(arc
					(start 233.790236 -140.962634)
					(mid 233.825345 -140.849447)
					(end 233.729276 -140.780008)
				)
				(arc
					(start 230.836216 -140.780008)
					(mid 230.7401 -140.849431)
					(end 230.775256 -140.962634)
				)
				(arc
					(start 230.775256 -140.962634)
					(mid 230.992948 -141.249051)
					(end 231.02824 -141.607032)
				)
				(xy 231.023668 -141.633194)
				(arc
					(start 231.06761 -141.677136)
					(mid 231.178155 -141.698972)
					(end 231.240838 -141.605254)
				)
				(arc
					(start 231.240838 -141.5034)
					(mid 231.360019 -141.215673)
					(end 231.647746 -141.096492)
				)
				(arc
					(start 232.003346 -141.096492)
					(mid 232.13792 -141.119479)
					(end 232.257346 -141.185646)
				)
				(arc
					(start 232.257346 -141.185646)
					(mid 232.376756 -141.119434)
					(end 232.511346 -141.096492)
				)
				(arc
					(start 232.866946 -141.096492)
					(mid 232.949987 -141.105109)
					(end 233.029506 -141.130528)
				)
				(xy 233.039158 -141.134592) (xy 233.630216 -141.134592)
				(arc
					(start 233.645456 -141.113002)
					(mid 233.711868 -141.032062)
					(end 233.790236 -140.962634)
				)
			)
		)
		(polygon
			(pts
				(arc
					(start 228.861366 -140.934186)
					(mid 228.862955 -140.83175)
					(end 228.774498 -140.780008)
				)
				(xy 225.656394 -140.780008) (xy 225.539554 -140.896848)
				(arc
					(start 225.539554 -141.694916)
					(mid 225.571965 -141.769316)
					(end 225.64852 -141.796262)
				)
				(xy 225.678746 -141.794992)
				(arc
					(start 225.834194 -141.794992)
					(mid 225.743036 -141.852248)
					(end 225.754438 -141.95933)
				)
				(arc
					(start 225.754438 -141.95933)
					(mid 225.887842 -142.465018)
					(end 225.611944 -142.90929)
				)
				(xy 225.5901 -142.92453) (xy 225.5901 -142.984474)
				(arc
					(start 225.61423 -142.99946)
					(mid 225.754876 -143.147338)
					(end 225.806 -143.3449)
				)
				(xy 225.806 -143.397732) (xy 226.007168 -143.397732) (xy 226.007168 -143.143478) (xy 226.225354 -143.143478)
				(xy 226.225354 -143.140176) (xy 227.583746 -143.140176) (xy 227.583746 -144.5387) (xy 227.837746 -144.7927)
				(xy 229.742746 -144.7927) (xy 230.377746 -144.1577) (xy 230.377746 -142.6337) (xy 229.869746 -142.1257)
				(xy 229.747318 -142.1257) (xy 229.438454 -141.816836)
				(arc
					(start 229.414832 -141.819122)
					(mid 228.865918 -141.546842)
					(end 228.861366 -140.934186)
				)
			)
		)
		(polygon
			(pts
				(xy 46.659546 -133.4897) (xy 46.405546 -133.4897) (xy 46.405546 -133.7437) (xy 46.659546 -133.7437)
			)
		)
		(polygon
			(pts
				(xy 54.2798 -129.032) (xy 54.0258 -129.032) (xy 54.0258 -129.286) (xy 54.2798 -129.286)
			)
		)
		(polygon
			(pts
				(xy 53.6702 -129.032) (xy 53.4162 -129.032) (xy 53.4162 -129.286) (xy 53.6702 -129.286)
			)
		)
		(polygon
			(pts
				(xy 49.8348 -127.889) (xy 49.5808 -127.889) (xy 49.5808 -128.143) (xy 49.8348 -128.143)
			)
		)
		(polygon
			(pts
				(xy 49.2252 -127.889) (xy 48.9712 -127.889) (xy 48.9712 -128.143) (xy 49.2252 -128.143)
			)
		)
		(polygon
			(pts
				(xy 10.6934 -103.4542) (xy 10.4394 -103.4542) (xy 10.4394 -103.7082) (xy 10.6934 -103.7082)
			)
		)
		(polygon
			(pts
				(xy 82.296 -92.964) (xy 80.391 -92.964) (xy 79.121 -94.234) (xy 79.121 -94.869) (xy 78.994 -94.996)
				(xy 79.121 -94.996) (xy 79.629 -95.504) (xy 79.629 -97.155) (xy 79.756 -97.282) (xy 83.566 -97.282)
				(xy 83.693 -97.155) (xy 83.693 -95.504) (xy 82.677 -94.488) (xy 82.677 -93.345)
			)
		)
		(polygon
			(pts
				(xy 54.812692 -89.436956) (xy 54.558692 -89.436956) (xy 54.558692 -89.690956) (xy 54.812692 -89.690956)
			)
		)
		(polygon
			(pts
				(xy 53.949092 -89.436956) (xy 53.695092 -89.436956) (xy 53.695092 -89.690956) (xy 53.949092 -89.690956)
			)
		)
		(polygon
			(pts
				(xy 83.6168 -88.773) (xy 83.3628 -88.773) (xy 83.3628 -89.027) (xy 83.6168 -89.027)
			)
		)
		(polygon
			(pts
				(xy 220.2434 -87.9094) (xy 219.9894 -87.9094) (xy 219.9894 -88.1634) (xy 220.2434 -88.1634)
			)
		)
		(polygon
			(pts
				(xy 219.3798 -87.9094) (xy 219.1258 -87.9094) (xy 219.1258 -88.1634) (xy 219.3798 -88.1634)
			)
		)
		(polygon
			(pts
				(xy 85.038692 -85.220556) (xy 84.784692 -85.220556) (xy 84.784692 -85.474556) (xy 85.038692 -85.474556)
			)
		)
		(polygon
			(pts
				(xy 85.038692 -84.763356) (xy 84.784692 -84.763356) (xy 84.784692 -85.017356) (xy 85.038692 -85.017356)
			)
		)
		(polygon
			(pts
				(xy 85.038692 -84.204556) (xy 84.784692 -84.204556) (xy 84.784692 -84.458556) (xy 85.038692 -84.458556)
			)
		)
		(polygon
			(pts
				(xy 79.883 -81.7372) (xy 79.629 -81.7372) (xy 79.629 -81.9912) (xy 79.883 -81.9912)
			)
		)
		(polygon
			(pts
				(xy 79.2734 -81.7372) (xy 79.0194 -81.7372) (xy 79.0194 -81.9912) (xy 79.2734 -81.9912)
			)
		)
		(polygon
			(pts
				(xy 79.883 -80.2132) (xy 79.629 -80.2132) (xy 79.629 -80.4672) (xy 79.883 -80.4672)
			)
		)
		(polygon
			(pts
				(xy 79.2734 -80.2132) (xy 79.0194 -80.2132) (xy 79.0194 -80.4672) (xy 79.2734 -80.4672)
			)
		)
		(polygon
			(pts
				(xy 194.6148 -76.962) (xy 194.3608 -76.962) (xy 194.3608 -77.216) (xy 194.6148 -77.216)
			)
		)
		(polygon
			(pts
				(xy 194.0052 -76.962) (xy 193.7512 -76.962) (xy 193.7512 -77.216) (xy 194.0052 -77.216)
			)
		)
		(polygon
			(pts
				(xy 198.546212 -76.942696) (xy 198.292212 -76.942696) (xy 198.292212 -77.196696) (xy 198.546212 -77.196696)
			)
		)
		(polygon
			(pts
				(xy 197.936612 -76.942696) (xy 197.682612 -76.942696) (xy 197.682612 -77.196696) (xy 197.936612 -77.196696)
			)
		)
		(polygon
			(pts
				(xy 207.2132 -71.374) (xy 206.9592 -71.374) (xy 206.9592 -71.628) (xy 207.2132 -71.628)
			)
		)
		(polygon
			(pts
				(xy 218.485212 -70.084696) (xy 218.231212 -70.084696) (xy 218.231212 -70.338696) (xy 218.485212 -70.338696)
			)
		)
		(polygon
			(pts
				(xy 56.4769 -69.9897) (xy 36.448746 -69.9897) (xy 36.194746 -70.2437) (xy 36.194746 -85.7377) (xy 36.448746 -85.9917)
				(xy 40.766746 -85.9917) (xy 40.766746 -86.1187) (xy 43.179746 -88.5317) (xy 61.2013 -88.5317) (xy 61.3156 -88.646)
				(xy 61.3156 -92.443554) (xy 62.991746 -94.1197) (xy 63.626746 -94.7547) (xy 71.373746 -94.7547)
				(xy 72.135746 -93.9927) (xy 77.977746 -93.9927) (xy 78.578202 -93.392244) (xy 78.636114 -93.450156)
				(arc
					(start 78.665832 -93.440504)
					(mid 78.727541 -93.425703)
					(end 78.7908 -93.420692)
				)
				(arc
					(start 79.1972 -93.420692)
					(mid 79.364898 -93.45697)
					(end 79.502762 -93.559122)
				)
				(arc
					(start 79.502762 -93.559122)
					(mid 79.536818 -93.576184)
					(end 79.57312 -93.56471)
				)
				(arc
					(start 79.57312 -93.56471)
					(mid 79.606013 -93.540267)
					(end 79.641192 -93.519244)
				)
				(arc
					(start 79.641192 -93.297756)
					(mid 79.483411 -93.148131)
					(end 79.425292 -92.9386)
				)
				(arc
					(start 79.425292 -92.583)
					(mid 79.502616 -92.344444)
					(end 79.7052 -92.196666)
				)
				(xy 79.739998 -92.184982) (xy 79.739998 -91.732608) (xy 79.363824 -91.732608)
				(arc
					(start 79.351886 -91.76639)
					(mid 79.20316 -91.962812)
					(end 78.968346 -92.037408)
				)
				(xy 78.866746 -92.037408) (xy 78.866746 -86.787482)
				(arc
					(start 78.88097 -86.802214)
					(mid 78.912658 -86.839566)
					(end 78.939644 -86.880446)
				)
				(xy 78.954122 -86.905592) (xy 79.021178 -86.905592) (xy 79.337154 -87.221822)
				(arc
					(start 79.363316 -87.21725)
					(mid 79.539828 -87.209608)
					(end 79.712058 -87.249)
				)
				(xy 79.742538 -87.26043) (xy 79.80172 -87.201502) (xy 79.716884 -87.11692) (xy 79.716884 -86.658704)
				(xy 79.158084 -86.658704) (xy 79.158084 -86.506304) (xy 78.93685 -86.506304)
				(arc
					(start 78.921864 -86.528148)
					(mid 78.902412 -86.553981)
					(end 78.88097 -86.578186)
				)
				(xy 78.866746 -86.592918) (xy 78.866746 -81.2927) (xy 78.358746 -80.7847) (xy 75.564746 -80.7847)
				(xy 75.183746 -80.4037) (xy 75.183746 -72.4027) (xy 61.721746 -72.4027) (xy 60.546996 -71.228204)
				(xy 57.715404 -71.228204)
			)
		)
		(polygon
			(pts
				(xy 226.567746 -60.3377) (xy 223.773746 -60.3377) (xy 223.646746 -60.4647) (xy 223.138746 -60.4647)
				(xy 222.503746 -61.0997) (xy 222.503746 -62.7507) (xy 222.262446 -62.992) (xy 215.011 -62.992) (xy 214.63 -63.373)
				(xy 214.63 -63.512446) (xy 214.629746 -63.5127) (xy 214.629746 -64.2747) (xy 215.264746 -64.9097)
				(xy 226.567746 -64.9097) (xy 226.948746 -64.5287) (xy 226.948746 -64.516254) (xy 226.949 -64.516)
				(xy 226.949 -63.373) (xy 226.948746 -63.372746) (xy 226.948746 -60.7187)
			)
		)
		(polygon
			(pts
				(xy 211.9376 -53.1876) (xy 210.5152 -53.1876) (xy 210.5152 -54.5592) (xy 211.9376 -54.5592)
			)
		)
		(polygon
			(pts
				(xy 213.613746 -42.7355) (xy 213.359746 -42.7355) (xy 213.359746 -42.9895) (xy 213.613746 -42.9895)
			)
		)
		(polygon
			(pts
				(xy 206.425546 -42.5831) (xy 206.171546 -42.5831) (xy 206.171546 -42.8371) (xy 206.425546 -42.8371)
			)
		)
		(polygon
			(pts
				(xy 213.613746 -42.1259) (xy 213.359746 -42.1259) (xy 213.359746 -42.3799) (xy 213.613746 -42.3799)
			)
		)
		(polygon
			(pts
				(xy 206.425546 -42.0243) (xy 206.171546 -42.0243) (xy 206.171546 -42.2783) (xy 206.425546 -42.2783)
			)
		)
		(polygon
			(pts
				(xy 237.145322 -40.615108) (xy 237.043722 -40.615108)
				(arc
					(start 237.029244 -40.640254)
					(mid 236.96929 -40.719718)
					(end 236.89183 -40.78224)
				)
				(arc
					(start 236.89183 -40.78224)
					(mid 236.844467 -40.856849)
					(end 236.873542 -40.940228)
				)
				(arc
					(start 236.873542 -40.940228)
					(mid 236.859914 -40.923319)
					(end 236.850174 -40.903906)
				)
				(arc
					(start 236.850174 -40.903906)
					(mid 236.806392 -40.851633)
					(end 236.73943 -40.838882)
				)
				(arc
					(start 236.73943 -40.838882)
					(mid 236.708281 -40.8425)
					(end 236.676946 -40.843708)
				)
				(arc
					(start 236.321346 -40.843708)
					(mid 236.186772 -40.820721)
					(end 236.067346 -40.754554)
				)
				(arc
					(start 236.067346 -40.754554)
					(mid 236.011736 -40.791875)
					(end 235.95076 -40.819578)
				)
				(arc
					(start 235.95076 -40.819578)
					(mid 235.886069 -40.891923)
					(end 235.911644 -40.98544)
				)
				(xy 235.769912 -40.843708) (xy 235.554266 -40.843708) (xy 235.554266 -41.22547)
				(arc
					(start 235.578396 -41.240456)
					(mid 235.719042 -41.388334)
					(end 235.770166 -41.585896)
				)
				(xy 235.770166 -41.909492)
				(arc
					(start 236.59084 -41.909492)
					(mid 236.684672 -41.846856)
					(end 236.662722 -41.736264)
				)
				(arc
					(start 236.662722 -41.736264)
					(mid 236.68471 -41.769126)
					(end 236.69244 -41.807892)
				)
				(arc
					(start 236.69244 -41.808146)
					(mid 236.722198 -41.879734)
					(end 236.793786 -41.909492)
				)
				(xy 237.617254 -41.909492) (xy 237.617254 -42.239692) (xy 237.768638 -42.239692)
				(arc
					(start 237.768638 -41.793414)
					(mid 237.739506 -41.722203)
					(end 237.668816 -41.691814)
				)
				(arc
					(start 237.668816 -41.691814)
					(mid 237.739679 -41.661523)
					(end 237.768892 -41.590214)
				)
				(xy 237.768892 -41.585896) (xy 237.768638 -41.240456) (xy 237.768638 -41.238424)
			)
		)
		(polygon
			(pts
				(xy 211.607146 -40.0685) (xy 211.353146 -40.0685) (xy 211.353146 -40.3225) (xy 211.607146 -40.3225)
			)
		)
		(polygon
			(pts
				(xy 211.048346 -40.0685) (xy 210.794346 -40.0685) (xy 210.794346 -40.3225) (xy 211.048346 -40.3225)
			)
		)
		(polygon
			(pts
				(xy 209.702146 -40.0685) (xy 209.448146 -40.0685) (xy 209.448146 -40.3225) (xy 209.702146 -40.3225)
			)
		)
		(polygon
			(pts
				(xy 209.143346 -40.0685) (xy 208.889346 -40.0685) (xy 208.889346 -40.3225) (xy 209.143346 -40.3225)
			)
		)
		(polygon
			(pts
				(xy 207.797146 -40.0685) (xy 207.543146 -40.0685) (xy 207.543146 -40.3225) (xy 207.797146 -40.3225)
			)
		)
		(polygon
			(pts
				(xy 207.238346 -40.0685) (xy 206.984346 -40.0685) (xy 206.984346 -40.3225) (xy 207.238346 -40.3225)
			)
		)
		(polygon
			(pts
				(xy 44.576746 -39.2557) (xy 43.433746 -39.2557) (xy 43.179746 -39.5097) (xy 43.179746 -40.5257)
				(xy 43.560746 -40.9067) (xy 44.576746 -40.9067) (xy 44.957746 -40.5257) (xy 44.957746 -39.6367)
			)
		)
		(polygon
			(pts
				(xy 48.132746 -38.1127) (xy 47.497746 -38.1127) (xy 45.973746 -39.6367) (xy 45.973746 -39.8907)
				(xy 46.227746 -40.1447) (xy 48.513746 -40.1447) (xy 48.894746 -39.7637) (xy 48.894746 -39.274496)
				(arc
					(start 48.93056 -39.274496)
					(mid 49.024426 -39.211777)
					(end 49.002442 -39.101014)
				)
				(xy 48.894746 -38.993318) (xy 48.894746 -38.8747)
			)
		)
		(polygon
			(pts
				(xy 229.361746 -31.8135) (xy 229.107746 -31.8135) (xy 229.107746 -32.0675) (xy 229.082346 -32.1945)
				(xy 229.082346 -32.4485) (xy 229.336346 -32.4485) (xy 229.336346 -32.1945) (xy 229.361746 -32.0675)
			)
		)
		(polygon
			(pts
				(arc
					(start 237.653322 -30.808422)
					(mid 237.664502 -30.752986)
					(end 237.617508 -30.721554)
				)
				(xy 237.533688 -30.721554)
				(arc
					(start 237.52683 -30.72384)
					(mid 237.362746 -30.74733)
					(end 237.198662 -30.72384)
				)
				(xy 237.191804 -30.721808)
				(arc
					(start 236.120686 -30.721808)
					(mid 236.040113 -30.761516)
					(end 236.022642 -30.84957)
				)
				(arc
					(start 236.022642 -30.84957)
					(mid 236.042067 -31.023436)
					(end 236.00918 -31.195264)
				)
				(arc
					(start 236.00918 -31.195264)
					(mid 236.022187 -31.287495)
					(end 236.104938 -31.330392)
				)
				(xy 237.131098 -31.330392)
			)
		)
		(polygon
			(pts
				(xy 228.093778 -29.7561) (xy 228.0158 -29.7561) (xy 228.0158 -29.857192) (xy 227.888292 -29.9847)
				(xy 228.853238 -30.949392) (xy 229.869238 -30.949392) (xy 230.017066 -31.097474)
				(arc
					(start 230.050594 -31.078424)
					(mid 230.147257 -31.039092)
					(end 230.250746 -31.025592)
				)
				(arc
					(start 230.657146 -31.025592)
					(mid 230.752934 -31.037089)
					(end 230.843328 -31.070804)
				)
				(xy 230.85425 -31.076392) (xy 231.222804 -31.076392) (xy 231.229662 -31.07436)
				(arc
					(start 231.271826 -31.063946)
					(mid 231.347918 -30.993376)
					(end 231.322372 -30.89275)
				)
				(xy 230.656892 -30.227016)
				(arc
					(start 230.656892 -30.060646)
					(mid 230.625313 -29.987028)
					(end 230.550212 -29.9593)
				)
				(xy 230.530146 -29.959808)
				(arc
					(start 229.869746 -29.959808)
					(mid 229.702538 -29.923751)
					(end 229.564946 -29.82214)
				)
				(arc
					(start 229.564946 -29.82214)
					(mid 229.488746 -29.787779)
					(end 229.412546 -29.82214)
				)
				(arc
					(start 229.412546 -29.82214)
					(mid 229.274941 -29.923722)
					(end 229.107746 -29.959808)
				)
				(arc
					(start 228.447346 -29.959808)
					(mid 228.255463 -29.911691)
					(end 228.109018 -29.778706)
				)
			)
		)
		(polygon
			(pts
				(arc
					(start 228.624892 -26.870914)
					(mid 228.613098 -26.777692)
					(end 228.529896 -26.734008)
				)
				(xy 228.0158 -26.734008)
				(arc
					(start 228.0158 -27.432508)
					(mid 228.058713 -27.515444)
					(end 228.151182 -27.528266)
				)
				(arc
					(start 228.151182 -27.528266)
					(mid 228.312695 -27.495953)
					(end 228.47681 -27.509978)
				)
				(arc
					(start 228.47681 -27.509978)
					(mid 228.566086 -27.487592)
					(end 228.600762 -27.402282)
				)
				(xy 228.599492 -27.3685)
				(arc
					(start 228.599492 -27.0129)
					(mid 228.605848 -26.940772)
					(end 228.624892 -26.870914)
				)
			)
		)
		(polygon
			(pts
				(arc
					(start 238.803434 -25.844246)
					(mid 238.74068 -25.750619)
					(end 238.630206 -25.772618)
				)
				(xy 238.176054 -26.22677) (xy 238.176054 -26.955242)
				(arc
					(start 238.207042 -26.96845)
					(mid 238.278745 -27.007647)
					(end 238.341154 -27.060398)
				)
				(xy 238.35614 -27.075892) (xy 238.401352 -27.075892)
				(arc
					(start 238.416338 -27.060398)
					(mid 238.55 -26.968503)
					(end 238.708946 -26.936192)
				)
				(xy 238.803434 -26.936192)
			)
		)
		(polygon
			(pts
				(xy 229.031546 -24.7523) (xy 228.777546 -24.7523) (xy 228.777546 -25.0063) (xy 229.031546 -25.0063)
			)
		)
		(polygon
			(pts
				(xy 242.950746 -24.5745) (xy 242.696746 -24.5745) (xy 242.696746 -24.8285) (xy 242.950746 -24.8285)
			)
		)
		(polygon
			(pts
				(arc
					(start 76.44384 -23.588472)
					(mid 76.347484 -23.59662)
					(end 76.3016 -23.68169)
				)
				(arc
					(start 76.3016 -23.803102)
					(mid 76.205643 -24.065559)
					(end 75.963018 -24.204168)
				)
				(xy 75.9206 -24.21128) (xy 75.9206 -24.313134)
				(arc
					(start 75.938888 -24.328374)
					(mid 76.118633 -24.96501)
					(end 75.589384 -25.3619)
				)
				(arc
					(start 75.589384 -25.3619)
					(mid 75.54468 -25.392687)
					(end 75.553316 -25.446228)
				)
				(arc
					(start 75.553316 -25.446228)
					(mid 75.577136 -25.474913)
					(end 75.59929 -25.504902)
				)
				(xy 75.61453 -25.526492) (xy 75.950826 -25.526492) (xy 76.307696 -25.169876)
				(arc
					(start 76.307696 -24.4348)
					(mid 76.389228 -24.158627)
					(end 76.60767 -23.970996)
				)
				(xy 76.637896 -23.957534)
				(arc
					(start 76.637896 -23.6728)
					(mid 76.623728 -23.637604)
					(end 76.589128 -23.622)
				)
				(arc
					(start 76.589128 -23.622)
					(mid 76.514935 -23.61195)
					(end 76.44384 -23.588472)
				)
			)
		)
		(polygon
			(pts
				(xy 74.243946 -23.015702) (xy 73.989946 -23.015702) (xy 73.989946 -23.269702) (xy 74.243946 -23.269702)
			)
		)
		(polygon
			(pts
				(xy 241.680746 -22.1869) (xy 241.426746 -22.1869) (xy 241.426746 -22.4409) (xy 241.680746 -22.4409)
			)
		)
		(polygon
			(pts
				(xy 82.484468 -21.196808) (xy 82.358992 -21.196808) (xy 82.155792 -21.399754)
				(arc
					(start 78.19517 -21.399754)
					(mid 78.148203 -21.431197)
					(end 78.159356 -21.486622)
				)
				(xy 78.22438 -21.551392) (xy 78.314804 -21.551392)
				(arc
					(start 78.321662 -21.54936)
					(mid 78.765132 -21.59692)
					(end 79.04607 -21.943314)
				)
				(xy 79.049626 -21.95576) (xy 80.039972 -22.945852) (xy 81.432908 -22.945852) (xy 81.432908 -23.748492)
				(xy 81.685892 -23.748492) (xy 81.685892 -22.945852)
				(arc
					(start 81.826608 -22.945852)
					(mid 81.905306 -22.908511)
					(end 81.926176 -22.823932)
				)
				(arc
					(start 81.926176 -22.823932)
					(mid 82.089336 -22.290586)
					(end 82.625438 -22.136608)
				)
				(arc
					(start 82.625438 -22.136608)
					(mid 82.736432 -22.086209)
					(end 82.719164 -21.965666)
				)
				(xy 82.484468 -21.73097)
			)
		)
		(polygon
			(pts
				(xy 229.133146 -21.1455) (xy 228.879146 -21.1455) (xy 228.879146 -21.3995) (xy 229.133146 -21.3995)
			)
		)
		(polygon
			(pts
				(xy 228.574346 -21.1455) (xy 228.320346 -21.1455) (xy 228.320346 -21.3995) (xy 228.574346 -21.3995)
			)
		)
		(polygon
			(pts
				(xy 231.063546 -21.0947) (xy 230.809546 -21.0947) (xy 230.809546 -21.3487) (xy 231.063546 -21.3487)
			)
		)
		(polygon
			(pts
				(xy 230.453946 -21.0947) (xy 229.920546 -21.0947) (xy 229.920546 -21.3487) (xy 230.453946 -21.3487)
			)
		)
		(polygon
			(pts
				(xy 229.564946 -21.0947) (xy 229.310946 -21.0947) (xy 229.310946 -21.3487) (xy 229.564946 -21.3487)
			)
		)
		(polygon
			(pts
				(xy 93.5228 -20.574) (xy 93.2688 -20.574) (xy 93.2688 -20.828) (xy 93.5228 -20.828)
			)
		)
		(polygon
			(pts
				(xy 92.9132 -20.574) (xy 92.6592 -20.574) (xy 92.6592 -20.828) (xy 92.9132 -20.828)
			)
		)
		(polygon
			(pts
				(xy 225.107754 -19.939508)
				(arc
					(start 224.81921 -19.939508)
					(mid 224.725378 -20.002144)
					(end 224.747328 -20.112736)
				)
				(arc
					(start 227.326444 -22.691598)
					(mid 227.409535 -22.720753)
					(end 227.484178 -22.674072)
				)
				(arc
					(start 227.484178 -22.674072)
					(mid 227.578231 -22.559676)
					(end 227.698046 -22.47265)
				)
				(xy 227.704396 -22.469094)
				(arc
					(start 227.901754 -22.271736)
					(mid 227.92359 -22.161191)
					(end 227.829872 -22.098508)
				)
				(xy 227.266754 -22.098508)
			)
		)
		(polygon
			(pts
				(xy 94.234 -19.4564) (xy 93.98 -19.4564) (xy 93.98 -19.7104) (xy 94.234 -19.7104)
			)
		)
		(polygon
			(pts
				(xy 93.6244 -19.4564) (xy 93.3704 -19.4564) (xy 93.3704 -19.7104) (xy 93.6244 -19.7104)
			)
		)
		(polygon
			(pts
				(xy 99.3648 -19.431) (xy 99.1108 -19.431) (xy 99.1108 -19.685) (xy 99.3648 -19.685)
			)
		)
		(polygon
			(pts
				(xy 98.7552 -19.431) (xy 98.5012 -19.431) (xy 98.5012 -19.685) (xy 98.7552 -19.685)
			)
		)
		(polygon
			(pts
				(arc
					(start 76.170282 -18.448782)
					(mid 76.059498 -18.426746)
					(end 75.9968 -18.520664)
				)
				(xy 75.9968 -19.527774) (xy 75.997054 -20.493228) (xy 75.997054 -21.094192) (xy 75.870054 -21.221192)
				(arc
					(start 75.870054 -21.26361)
					(mid 75.883868 -21.298433)
					(end 75.917806 -21.314156)
				)
				(arc
					(start 75.917806 -21.314156)
					(mid 76.086844 -21.361621)
					(end 76.220066 -21.475954)
				)
				(arc
					(start 76.220066 -21.475954)
					(mid 76.286978 -21.515573)
					(end 76.362306 -21.496274)
				)
				(arc
					(start 76.362306 -21.496274)
					(mid 76.477417 -21.436076)
					(end 76.605638 -21.415248)
				)
				(arc
					(start 76.728066 -21.415248)
					(mid 76.775033 -21.383805)
					(end 76.76388 -21.32838)
				)
				(xy 76.275438 -20.840192) (xy 76.275438 -18.554192)
			)
		)
		(polygon
			(pts
				(xy 80.390746 -18.062702) (xy 80.136746 -18.062702) (xy 80.136746 -18.316702) (xy 80.390746 -18.316702)
			)
		)
		(polygon
			(pts
				(xy 79.247746 -18.062702) (xy 78.993746 -18.062702) (xy 78.993746 -18.316702) (xy 79.247746 -18.316702)
			)
		)
		(polygon
			(pts
				(xy 94.234 -17.9324) (xy 93.98 -17.9324) (xy 93.98 -18.1864) (xy 94.234 -18.1864)
			)
		)
		(polygon
			(pts
				(xy 93.6244 -17.9324) (xy 93.3704 -17.9324) (xy 93.3704 -18.1864) (xy 93.6244 -18.1864)
			)
		)
		(polygon
			(pts
				(xy 99.3648 -17.907) (xy 99.1108 -17.907) (xy 99.1108 -18.161) (xy 99.3648 -18.161)
			)
		)
		(polygon
			(pts
				(xy 98.7552 -17.907) (xy 98.5012 -17.907) (xy 98.5012 -18.161) (xy 98.7552 -18.161)
			)
		)
		(polygon
			(pts
				(xy 78.866746 -15.1257) (xy 73.913746 -15.1257) (xy 73.024746 -16.0147) (xy 73.024746 -16.7767)
				(xy 78.866746 -16.7767)
			)
		)
		(polygon
			(pts
				(xy 95.173546 -14.6431) (xy 94.919546 -14.6431) (xy 94.919546 -14.8971) (xy 95.173546 -14.8971)
			)
		)
		(polygon
			(pts
				(xy 101.650546 -14.3891) (xy 101.396546 -14.3891) (xy 101.396546 -14.6431) (xy 101.650546 -14.6431)
			)
		)
		(polygon
			(pts
				(xy 75.234546 -13.744702) (xy 74.980546 -13.744702) (xy 74.980546 -13.998702) (xy 75.234546 -13.998702)
			)
		)
		(polygon
			(pts
				(xy 74.370946 -13.744702) (xy 74.116946 -13.744702) (xy 74.116946 -13.998702) (xy 74.370946 -13.998702)
			)
		)
		(polygon
			(pts
				(xy 93.726 -11.43) (xy 90.932 -11.43) (xy 90.297 -12.065) (xy 90.297 -14.986) (xy 90.805 -15.494)
				(xy 92.202 -15.494) (xy 94.996 -12.7)
			)
		)
		(polygon
			(pts
				(xy 80.390746 -9.553702) (xy 80.136746 -9.553702) (xy 80.136746 -9.807702) (xy 80.390746 -9.807702)
			)
		)
		(polygon
			(pts
				(xy 79.247746 -9.553702) (xy 78.993746 -9.553702) (xy 78.993746 -9.807702) (xy 79.247746 -9.807702)
			)
		)
		(polygon
			(pts
				(xy 94.499938 -8.827008) (xy 93.944948 -8.827008) (xy 93.777308 -8.994648)
				(arc
					(start 93.777308 -10.21715)
					(mid 93.820983 -10.300366)
					(end 93.914214 -10.312146)
				)
				(arc
					(start 93.914214 -10.312146)
					(mid 93.98406 -10.292968)
					(end 94.0562 -10.286492)
				)
				(xy 94.302326 -10.286492) (xy 94.59595 -9.993122) (xy 94.598998 -9.98982) (xy 94.590108 -10.001758)
				(arc
					(start 94.590108 -11.236706)
					(mid 94.615424 -11.280651)
					(end 94.666054 -11.280648)
				)
				(arc
					(start 94.666054 -11.280648)
					(mid 94.684479 -11.270645)
					(end 94.703392 -11.261598)
				)
				(xy 94.703392 -10.876026) (xy 94.766892 -10.812526)
				(arc
					(start 94.766892 -10.5664)
					(mid 94.886073 -10.278673)
					(end 95.1738 -10.159492)
				)
				(xy 95.419926 -10.159492)
				(arc
					(start 95.499682 -10.07999)
					(mid 95.521767 -9.969323)
					(end 95.428054 -9.906508)
				)
				(arc
					(start 94.661482 -9.906508)
					(mid 94.626104 -9.920852)
					(end 94.610682 -9.955784)
				)
				(arc
					(start 94.610682 -9.955784)
					(mid 94.595276 -9.920836)
					(end 94.559882 -9.906508)
				)
				(xy 94.499938 -9.906508)
			)
		)
		(polygon
			(pts
				(xy 97.205546 -7.9121) (xy 96.951546 -7.9121) (xy 96.951546 -8.1661) (xy 97.205546 -8.1661)
			)
		)
		(polygon
			(pts
				(xy 97.205546 -7.3533) (xy 96.951546 -7.3533) (xy 96.951546 -7.6073) (xy 97.205546 -7.6073)
			)
		)
		(polygon
			(pts
				(xy 97.205546 -6.7691) (xy 96.951546 -6.7691) (xy 96.951546 -7.0231) (xy 97.205546 -7.0231)
			)
		)
		(polygon
			(pts
				(xy 78.866746 -6.3627) (xy 73.405746 -6.3627) (xy 71.754746 -8.0137) (xy 71.754746 -11.5697) (xy 73.024746 -12.8397)
				(xy 78.866746 -12.8397)
			)
		)
		(polygon
			(pts
				(xy 97.205546 -6.2103) (xy 96.951546 -6.2103) (xy 96.951546 -6.4643) (xy 97.205546 -6.4643)
			)
		)
		(polygon
			(pts
				(xy 73.989946 -5.362702) (xy 73.735946 -5.362702) (xy 73.735946 -5.616702) (xy 73.989946 -5.616702)
			)
		)
		(polygon
			(pts
				(xy 73.126346 -5.362702) (xy 72.872346 -5.362702) (xy 72.872346 -5.616702) (xy 73.126346 -5.616702)
			)
		)
	)
	(zone
		(net "P12V_HDD4")
		(layer "F.Cu")
		(hatch none 0.5)
		(connect_pads
			(clearance 0.5)
		)
		(min_thickness 0.25)
		(fill yes
			(thermal_gap 0.5)
			(thermal_bridge_width 0.5)
			(island_removal_mode 0)
		)
		(polygon
			(pts
				(xy 204.977746 -81.0387) (xy 204.342746 -81.6737) (xy 204.342746 -85.6234) (xy 203.593446 -86.3727)
				(xy 201.675746 -86.3727) (xy 201.167746 -86.8807) (xy 201.167746 -92.2147) (xy 201.802746 -92.8497)
				(xy 211.6709 -92.8497) (xy 212.2678 -92.2528) (xy 212.2678 -86.8934) (xy 212.5345 -86.6267) (xy 221.741746 -86.6267)
				(xy 224.408746 -83.9597) (xy 224.408746 -82.0547) (xy 224.281746 -81.9277) (xy 222.122746 -81.9277)
				(xy 219.709746 -84.3407) (xy 216.915746 -84.3407) (xy 216.407746 -83.8327) (xy 216.407746 -81.6737)
				(xy 215.772746 -81.0387)
			)
		)
		(polygon
			(pts
				(xy 220.2434 -85.6234) (xy 219.9894 -85.6234) (xy 219.9894 -85.8774) (xy 220.2434 -85.8774)
			)
		)
		(polygon
			(pts
				(xy 219.3798 -85.6234) (xy 219.1258 -85.6234) (xy 219.1258 -85.8774) (xy 219.3798 -85.8774)
			)
		)
		(polygon
			(pts
				(xy 214.433912 -83.546696) (xy 214.179912 -83.546696) (xy 214.179912 -83.800696) (xy 214.433912 -83.800696)
			)
		)
		(polygon
			(pts
				(xy 213.290912 -83.546696) (xy 213.036912 -83.546696) (xy 213.036912 -83.800696) (xy 213.290912 -83.800696)
			)
		)
	)
	(zone
		(layer "F.Cu")
		(hatch none 0.5)
		(connect_pads
			(clearance 0)
		)
		(min_thickness 0.25)
		(keepout
			(tracks not_allowed)
			(vias allowed)
			(pads allowed)
			(copperpour not_allowed)
			(footprints allowed)
		)
		(placement
			(enabled no)
			(sheetname "")
		)
		(fill
			(thermal_gap 0.5)
			(thermal_bridge_width 0.5)
			(island_removal_mode 0)
		)
		(polygon
			(pts
				(arc
					(start 22.481286 -135.191754)
					(mid 21.894673 -134.60476)
					(end 21.307806 -135.1915)
				)
				(xy 21.307806 -135.3566)
				(arc
					(start 21.342604 -135.3566)
					(mid 21.485698 -135.342177)
					(end 21.62302 -135.29945)
				)
				(arc
					(start 21.62302 -135.29945)
					(mid 22.13493 -135.025747)
					(end 21.696172 -135.405876)
				)
				(arc
					(start 21.696172 -135.405876)
					(mid 21.536603 -135.460909)
					(end 21.369274 -135.483092)
				)
				(xy 21.36902 -135.4836) (xy 21.307806 -135.4836) (xy 21.307806 -135.6868) (xy 21.39061 -135.6868)
				(arc
					(start 21.391372 -135.687816)
					(mid 21.508708 -135.715495)
					(end 21.611336 -135.778748)
				)
				(xy 21.61286 -135.778748)
				(arc
					(start 21.737828 -135.903716)
					(mid 22.101172 -136.356976)
					(end 21.647912 -135.993632)
				)
				(arc
					(start 21.541486 -135.887206)
					(mid 21.460261 -135.832903)
					(end 21.364448 -135.8138)
				)
				(xy 21.307806 -135.8138)
				(arc
					(start 21.307806 -136.15035)
					(mid 21.894546 -136.73709)
					(end 22.481286 -136.15035)
				)
			)
		)
	)
	(zone
		(layer "F.Cu")
		(hatch none 0.5)
		(connect_pads
			(clearance 0)
		)
		(min_thickness 0.25)
		(keepout
			(tracks not_allowed)
			(vias allowed)
			(pads allowed)
			(copperpour not_allowed)
			(footprints allowed)
		)
		(placement
			(enabled no)
			(sheetname "")
		)
		(fill
			(thermal_gap 0.5)
			(thermal_bridge_width 0.5)
			(island_removal_mode 0)
		)
		(polygon
			(pts
				(arc
					(start 7.616444 -417.344606)
					(mid 7.62683 -417.294506)
					(end 7.640828 -417.245292)
				)
				(arc
					(start 7.53364 -417.243768)
					(mid 6.93852 -417.821999)
					(end 7.516622 -418.417248)
				)
				(arc
					(start 8.380222 -418.429694)
					(mid 8.975344 -417.851336)
					(end 8.396986 -417.256214)
				)
				(arc
					(start 8.177276 -417.253166)
					(mid 8.15586 -417.270784)
					(end 8.13562 -417.289742)
				)
				(arc
					(start 8.13562 -417.289742)
					(mid 8.064318 -417.46152)
					(end 8.135366 -417.633404)
				)
				(arc
					(start 8.161274 -417.659566)
					(mid 8.652123 -417.969546)
					(end 8.103108 -417.780978)
				)
				(xy 8.045704 -417.723574) (xy 8.04545 -417.72332) (xy 8.027162 -417.705032)
				(arc
					(start 8.027162 -417.703508)
					(mid 7.937752 -417.481158)
					(end 8.003286 -417.250626)
				)
				(arc
					(start 7.775194 -417.247324)
					(mid 7.752344 -417.316262)
					(end 7.738364 -417.387532)
				)
				(xy 7.712456 -417.585906) (xy 7.712456 -417.58616)
				(arc
					(start 7.709916 -417.604448)
					(mid 7.396353 -418.092531)
					(end 7.58952 -417.54552)
				)
				(xy 7.615936 -417.345114)
			)
		)
	)
	(zone
		(layer "F.Cu")
		(hatch none 0.5)
		(connect_pads
			(clearance 0)
		)
		(min_thickness 0.25)
		(keepout
			(tracks not_allowed)
			(vias allowed)
			(pads allowed)
			(copperpour not_allowed)
			(footprints allowed)
		)
		(placement
			(enabled no)
			(sheetname "")
		)
		(fill
			(thermal_gap 0.5)
			(thermal_bridge_width 0.5)
			(island_removal_mode 0)
		)
		(polygon
			(pts
				(arc
					(start 6.980682 -399.062702)
					(mid 7.031783 -398.908175)
					(end 7.057644 -398.747488)
				)
				(arc
					(start 6.862318 -398.756378)
					(mid 6.30555 -399.366994)
					(end 6.916166 -399.923762)
				)
				(arc
					(start 7.77875 -399.884138)
					(mid 8.335766 -399.273649)
					(end 7.725156 -398.716754)
				)
				(arc
					(start 7.520432 -398.726152)
					(mid 7.551594 -398.889045)
					(end 7.617206 -399.041366)
				)
				(arc
					(start 7.617206 -399.041366)
					(mid 7.940394 -399.523901)
					(end 7.518654 -399.124678)
				)
				(arc
					(start 7.518654 -399.124678)
					(mid 7.433114 -398.935673)
					(end 7.393686 -398.731994)
				)
				(arc
					(start 7.185406 -398.741646)
					(mid 7.154954 -398.939212)
					(end 7.090664 -399.128488)
				)
				(arc
					(start 7.090664 -399.128488)
					(mid 6.739669 -399.590644)
					(end 6.980682 -399.062702)
				)
			)
		)
	)
	(zone
		(layer "F.Cu")
		(hatch none 0.5)
		(connect_pads
			(clearance 0)
		)
		(min_thickness 0.25)
		(keepout
			(tracks allowed)
			(vias allowed)
			(pads allowed)
			(copperpour allowed)
			(footprints not_allowed)
		)
		(placement
			(enabled no)
			(sheetname "")
		)
		(fill
			(thermal_gap 0.5)
			(thermal_bridge_width 0.5)
			(island_removal_mode 0)
		)
		(polygon
			(pts
				(arc
					(start 252.499876 -33.999932)
					(mid 256.499868 -37.999924)
					(end 252.499876 -41.999916)
				)
				(arc
					(start 252.499876 -41.999916)
					(mid 248.499884 -37.999924)
					(end 252.499876 -33.999932)
				)
			)
		)
	)
	(zone
		(layer "F.Cu")
		(hatch none 0.5)
		(connect_pads
			(clearance 0)
		)
		(min_thickness 0.25)
		(keepout
			(tracks allowed)
			(vias allowed)
			(pads allowed)
			(copperpour allowed)
			(footprints not_allowed)
		)
		(placement
			(enabled no)
			(sheetname "")
		)
		(fill
			(thermal_gap 0.5)
			(thermal_bridge_width 0.5)
			(island_removal_mode 0)
		)
		(polygon
			(pts
				(arc
					(start 7.500112 -257.50012)
					(mid 11.500104 -261.500112)
					(end 7.500112 -265.500104)
				)
				(arc
					(start 7.500112 -265.500104)
					(mid 3.50012 -261.500112)
					(end 7.500112 -257.50012)
				)
			)
		)
	)
	(zone
		(layer "F.Cu")
		(hatch none 0.5)
		(connect_pads
			(clearance 0)
		)
		(min_thickness 0.25)
		(keepout
			(tracks allowed)
			(vias allowed)
			(pads allowed)
			(copperpour allowed)
			(footprints not_allowed)
		)
		(placement
			(enabled no)
			(sheetname "")
		)
		(fill
			(thermal_gap 0.5)
			(thermal_bridge_width 0.5)
			(island_removal_mode 0)
		)
		(polygon
			(pts
				(arc
					(start 32.999934 -0.500126)
					(mid 36.999926 -4.500118)
					(end 32.999934 -8.50011)
				)
				(arc
					(start 32.999934 -8.50011)
					(mid 28.999942 -4.500118)
					(end 32.999934 -0.500126)
				)
			)
		)
	)
	(zone
		(layer "F.Cu")
		(hatch none 0.5)
		(connect_pads
			(clearance 0.5)
		)
		(min_thickness 0.25)
		(fill
			(thermal_gap 0.5)
			(thermal_bridge_width 0.5)
			(island_removal_mode 0)
		)
		(polygon
			(pts
				(xy 20.446746 -473.4687) (xy 20.192746 -473.7227) (xy 20.192746 -476.1357) (xy 19.430746 -476.8977)
				(xy 14.223746 -476.8977) (xy 13.969746 -477.1517) (xy 13.969746 -483.1207) (xy 14.160246 -483.3112)
				(xy 14.668246 -483.3112) (xy 14.979396 -483.62235) (xy 18.67535 -483.62235) (xy 19.558 -484.505)
				(xy 21.844 -484.505) (xy 23.876 -486.537) (xy 23.869396 -486.543604) (xy 23.869396 -494.671604)
				(xy 25.526746 -496.3287) (xy 34.035746 -496.3287) (xy 34.924746 -495.4397) (xy 34.924746 -485.2797)
				(xy 33.400746 -483.7557) (xy 30.225746 -483.7557) (xy 27.177746 -480.7077) (xy 27.177746 -474.1037)
				(xy 26.542746 -473.4687)
			)
		)
		(polygon
			(pts
				(xy 14.985746 -482.5619) (xy 14.731746 -482.5619) (xy 14.731746 -482.8159) (xy 14.985746 -482.8159)
			)
		)
		(polygon
			(pts
				(xy 14.553946 -482.0031) (xy 14.299946 -482.0031) (xy 14.299946 -482.2571) (xy 14.553946 -482.2571)
			)
		)
		(polygon
			(pts
				(xy 14.553946 -481.4443) (xy 14.299946 -481.4443) (xy 14.299946 -481.6983) (xy 14.553946 -481.6983)
			)
		)
	)
	(zone
		(layer "F.Cu")
		(hatch none 0.5)
		(connect_pads
			(clearance 0)
		)
		(min_thickness 0.25)
		(keepout
			(tracks allowed)
			(vias allowed)
			(pads allowed)
			(copperpour allowed)
			(footprints not_allowed)
		)
		(placement
			(enabled no)
			(sheetname "")
		)
		(fill
			(thermal_gap 0.5)
			(thermal_bridge_width 0.5)
			(island_removal_mode 0)
		)
		(polygon
			(pts
				(arc
					(start 7.500112 -265.500104)
					(mid 3.50012 -261.500112)
					(end 7.500112 -257.50012)
				)
				(arc
					(start 7.500112 -257.50012)
					(mid 11.500104 -261.500112)
					(end 7.500112 -265.500104)
				)
			)
		)
	)
	(zone
		(net "P12V_HDD2")
		(layer "F.Cu")
		(hatch none 0.5)
		(connect_pads
			(clearance 0.5)
		)
		(min_thickness 0.25)
		(fill yes
			(thermal_gap 0.5)
			(thermal_bridge_width 0.5)
			(island_removal_mode 0)
		)
		(polygon
			(pts
				(xy 204.215746 -285.5087) (xy 203.961746 -285.7627) (xy 203.961746 -290.0807) (xy 201.421746 -290.0807)
				(xy 201.040746 -290.4617) (xy 201.040746 -295.4147) (xy 201.675746 -296.0497) (xy 211.4169 -296.0497)
				(xy 211.7852 -295.6814) (xy 211.7852 -291.1348) (xy 211.9503 -290.9697) (xy 223.519746 -290.9697)
				(xy 224.535746 -289.9537) (xy 224.535746 -288.3027) (xy 224.281746 -288.0487) (xy 221.614746 -288.0487)
				(xy 220.2942 -288.0487) (xy 220.262704 -288.080196) (xy 219.4052 -288.9377) (xy 217.3732 -288.9377)
				(xy 217.2843 -288.9377) (xy 217.0938 -288.7472) (xy 216.4334 -288.0868) (xy 216.4334 -285.9024)
				(xy 216.0397 -285.5087) (xy 214.121746 -285.5087)
			)
		)
		(polygon
			(pts
				(xy 213.994746 -288.1757) (xy 213.740746 -288.1757) (xy 213.740746 -288.4297) (xy 213.994746 -288.4297)
			)
		)
		(polygon
			(pts
				(xy 212.851746 -288.1757) (xy 212.597746 -288.1757) (xy 212.597746 -288.4297) (xy 212.851746 -288.4297)
			)
		)
	)
	(zone
		(net "P3V3")
		(layer "F.Cu")
		(hatch none 0.5)
		(connect_pads
			(clearance 0.5)
		)
		(min_thickness 0.25)
		(fill yes
			(thermal_gap 0.5)
			(thermal_bridge_width 0.5)
			(island_removal_mode 0)
		)
		(polygon
			(pts
				(xy 39.496746 -203.7207) (xy 38.226746 -204.9907) (xy 38.226746 -210.9597) (xy 39.115746 -211.8487)
				(xy 41.782746 -211.8487) (xy 42.036746 -212.1027) (xy 42.925746 -212.1027) (xy 43.052746 -211.9757)
				(xy 43.052746 -209.4357) (xy 42.925746 -209.3087) (xy 42.417746 -209.3087) (xy 42.163746 -209.0547)
				(xy 42.163746 -208.8007) (xy 41.782746 -208.4197) (xy 39.9796 -208.4197) (xy 39.7002 -208.1403)
				(xy 39.7002 -206.2226) (xy 40.1828 -205.74) (xy 44.170346 -205.74) (xy 44.576746 -205.3336) (xy 44.576746 -204.2287)
				(xy 44.068746 -203.7207)
			)
		)
		(polygon
			(pts
				(xy 42.392346 -211.280502) (xy 42.138346 -211.280502) (xy 42.138346 -211.534502) (xy 42.392346 -211.534502)
			)
		)
		(polygon
			(pts
				(xy 40.9448 -208.915) (xy 40.6908 -208.915) (xy 40.6908 -209.169) (xy 40.9448 -209.169)
			)
		)
		(polygon
			(pts
				(xy 40.3352 -208.915) (xy 40.0812 -208.915) (xy 40.0812 -209.169) (xy 40.3352 -209.169)
			)
		)
		(polygon
			(pts
				(xy 43.713146 -205.057502) (xy 43.459146 -205.057502) (xy 43.459146 -205.311502) (xy 43.713146 -205.311502)
			)
		)
		(polygon
			(pts
				(xy 43.154346 -205.057502) (xy 42.900346 -205.057502) (xy 42.900346 -205.311502) (xy 43.154346 -205.311502)
			)
		)
		(polygon
			(pts
				(xy 42.697146 -205.057502) (xy 42.443146 -205.057502) (xy 42.443146 -205.311502) (xy 42.697146 -205.311502)
			)
		)
		(polygon
			(pts
				(xy 42.138346 -205.057502) (xy 41.884346 -205.057502) (xy 41.884346 -205.311502) (xy 42.138346 -205.311502)
			)
		)
	)
	(zone
		(net "P5V_HDD13")
		(layer "F.Cu")
		(hatch none 0.5)
		(connect_pads
			(clearance 0.5)
		)
		(min_thickness 0.25)
		(fill yes
			(thermal_gap 0.5)
			(thermal_bridge_width 0.5)
			(island_removal_mode 0)
		)
		(polygon
			(pts
				(xy 38.735 -122.4534) (xy 38.5572 -122.6312) (xy 38.5572 -124.2949) (xy 37.8714 -124.9807) (xy 34.670746 -124.9807)
				(xy 34.035746 -125.6157) (xy 34.035746 -126.7587) (xy 34.543746 -127.2667) (xy 36.702746 -127.2667)
				(xy 40.004746 -130.5687) (xy 41.020746 -130.5687) (xy 41.033446 -130.556) (xy 42.418 -130.556) (xy 43.053 -129.921)
				(xy 43.852846 -129.921) (xy 46.675548 -132.743702) (xy 51.307746 -132.743702) (xy 51.561746 -132.489702)
				(xy 51.561746 -129.695702) (xy 51.434746 -129.568702) (xy 47.751746 -129.568702) (xy 43.4086 -125.225556)
				(xy 43.4086 -122.7074) (xy 43.2054 -122.5042) (xy 43.1546 -122.4534) (xy 40.9448 -122.4534)
			)
		)
		(polygon
			(pts
				(xy 40.068246 -127.536702) (xy 39.814246 -127.536702) (xy 39.814246 -127.790702) (xy 40.068246 -127.790702)
			)
		)
		(polygon
			(pts
				(xy 35.991546 -125.885702) (xy 35.737546 -125.885702) (xy 35.737546 -126.139702) (xy 35.991546 -126.139702)
			)
		)
		(polygon
			(pts
				(xy 35.127946 -125.885702) (xy 34.873946 -125.885702) (xy 34.873946 -126.139702) (xy 35.127946 -126.139702)
			)
		)
	)
	(zone
		(net "P5V_HDD5")
		(layer "F.Cu")
		(hatch none 0.5)
		(connect_pads
			(clearance 0.5)
		)
		(min_thickness 0.25)
		(fill yes
			(thermal_gap 0.5)
			(thermal_bridge_width 0.5)
			(island_removal_mode 0)
		)
		(polygon
			(pts
				(xy 60.7568 -482.346) (xy 60.3631 -482.7397) (xy 58.419746 -482.7397) (xy 57.403746 -483.7557) (xy 57.403746 -485.7877)
				(xy 56.895746 -486.2957) (xy 54.1782 -486.2957) (xy 53.0225 -485.14) (xy 41.0972 -485.14) (xy 40.9702 -485.267)
				(xy 40.9702 -485.2797) (xy 39.9542 -486.2957) (xy 37.083746 -486.2957) (xy 36.956746 -486.4227)
				(xy 36.956746 -488.2007) (xy 37.083746 -488.3277) (xy 57.911746 -488.3277) (xy 58.673746 -489.0897)
				(xy 58.788046 -489.204) (xy 60.325 -489.204) (xy 61.582046 -489.204) (xy 62.356746 -489.9787) (xy 63.499746 -489.9787)
				(xy 63.880746 -490.3597) (xy 63.880746 -490.8677) (xy 64.261746 -491.2487) (xy 65.785746 -491.2487)
				(xy 66.039746 -490.9947) (xy 66.039746 -488.2007) (xy 65.785746 -487.9467) (xy 64.134746 -487.9467)
				(xy 63.8048 -487.616754) (xy 63.8048 -484.8098) (xy 63.5127 -484.5177) (xy 63.5127 -482.6127) (xy 63.246 -482.346)
			)
		)
		(polygon
			(pts
				(xy 56.137556 -487.200702) (xy 55.883556 -487.200702) (xy 55.883556 -487.454702) (xy 56.137556 -487.454702)
			)
		)
		(polygon
			(pts
				(xy 55.273956 -487.200702) (xy 55.019956 -487.200702) (xy 55.019956 -487.454702) (xy 55.273956 -487.454702)
			)
		)
		(polygon
			(pts
				(xy 61.197236 -485.568498) (xy 60.943236 -485.568498) (xy 60.943236 -485.822498) (xy 61.197236 -485.822498)
			)
		)
		(polygon
			(pts
				(xy 60.054236 -485.568498) (xy 59.800236 -485.568498) (xy 59.800236 -485.822498) (xy 60.054236 -485.822498)
			)
		)
		(polygon
			(pts
				(xy 61.197236 -482.774498) (xy 60.943236 -482.774498) (xy 60.943236 -483.028498) (xy 61.197236 -483.028498)
			)
		)
	)
	(zone
		(net "P5VC")
		(layer "F.Cu")
		(hatch none 0.5)
		(connect_pads
			(clearance 0.5)
		)
		(min_thickness 0.25)
		(fill yes
			(thermal_gap 0.5)
			(thermal_bridge_width 0.5)
			(island_removal_mode 0)
		)
		(polygon
			(pts
				(xy 39.115746 -327.2917) (xy 38.861746 -327.5457) (xy 38.861746 -331.8637) (xy 39.496746 -332.4987)
				(xy 45.719746 -332.4987) (xy 46.227746 -331.9907) (xy 46.227746 -327.5457) (xy 45.973746 -327.2917)
			)
		)
	)
	(zone
		(layer "F.Cu")
		(hatch none 0.5)
		(connect_pads
			(clearance 0)
		)
		(min_thickness 0.25)
		(keepout
			(tracks not_allowed)
			(vias allowed)
			(pads allowed)
			(copperpour not_allowed)
			(footprints allowed)
		)
		(placement
			(enabled no)
			(sheetname "")
		)
		(fill
			(thermal_gap 0.5)
			(thermal_bridge_width 0.5)
			(island_removal_mode 0)
		)
		(polygon
			(pts
				(arc
					(start 21.881338 -341.309452)
					(mid 21.689994 -341.395001)
					(end 21.48586 -341.442548)
				)
				(arc
					(start 21.48586 -341.672672)
					(mid 21.691603 -341.728292)
					(end 21.883878 -341.820246)
				)
				(arc
					(start 21.883878 -341.820246)
					(mid 22.300571 -342.224641)
					(end 21.805392 -341.921338)
				)
				(arc
					(start 21.805392 -341.921338)
					(mid 21.650536 -341.848507)
					(end 21.48586 -341.801958)
				)
				(arc
					(start 21.48586 -342.045036)
					(mid 22.069933 -342.62949)
					(end 22.65426 -342.04529)
				)
				(arc
					(start 22.65426 -341.08644)
					(mid 22.07006 -340.50224)
					(end 21.48586 -341.08644)
				)
				(arc
					(start 21.48586 -341.314278)
					(mid 21.649675 -341.274589)
					(end 21.804122 -341.20709)
				)
				(arc
					(start 21.804122 -341.20709)
					(mid 22.303596 -340.910816)
					(end 21.881338 -341.309452)
				)
			)
		)
	)
	(zone
		(net "P12V")
		(layer "F.Cu")
		(hatch none 0.5)
		(connect_pads
			(clearance 0.5)
		)
		(min_thickness 0.25)
		(fill yes
			(thermal_gap 0.5)
			(thermal_bridge_width 0.5)
			(island_removal_mode 0)
		)
		(polygon
			(pts
				(xy 196.596 -87.737696) (xy 196.596 -87.757) (xy 196.469 -87.884) (xy 196.469 -89.916) (xy 196.342 -90.043)
				(xy 194.056 -90.043) (xy 193.929 -90.17) (xy 193.929 -90.678) (xy 194.564 -91.313) (xy 195.453 -91.313)
				(xy 195.707 -91.567) (xy 195.707 -93.98) (xy 195.961 -94.234) (xy 199.009 -94.234) (xy 199.898 -93.345)
				(xy 199.898 -92.569284) (xy 199.892412 -92.563696) (xy 199.892412 -88.118696) (xy 199.511412 -87.737696)
			)
		)
		(polygon
			(pts
				(xy 195.7578 -90.551) (xy 195.5038 -90.551) (xy 195.5038 -90.805) (xy 195.7578 -90.805)
			)
		)
		(polygon
			(pts
				(xy 195.1482 -90.551) (xy 194.8942 -90.551) (xy 194.8942 -90.805) (xy 195.1482 -90.805)
			)
		)
		(polygon
			(pts
				(xy 194.7164 -90.5002) (xy 194.4624 -90.5002) (xy 194.4624 -90.7542) (xy 194.7164 -90.7542)
			)
		)
	)
	(zone
		(layer "F.Cu")
		(hatch none 0.5)
		(connect_pads
			(clearance 0)
		)
		(min_thickness 0.25)
		(keepout
			(tracks not_allowed)
			(vias allowed)
			(pads allowed)
			(copperpour not_allowed)
			(footprints allowed)
		)
		(placement
			(enabled no)
			(sheetname "")
		)
		(fill
			(thermal_gap 0.5)
			(thermal_bridge_width 0.5)
			(island_removal_mode 0)
		)
		(polygon
			(pts
				(arc
					(start 32.591756 -164.550852)
					(mid 32.630888 -164.544163)
					(end 32.66948 -164.53485)
				)
				(xy 32.983424 -164.44722)
				(arc
					(start 33.126172 -164.304472)
					(mid 33.229875 -164.16803)
					(end 33.293304 -164.008816)
				)
				(arc
					(start 33.293304 -164.008816)
					(mid 33.393056 -163.436853)
					(end 33.421828 -164.01669)
				)
				(arc
					(start 33.421828 -164.01669)
					(mid 33.352426 -164.20852)
					(end 33.23463 -164.375084)
				)
				(xy 33.23463 -164.375846) (xy 33.232852 -164.37737)
				(arc
					(start 33.533334 -164.29355)
					(mid 33.94075 -163.570666)
					(end 33.217866 -163.16325)
				)
				(arc
					(start 32.361886 -163.402518)
					(mid 31.925723 -163.996726)
					(end 32.414718 -164.548312)
				)
				(arc
					(start 32.562038 -164.400992)
					(mid 32.585237 -164.373092)
					(end 32.603186 -164.341556)
				)
				(xy 32.604456 -164.338508)
				(arc
					(start 32.614362 -164.312092)
					(mid 32.621364 -164.276488)
					(end 32.621982 -164.24021)
				)
				(arc
					(start 32.621982 -164.24021)
					(mid 32.340044 -163.733382)
					(end 32.735012 -164.158168)
				)
				(arc
					(start 32.7406 -164.179504)
					(mid 32.749212 -164.263729)
					(end 32.736282 -164.347398)
				)
				(arc
					(start 32.736282 -164.347906)
					(mid 32.729455 -164.368472)
					(end 32.721296 -164.388546)
				)
				(arc
					(start 32.720026 -164.39134)
					(mid 32.698063 -164.432716)
					(end 32.670496 -164.470588)
				)
				(xy 32.670496 -164.472366)
			)
		)
	)
	(zone
		(net "P5VA")
		(layer "F.Cu")
		(hatch none 0.5)
		(connect_pads
			(clearance 0.5)
		)
		(min_thickness 0.25)
		(fill yes
			(thermal_gap 0.5)
			(thermal_bridge_width 0.5)
			(island_removal_mode 0)
		)
		(polygon
			(pts
				(xy 200.998074 -176.111662) (xy 200.617074 -176.492662) (xy 200.617074 -181.445662) (xy 200.871074 -181.699662)
				(xy 205.062074 -181.699662) (xy 205.443074 -181.318662) (xy 205.443074 -176.365662) (xy 205.189074 -176.111662)
			)
		)
	)
	(zone
		(net "GND")
		(layer "F.Cu")
		(hatch none 0.5)
		(connect_pads
			(clearance 0.5)
		)
		(min_thickness 0.25)
		(fill yes
			(thermal_gap 0.5)
			(thermal_bridge_width 0.5)
			(island_removal_mode 0)
		)
		(polygon
			(pts
				(xy 42.417746 -488.8357) (xy 41.655746 -489.5977) (xy 41.655746 -491.7567) (xy 41.909746 -492.0107)
				(xy 51.434746 -492.0107) (xy 51.834542 -491.610904) (xy 60.940696 -491.610904) (xy 61.467746 -492.1377)
				(xy 63.245746 -492.1377) (xy 63.626746 -491.7567) (xy 63.626746 -490.8677) (xy 63.118746 -490.3597)
				(xy 62.102746 -490.3597) (xy 61.467746 -489.7247) (xy 57.784746 -489.7247) (xy 56.895746 -488.8357)
			)
		)
		(polygon
			(pts
				(xy 56.137556 -489.486702) (xy 55.883556 -489.486702) (xy 55.883556 -489.740702) (xy 56.137556 -489.740702)
			)
		)
		(polygon
			(pts
				(xy 55.273956 -489.486702) (xy 55.019956 -489.486702) (xy 55.019956 -489.740702) (xy 55.273956 -489.740702)
			)
		)
	)
	(zone
		(layer "F.Cu")
		(hatch none 0.5)
		(connect_pads
			(clearance 0.5)
		)
		(min_thickness 0.25)
		(fill
			(thermal_gap 0.5)
			(thermal_bridge_width 0.5)
			(island_removal_mode 0)
		)
		(polygon
			(pts
				(xy 1.650746 -469.1507) (xy 1.269746 -469.5317) (xy 1.269746 -486.0417) (xy 2.031746 -486.8037)
				(xy 6.476746 -486.8037) (xy 12.445746 -480.8347) (xy 12.445746 -477.0247) (xy 13.080746 -476.3897)
				(xy 19.049746 -476.3897) (xy 19.684746 -475.7547) (xy 19.684746 -473.5957) (xy 19.616166 -473.52712)
				(xy 14.79042 -473.52712) (xy 14.659864 -473.396564) (xy 10.414 -469.1507)
			)
		)
	)
	(zone
		(net "P12V")
		(layer "F.Cu")
		(hatch none 0.5)
		(connect_pads
			(clearance 0.5)
		)
		(min_thickness 0.25)
		(fill yes
			(thermal_gap 0.5)
			(thermal_bridge_width 0.5)
			(island_removal_mode 0)
		)
		(polygon
			(pts
				(xy 196.088 -189.484) (xy 195.961 -189.611) (xy 195.961 -191.135) (xy 195.707 -191.389) (xy 194.31 -191.389)
				(xy 194.183 -191.516) (xy 194.183 -191.897) (xy 194.691 -192.405) (xy 195.072 -192.405) (xy 195.326 -192.659)
				(xy 195.326 -194.564) (xy 195.707 -194.945) (xy 199.009 -194.945) (xy 199.566784 -194.387216) (xy 199.566784 -189.835028)
				(xy 199.215756 -189.484)
			)
		)
		(polygon
			(pts
				(xy 196.0118 -191.897) (xy 195.7578 -191.897) (xy 195.7578 -192.151) (xy 196.0118 -192.151)
			)
		)
		(polygon
			(pts
				(xy 195.4022 -191.897) (xy 195.1482 -191.897) (xy 195.1482 -192.151) (xy 195.4022 -192.151)
			)
		)
		(polygon
			(pts
				(xy 194.9704 -191.8462) (xy 194.7164 -191.8462) (xy 194.7164 -192.1002) (xy 194.9704 -192.1002)
			)
		)
	)
	(zone
		(net "GND")
		(layer "F.Cu")
		(hatch none 0.5)
		(connect_pads
			(clearance 0.5)
		)
		(min_thickness 0.25)
		(fill yes
			(thermal_gap 0.5)
			(thermal_bridge_width 0.5)
			(island_removal_mode 0)
		)
		(polygon
			(pts
				(xy 27.177746 -320.5607) (xy 26.034746 -321.7037) (xy 26.034746 -322.2117) (xy 26.288746 -322.4657)
				(xy 31.876746 -322.4657) (xy 32.035496 -322.30695) (xy 34.28365 -322.30695) (xy 34.543746 -322.046854)
				(xy 34.543746 -320.6877) (xy 34.416746 -320.5607)
			)
		)
		(polygon
			(pts
				(xy 27.101546 -321.465702) (xy 26.847546 -321.465702) (xy 26.847546 -321.719702) (xy 27.101546 -321.719702)
			)
		)
	)
	(zone
		(layer "F.Cu")
		(hatch none 0.5)
		(connect_pads
			(clearance 0)
		)
		(min_thickness 0.25)
		(keepout
			(tracks not_allowed)
			(vias allowed)
			(pads allowed)
			(copperpour not_allowed)
			(footprints allowed)
		)
		(placement
			(enabled no)
			(sheetname "")
		)
		(fill
			(thermal_gap 0.5)
			(thermal_bridge_width 0.5)
			(island_removal_mode 0)
		)
		(polygon
			(pts
				(arc
					(start 22.581108 -32.148526)
					(mid 21.950172 -31.609538)
					(end 21.411184 -32.240474)
				)
				(xy 21.424392 -32.408622)
				(arc
					(start 21.462746 -32.408622)
					(mid 21.606055 -32.389756)
					(end 21.739606 -32.334454)
				)
				(arc
					(start 21.739606 -32.334454)
					(mid 22.214891 -32.000907)
					(end 21.82495 -32.431228)
				)
				(arc
					(start 21.82495 -32.431228)
					(mid 21.664121 -32.50516)
					(end 21.48967 -32.535114)
				)
				(xy 21.489162 -32.535622) (xy 21.434298 -32.535622) (xy 21.4503 -32.738822) (xy 21.743162 -32.738822)
				(arc
					(start 21.743924 -32.739584)
					(mid 21.898309 -32.780163)
					(end 22.026372 -32.875474)
				)
				(arc
					(start 22.026372 -32.875474)
					(mid 22.185957 -33.432833)
					(end 21.89861 -32.929322)
				)
				(arc
					(start 21.89861 -32.929322)
					(mid 21.813064 -32.882141)
					(end 21.716746 -32.865822)
				)
				(xy 21.46046 -32.865822)
				(arc
					(start 21.487384 -33.209738)
					(mid 22.118192 -33.74897)
					(end 22.657308 -33.118044)
				)
			)
		)
	)
	(zone
		(layer "F.Cu")
		(hatch none 0.5)
		(connect_pads
			(clearance 0)
		)
		(min_thickness 0.25)
		(keepout
			(tracks allowed)
			(vias allowed)
			(pads allowed)
			(copperpour allowed)
			(footprints allowed)
		)
		(placement
			(enabled no)
			(sheetname "")
		)
		(fill
			(thermal_gap 0.5)
			(thermal_bridge_width 0.5)
			(island_removal_mode 0)
		)
		(polygon
			(pts
				(xy 232.155746 -24.2697) (xy 233.171746 -24.2697) (xy 233.552746 -23.8887) (xy 233.552746 -22.7457)
				(xy 233.298746 -22.4917) (xy 232.282746 -22.4917) (xy 231.647746 -23.1267) (xy 231.647746 -23.7617)
			)
		)
	)
	(zone
		(net "P5V_HDD2")
		(layer "F.Cu")
		(hatch none 0.5)
		(connect_pads
			(clearance 0.5)
		)
		(min_thickness 0.25)
		(fill yes
			(thermal_gap 0.5)
			(thermal_bridge_width 0.5)
			(island_removal_mode 0)
		)
		(polygon
			(pts
				(xy 210.6549 -276.9489) (xy 210.644232 -276.959568) (xy 210.110832 -276.959568) (xy 210.1088 -276.9616)
				(xy 207.9498 -276.9616) (xy 207.645 -277.2664) (xy 207.645 -277.888446) (xy 207.517746 -278.0157)
				(xy 207.517746 -282.5877) (xy 207.771746 -282.8417) (xy 210.946746 -282.8417) (xy 212.595714 -282.8417)
				(xy 212.809582 -283.055568) (xy 220.175582 -283.055568) (xy 220.683582 -282.547568) (xy 224.112582 -282.547568)
				(xy 224.366582 -282.293568) (xy 224.366582 -280.515568) (xy 224.18548 -280.334466) (xy 215.93048 -280.334466)
				(xy 215.857582 -280.261568) (xy 215.476582 -279.880568) (xy 215.476582 -277.213568) (xy 215.222582 -276.959568)
				(xy 210.665568 -276.959568)
			)
		)
		(polygon
			(pts
				(xy 217.813382 -281.912568) (xy 217.559382 -281.912568) (xy 217.559382 -282.166568) (xy 217.813382 -282.166568)
			)
		)
		(polygon
			(pts
				(xy 216.949782 -281.912568) (xy 216.695782 -281.912568) (xy 216.695782 -282.166568) (xy 216.949782 -282.166568)
			)
		)
		(polygon
			(pts
				(xy 213.127082 -279.829768) (xy 212.873082 -279.829768) (xy 212.873082 -280.083768) (xy 213.127082 -280.083768)
			)
		)
	)
	(zone
		(net "P5V_HDD1")
		(layer "F.Cu")
		(hatch none 0.5)
		(connect_pads
			(clearance 0.5)
		)
		(min_thickness 0.25)
		(fill yes
			(thermal_gap 0.5)
			(thermal_bridge_width 0.5)
			(island_removal_mode 0)
		)
		(polygon
			(pts
				(xy 208.0006 -379.3236) (xy 207.771746 -379.552454) (xy 207.771746 -385.3307) (xy 208.025746 -385.5847)
				(xy 211.581746 -385.5847) (xy 211.588096 -385.578096) (xy 212.99297 -385.578096) (xy 213.062058 -385.647184)
				(xy 213.316058 -385.901184) (xy 220.682058 -385.901184) (xy 221.190058 -385.393184) (xy 224.619058 -385.393184)
				(xy 224.873058 -385.139184) (xy 224.873058 -383.361184) (xy 224.619058 -383.107184) (xy 216.364058 -383.107184)
				(xy 215.983058 -382.726184) (xy 215.983058 -380.059184) (xy 215.729058 -379.805184) (xy 214.5792 -379.805184)
				(xy 214.046816 -379.2728) (xy 210.5152 -379.2728) (xy 208.0514 -379.2728)
			)
		)
		(polygon
			(pts
				(xy 218.446858 -384.758184) (xy 218.192858 -384.758184) (xy 218.192858 -385.012184) (xy 218.446858 -385.012184)
			)
		)
		(polygon
			(pts
				(xy 217.583258 -384.758184) (xy 217.329258 -384.758184) (xy 217.329258 -385.012184) (xy 217.583258 -385.012184)
			)
		)
		(polygon
			(pts
				(xy 213.570058 -382.675384) (xy 213.316058 -382.675384) (xy 213.316058 -382.929384) (xy 213.570058 -382.929384)
			)
		)
		(polygon
			(pts
				(xy 213.570058 -379.881384) (xy 213.316058 -379.881384) (xy 213.316058 -380.135384) (xy 213.570058 -380.135384)
			)
		)
		(polygon
			(pts
				(xy 212.427058 -379.881384) (xy 212.173058 -379.881384) (xy 212.173058 -380.135384) (xy 212.427058 -380.135384)
			)
		)
	)
	(zone
		(net "P3V3")
		(layer "F.Cu")
		(hatch none 0.5)
		(connect_pads
			(clearance 0.5)
		)
		(min_thickness 0.25)
		(fill yes
			(thermal_gap 0.5)
			(thermal_bridge_width 0.5)
			(island_removal_mode 0)
		)
		(polygon
			(pts
				(xy 31.114746 -436.5117) (xy 30.733746 -436.8927) (xy 30.733746 -437.6547) (xy 28.828746 -439.5597)
				(xy 28.828746 -440.7027) (xy 29.336746 -441.2107) (xy 37.083746 -441.2107) (xy 37.718746 -440.5757)
				(xy 37.718746 -438.9247) (xy 36.956746 -438.1627) (xy 36.956746 -437.4007) (xy 36.829746 -437.2737)
				(xy 36.321746 -437.2737) (xy 36.194746 -437.4007) (xy 36.194746 -438.1627) (xy 36.067746 -438.2897)
				(xy 34.543746 -438.2897) (xy 34.289746 -438.0357) (xy 34.289746 -437.0197) (xy 33.781746 -436.5117)
			)
		)
		(polygon
			(pts
				(xy 35.357816 -440.391042) (xy 35.103816 -440.391042) (xy 35.103816 -440.645042) (xy 35.357816 -440.645042)
			)
		)
		(polygon
			(pts
				(xy 34.748216 -440.391042) (xy 34.494216 -440.391042) (xy 34.494216 -440.645042) (xy 34.748216 -440.645042)
			)
		)
		(polygon
			(pts
				(xy 31.927546 -440.210702) (xy 31.673546 -440.210702) (xy 31.673546 -440.464702) (xy 31.927546 -440.464702)
			)
		)
		(polygon
			(pts
				(xy 31.317946 -440.210702) (xy 31.063946 -440.210702) (xy 31.063946 -440.464702) (xy 31.317946 -440.464702)
			)
		)
	)
	(zone
		(layer "F.Cu")
		(hatch none 0.5)
		(connect_pads
			(clearance 0)
		)
		(min_thickness 0.25)
		(keepout
			(tracks allowed)
			(vias allowed)
			(pads allowed)
			(copperpour allowed)
			(footprints not_allowed)
		)
		(placement
			(enabled no)
			(sheetname "")
		)
		(fill
			(thermal_gap 0.5)
			(thermal_bridge_width 0.5)
			(island_removal_mode 0)
		)
		(polygon
			(pts
				(arc
					(start 69.000116 -381)
					(mid 65.000124 -377.000008)
					(end 69.000116 -373.000016)
				)
				(arc
					(start 69.000116 -373.000016)
					(mid 73.000108 -377.000008)
					(end 69.000116 -381)
				)
			)
		)
	)
	(zone
		(net "P12V")
		(layer "F.Cu")
		(hatch none 0.5)
		(connect_pads
			(clearance 0.5)
		)
		(min_thickness 0.25)
		(fill yes
			(thermal_gap 0.5)
			(thermal_bridge_width 0.5)
			(island_removal_mode 0)
		)
		(polygon
			(pts
				(xy 93.725746 -3.3147) (xy 93.344746 -3.6957) (xy 93.344746 -8.1407) (xy 93.725746 -8.5217) (xy 97.408746 -8.5217)
				(xy 97.662746 -8.2677) (xy 97.662746 -3.8227) (xy 97.154746 -3.3147)
			)
		)
		(polygon
			(pts
				(xy 97.205546 -7.9121) (xy 96.951546 -7.9121) (xy 96.951546 -8.1661) (xy 97.205546 -8.1661)
			)
		)
		(polygon
			(pts
				(xy 97.205546 -7.3533) (xy 96.951546 -7.3533) (xy 96.951546 -7.6073) (xy 97.205546 -7.6073)
			)
		)
		(polygon
			(pts
				(xy 97.205546 -6.7691) (xy 96.951546 -6.7691) (xy 96.951546 -7.0231) (xy 97.205546 -7.0231)
			)
		)
		(polygon
			(pts
				(xy 97.205546 -6.2103) (xy 96.951546 -6.2103) (xy 96.951546 -6.4643) (xy 97.205546 -6.4643)
			)
		)
	)
	(zone
		(net "GND")
		(layer "F.Cu")
		(hatch none 0.5)
		(connect_pads
			(clearance 0.5)
		)
		(min_thickness 0.25)
		(fill yes
			(thermal_gap 0.5)
			(thermal_bridge_width 0.5)
			(island_removal_mode 0)
		)
		(polygon
			(pts
				(xy 34.162746 -122.6947) (xy 33.781746 -123.0757) (xy 33.781746 -124.0917) (xy 34.289746 -124.5997)
				(xy 37.846 -124.5997) (xy 38.1762 -124.2695) (xy 38.1762 -122.9995) (xy 37.8714 -122.6947)
			)
		)
		(polygon
			(pts
				(xy 35.991546 -123.599702) (xy 35.737546 -123.599702) (xy 35.737546 -123.853702) (xy 35.991546 -123.853702)
			)
		)
		(polygon
			(pts
				(xy 35.127946 -123.599702) (xy 34.873946 -123.599702) (xy 34.873946 -123.853702) (xy 35.127946 -123.853702)
			)
		)
	)
	(zone
		(layer "F.Cu")
		(hatch none 0.5)
		(connect_pads
			(clearance 0.5)
		)
		(min_thickness 0.25)
		(fill
			(thermal_gap 0.5)
			(thermal_bridge_width 0.5)
			(island_removal_mode 0)
		)
		(polygon
			(pts
				(xy 54.863746 -7.3787) (xy 54.482746 -7.7597) (xy 54.482746 -12.9667) (xy 55.625746 -14.1097) (xy 55.625746 -18.3007)
				(xy 55.752746 -18.4277) (xy 57.276746 -18.4277) (xy 57.403746 -18.5547) (xy 58.165746 -18.5547)
				(xy 59.562746 -19.9517) (xy 60.578746 -19.9517) (xy 60.705746 -19.8247) (xy 60.705746 -18.9357)
				(xy 59.943746 -18.1737) (xy 59.943746 -7.7597) (xy 59.562746 -7.3787)
			)
		)
		(polygon
			(pts
				(xy 59.816746 -18.8849) (xy 59.562746 -18.8849) (xy 59.562746 -19.1389) (xy 59.816746 -19.1389)
			)
		)
	)
	(zone
		(layer "F.Cu")
		(hatch none 0.5)
		(connect_pads
			(clearance 0.5)
		)
		(min_thickness 0.25)
		(fill
			(thermal_gap 0.5)
			(thermal_bridge_width 0.5)
			(island_removal_mode 0)
		)
		(polygon
			(pts
				(xy 213.232746 -9.2837) (xy 212.343746 -10.1727) (xy 212.343746 -19.3167) (xy 212.661246 -19.6342)
				(xy 225.234246 -19.6342) (xy 227.393246 -21.7932) (xy 231.584246 -21.7932) (xy 231.647746 -21.8567)
				(xy 233.679746 -21.8567) (xy 233.806746 -21.7297) (xy 233.806746 -15.6337) (xy 227.456746 -9.2837)
			)
		)
		(polygon
			(pts
				(xy 229.133146 -21.1455) (xy 228.879146 -21.1455) (xy 228.879146 -21.3995) (xy 229.133146 -21.3995)
			)
		)
		(polygon
			(pts
				(xy 228.574346 -21.1455) (xy 228.320346 -21.1455) (xy 228.320346 -21.3995) (xy 228.574346 -21.3995)
			)
		)
		(polygon
			(pts
				(xy 231.063546 -21.0947) (xy 230.809546 -21.0947) (xy 230.809546 -21.3487) (xy 231.063546 -21.3487)
			)
		)
		(polygon
			(pts
				(xy 230.453946 -21.0947) (xy 229.920546 -21.0947) (xy 229.920546 -21.3487) (xy 230.453946 -21.3487)
			)
		)
		(polygon
			(pts
				(xy 229.564946 -21.0947) (xy 229.310946 -21.0947) (xy 229.310946 -21.3487) (xy 229.564946 -21.3487)
			)
		)
	)
	(zone
		(layer "F.Cu")
		(hatch none 0.5)
		(connect_pads
			(clearance 0)
		)
		(min_thickness 0.25)
		(keepout
			(tracks allowed)
			(vias allowed)
			(pads allowed)
			(copperpour allowed)
			(footprints not_allowed)
		)
		(placement
			(enabled no)
			(sheetname "")
		)
		(fill
			(thermal_gap 0.5)
			(thermal_bridge_width 0.5)
			(island_removal_mode 0)
		)
		(polygon
			(pts
				(arc
					(start 252.499876 -166.99992)
					(mid 256.499868 -170.999912)
					(end 252.499876 -174.999904)
				)
				(arc
					(start 252.499876 -174.999904)
					(mid 248.499884 -170.999912)
					(end 252.499876 -166.99992)
				)
			)
		)
	)
	(zone
		(layer "F.Cu")
		(hatch none 0.5)
		(connect_pads
			(clearance 0)
		)
		(min_thickness 0.25)
		(keepout
			(tracks not_allowed)
			(vias allowed)
			(pads allowed)
			(copperpour not_allowed)
			(footprints allowed)
		)
		(placement
			(enabled no)
			(sheetname "")
		)
		(fill
			(thermal_gap 0.5)
			(thermal_bridge_width 0.5)
			(island_removal_mode 0)
		)
		(polygon
			(pts
				(arc
					(start 24.257 -129.81686)
					(mid 23.67026 -130.4036)
					(end 24.257 -130.99034)
				)
				(arc
					(start 24.490934 -130.99034)
					(mid 24.477443 -130.904192)
					(end 24.4729 -130.817112)
				)
				(arc
					(start 24.4729 -130.817112)
					(mid 24.457509 -130.728669)
					(end 24.412956 -130.650742)
				)
				(arc
					(start 24.412956 -130.650742)
					(mid 24.05016 -130.197268)
					(end 24.503634 -130.560064)
				)
				(xy 24.505158 -130.561588)
				(arc
					(start 24.505158 -130.563112)
					(mid 24.575366 -130.681319)
					(end 24.5999 -130.816604)
				)
				(arc
					(start 24.5999 -130.817112)
					(mid 24.605292 -130.904375)
					(end 24.621236 -130.99034)
				)
				(arc
					(start 24.83358 -130.99034)
					(mid 24.813527 -130.918389)
					(end 24.804116 -130.84429)
				)
				(xy 24.8031 -130.843528) (xy 24.8031 -130.790696)
				(arc
					(start 24.803862 -130.789934)
					(mid 24.826537 -130.673821)
					(end 24.878792 -130.567684)
				)
				(arc
					(start 24.878792 -130.567684)
					(mid 25.318944 -130.189144)
					(end 24.973534 -130.655822)
				)
				(arc
					(start 24.973534 -130.655822)
					(mid 24.942896 -130.727485)
					(end 24.930354 -130.804412)
				)
				(arc
					(start 24.930354 -130.817366)
					(mid 24.940702 -130.906244)
					(end 24.971248 -130.99034)
				)
				(arc
					(start 25.1206 -130.99034)
					(mid 25.70734 -130.4036)
					(end 25.1206 -129.81686)
				)
			)
		)
	)
	(zone
		(layer "F.Cu")
		(hatch none 0.5)
		(connect_pads
			(clearance 0)
		)
		(min_thickness 0.25)
		(keepout
			(tracks not_allowed)
			(vias allowed)
			(pads allowed)
			(copperpour not_allowed)
			(footprints allowed)
		)
		(placement
			(enabled no)
			(sheetname "")
		)
		(fill
			(thermal_gap 0.5)
			(thermal_bridge_width 0.5)
			(island_removal_mode 0)
		)
		(polygon
			(pts
				(arc
					(start 223.618552 -60.986416)
					(mid 223.031939 -60.399422)
					(end 222.445072 -60.986162)
				)
				(arc
					(start 222.445072 -61.945012)
					(mid 223.031812 -62.531752)
					(end 223.618552 -61.945012)
				)
				(xy 223.618552 -61.61532)
				(arc
					(start 223.56318 -61.616844)
					(mid 223.453073 -61.643011)
					(end 223.359726 -61.707014)
				)
				(arc
					(start 223.278446 -61.788294)
					(mid 222.825186 -62.151638)
					(end 223.18853 -61.698378)
				)
				(xy 223.26981 -61.617098) (xy 223.288352 -61.598556)
				(arc
					(start 223.289622 -61.598556)
					(mid 223.411054 -61.522769)
					(end 223.55048 -61.490352)
				)
				(xy 223.550734 -61.490098) (xy 223.558608 -61.489844) (xy 223.577658 -61.489336) (xy 223.594422 -61.488828)
				(xy 223.59493 -61.48832) (xy 223.618552 -61.48832) (xy 223.618552 -61.28512) (xy 223.54413 -61.28512)
				(arc
					(start 223.543876 -61.284612)
					(mid 223.379989 -61.261959)
					(end 223.224344 -61.205872)
				)
				(arc
					(start 223.224344 -61.205872)
					(mid 222.795428 -60.814512)
					(end 223.30029 -61.101224)
				)
				(arc
					(start 223.30029 -61.101224)
					(mid 223.432323 -61.143762)
					(end 223.570292 -61.15812)
				)
				(xy 223.618552 -61.15812)
			)
		)
	)
	(zone
		(net "5V_PRE_0")
		(layer "F.Cu")
		(hatch none 0.5)
		(connect_pads
			(clearance 0.5)
		)
		(min_thickness 0.25)
		(fill yes
			(thermal_gap 0.5)
			(thermal_bridge_width 0.5)
			(island_removal_mode 0)
		)
		(polygon
			(pts
				(xy 216.868756 -482.882702) (xy 216.614756 -483.136702) (xy 216.614756 -485.676702) (xy 216.868756 -485.930702)
				(xy 224.615756 -485.930702) (xy 224.869756 -485.676702) (xy 224.869756 -485.168702) (xy 224.615756 -484.914702)
				(xy 221.186756 -484.914702) (xy 219.154756 -482.882702)
			)
		)
	)
	(zone
		(net "P3V3")
		(layer "F.Cu")
		(hatch none 0.5)
		(connect_pads
			(clearance 0.5)
		)
		(min_thickness 0.25)
		(fill yes
			(thermal_gap 0.5)
			(thermal_bridge_width 0.5)
			(island_removal_mode 0)
		)
		(polygon
			(pts
				(xy 52.8066 -223.7994) (xy 52.6542 -223.9518) (xy 52.6542 -225.3742) (xy 52.8066 -225.5266) (xy 53.5686 -225.5266)
				(xy 54.2036 -226.1616) (xy 54.2036 -227.8126) (xy 54.5084 -228.1174) (xy 56.2356 -228.1174) (xy 56.6166 -227.7364)
				(xy 56.6166 -224.536) (xy 55.88 -223.7994)
			)
		)
		(polygon
			(pts
				(xy 55.2704 -227.3808) (xy 55.0164 -227.3808) (xy 55.0164 -227.6348) (xy 55.2704 -227.6348)
			)
		)
	)
	(zone
		(net "P12V_HDD11")
		(layer "F.Cu")
		(hatch none 0.5)
		(connect_pads
			(clearance 0.5)
		)
		(min_thickness 0.25)
		(fill yes
			(thermal_gap 0.5)
			(thermal_bridge_width 0.5)
			(island_removal_mode 0)
		)
		(polygon
			(pts
				(xy 39.496746 -308.4957) (xy 39.369746 -308.6227) (xy 39.369746 -313.321954) (xy 38.608 -314.0837)
				(xy 34.543746 -314.0837) (xy 34.273744 -314.353702) (xy 25.145746 -314.353702) (xy 20.319746 -319.179702)
				(xy 20.319746 -320.957702) (xy 20.573746 -321.211702) (xy 22.986746 -321.211702) (xy 23.240746 -320.957702)
				(xy 23.240746 -319.433702) (xy 25.907746 -316.766702) (xy 27.939746 -316.766702) (xy 28.447746 -317.274702)
				(xy 28.447746 -320.195702) (xy 28.701746 -320.449702) (xy 35.686746 -320.449702) (xy 37.334444 -322.0974)
				(xy 38.5572 -322.0974) (xy 43.6626 -322.0974) (xy 43.7388 -322.0212) (xy 44.576746 -321.183254)
				(xy 44.576746 -308.8767) (xy 44.195746 -308.4957)
			)
		)
		(polygon
			(pts
				(xy 32.257746 -317.274702) (xy 32.003746 -317.274702) (xy 32.003746 -317.528702) (xy 32.257746 -317.528702)
			)
		)
		(polygon
			(pts
				(xy 31.114746 -317.274702) (xy 30.860746 -317.274702) (xy 30.860746 -317.528702) (xy 31.114746 -317.528702)
			)
		)
		(polygon
			(pts
				(xy 26.974546 -315.4807) (xy 26.720546 -315.4807) (xy 26.720546 -315.7347) (xy 26.974546 -315.7347)
			)
		)
		(polygon
			(pts
				(xy 26.110946 -315.4807) (xy 25.856946 -315.4807) (xy 25.856946 -315.7347) (xy 26.110946 -315.7347)
			)
		)
	)
	(zone
		(layer "F.Cu")
		(hatch none 0.5)
		(connect_pads
			(clearance 0)
		)
		(min_thickness 0.25)
		(keepout
			(tracks allowed)
			(vias allowed)
			(pads allowed)
			(copperpour allowed)
			(footprints not_allowed)
		)
		(placement
			(enabled no)
			(sheetname "")
		)
		(fill
			(thermal_gap 0.5)
			(thermal_bridge_width 0.5)
			(island_removal_mode 0)
		)
		(polygon
			(pts
				(arc
					(start 69.000116 -174.999904)
					(mid 65.000124 -170.999912)
					(end 69.000116 -166.99992)
				)
				(arc
					(start 69.000116 -166.99992)
					(mid 73.000108 -170.999912)
					(end 69.000116 -174.999904)
				)
			)
		)
	)
	(zone
		(net "GND")
		(layer "F.Cu")
		(hatch none 0.5)
		(connect_pads
			(clearance 0.5)
		)
		(min_thickness 0.25)
		(fill yes
			(thermal_gap 0.5)
			(thermal_bridge_width 0.5)
			(island_removal_mode 0)
		)
		(polygon
			(pts
				(xy 27.050746 -423.3037) (xy 25.907746 -424.4467) (xy 25.907746 -425.3357) (xy 26.034746 -425.4627)
				(xy 34.416746 -425.4627) (xy 34.924746 -424.9547) (xy 34.924746 -423.4307) (xy 34.797746 -423.3037)
			)
		)
		(polygon
			(pts
				(xy 27.355546 -424.462702) (xy 27.101546 -424.462702) (xy 27.101546 -424.716702) (xy 27.355546 -424.716702)
			)
		)
		(polygon
			(pts
				(xy 26.491946 -424.462702) (xy 26.237946 -424.462702) (xy 26.237946 -424.716702) (xy 26.491946 -424.716702)
			)
		)
	)
	(zone
		(layer "F.Cu")
		(hatch none 0.5)
		(connect_pads
			(clearance 0)
		)
		(min_thickness 0.25)
		(keepout
			(tracks allowed)
			(vias allowed)
			(pads allowed)
			(copperpour allowed)
			(footprints not_allowed)
		)
		(placement
			(enabled no)
			(sheetname "")
		)
		(fill
			(thermal_gap 0.5)
			(thermal_bridge_width 0.5)
			(island_removal_mode 0)
		)
		(polygon
			(pts
				(xy 16.889984 -464.829906) (xy 16.889984 -503.00001) (xy 34.99993 -503.00001) (xy 34.99993 -447.28003)
				(xy 27.999944 -447.28003) (xy 27.999944 -464.829906)
			)
		)
	)
	(zone
		(layer "F.Cu")
		(hatch none 0.5)
		(connect_pads
			(clearance 0.5)
		)
		(min_thickness 0.25)
		(fill
			(thermal_gap 0.5)
			(thermal_bridge_width 0.5)
			(island_removal_mode 0)
		)
		(polygon
			(pts
				(xy 11.175746 -496.4557) (xy 11.048746 -496.5827) (xy 11.048746 -496.8367) (xy 11.683746 -497.4717)
				(xy 11.683746 -499.2497) (xy 12.699746 -500.2657) (xy 24.637746 -500.2657) (xy 25.272746 -500.9007)
				(xy 27.685746 -500.9007) (xy 28.574746 -500.0117) (xy 28.574746 -497.5987) (xy 28.193746 -497.2177)
				(xy 24.002746 -497.2177) (xy 23.240746 -496.4557)
			)
		)
		(polygon
			(pts
				(xy 13.258546 -498.8687) (xy 13.004546 -498.8687) (xy 13.004546 -499.1227) (xy 13.258546 -499.1227)
			)
		)
		(polygon
			(pts
				(xy 12.394946 -498.8687) (xy 12.140946 -498.8687) (xy 12.140946 -499.1227) (xy 12.394946 -499.1227)
			)
		)
	)
	(zone
		(net "P3V3")
		(layer "F.Cu")
		(hatch none 0.5)
		(connect_pads
			(clearance 0.5)
		)
		(min_thickness 0.25)
		(fill yes
			(thermal_gap 0.5)
			(thermal_bridge_width 0.5)
			(island_removal_mode 0)
		)
		(polygon
			(pts
				(xy 29.590746 -329.3237) (xy 29.336746 -329.5777) (xy 29.336746 -330.0857) (xy 30.352746 -331.1017)
				(xy 30.352746 -331.7367) (xy 30.733746 -332.1177) (xy 38.099746 -332.1177) (xy 38.353746 -331.8637)
				(xy 38.353746 -329.7047) (xy 37.972746 -329.3237)
			)
		)
		(polygon
			(pts
				(xy 34.213546 -331.498702) (xy 33.959546 -331.498702) (xy 33.959546 -331.752702) (xy 34.213546 -331.752702)
			)
		)
		(polygon
			(pts
				(xy 33.603946 -331.498702) (xy 33.349946 -331.498702) (xy 33.349946 -331.752702) (xy 33.603946 -331.752702)
			)
		)
		(polygon
			(pts
				(xy 36.669218 -331.40904) (xy 36.415218 -331.40904) (xy 36.415218 -331.66304) (xy 36.669218 -331.66304)
			)
		)
		(polygon
			(pts
				(xy 36.059618 -331.40904) (xy 35.805618 -331.40904) (xy 35.805618 -331.66304) (xy 36.059618 -331.66304)
			)
		)
		(polygon
			(pts
				(xy 29.920946 -329.873102) (xy 29.666946 -329.873102) (xy 29.666946 -330.127102) (xy 29.920946 -330.127102)
			)
		)
	)
	(zone
		(net "P5V_HDD13")
		(layer "F.Cu")
		(hatch none 0.5)
		(connect_pads
			(clearance 0.5)
		)
		(min_thickness 0.25)
		(fill yes
			(thermal_gap 0.5)
			(thermal_bridge_width 0.5)
			(island_removal_mode 0)
		)
		(polygon
			(pts
				(xy 20.700746 -120.7897) (xy 20.573746 -120.9167) (xy 20.573746 -122.5677) (xy 20.700746 -122.6947)
				(xy 25.526746 -122.6947) (xy 25.653746 -122.5677) (xy 25.653746 -120.9167) (xy 25.526746 -120.7897)
			)
		)
	)
	(zone
		(layer "F.Cu")
		(hatch none 0.5)
		(connect_pads
			(clearance 0)
		)
		(min_thickness 0.25)
		(keepout
			(tracks not_allowed)
			(vias allowed)
			(pads allowed)
			(copperpour not_allowed)
			(footprints allowed)
		)
		(placement
			(enabled no)
			(sheetname "")
		)
		(fill
			(thermal_gap 0.5)
			(thermal_bridge_width 0.5)
			(island_removal_mode 0)
		)
		(polygon
			(pts
				(arc
					(start 223.61144 -369.971574)
					(mid 223.058863 -369.352569)
					(end 222.439992 -369.90528)
				)
				(xy 222.437452 -369.905026) (xy 222.386398 -370.80444)
				(arc
					(start 222.388938 -370.804694)
					(mid 222.941642 -371.423438)
					(end 223.560386 -370.870734)
				)
				(xy 223.562926 -370.870988) (xy 223.577404 -370.615464)
				(arc
					(start 223.260412 -370.615464)
					(mid 223.219717 -370.619269)
					(end 223.180402 -370.63045)
				)
				(arc
					(start 223.180402 -370.63045)
					(mid 222.827688 -371.090075)
					(end 223.053402 -370.556536)
				)
				(arc
					(start 223.053402 -370.556536)
					(mid 223.138504 -370.510459)
					(end 223.23298 -370.48948)
				)
				(xy 223.233996 -370.488464) (xy 223.58477 -370.488464) (xy 223.5962 -370.285264) (xy 223.282764 -370.285264)
				(arc
					(start 223.281748 -370.284248)
					(mid 223.189248 -370.263879)
					(end 223.105726 -370.219224)
				)
				(arc
					(start 223.105726 -370.219224)
					(mid 222.877931 -369.686578)
					(end 223.232726 -370.144548)
				)
				(arc
					(start 223.232726 -370.144548)
					(mid 223.270343 -370.154807)
					(end 223.30918 -370.158264)
				)
				(xy 223.603312 -370.158264) (xy 223.61398 -369.971828) (xy 223.613726 -369.971574)
			)
		)
	)
	(zone
		(net "P3V3")
		(layer "F.Cu")
		(hatch none 0.5)
		(connect_pads
			(clearance 0.5)
		)
		(min_thickness 0.25)
		(fill yes
			(thermal_gap 0.5)
			(thermal_bridge_width 0.5)
			(island_removal_mode 0)
		)
		(polygon
			(pts
				(xy 73.278746 -490.3597) (xy 73.024746 -490.6137) (xy 73.024746 -492.1377) (xy 73.278746 -492.3917)
				(xy 73.913746 -492.3917) (xy 74.040746 -492.5187) (xy 74.040746 -494.2967) (xy 74.167746 -494.4237)
				(xy 75.945746 -494.4237) (xy 76.580746 -493.7887) (xy 77.469746 -493.7887) (xy 77.850746 -493.4077)
				(xy 79.247746 -493.4077) (xy 79.501746 -493.6617) (xy 79.501746 -494.0427) (xy 79.755746 -494.2967)
				(xy 81.787746 -494.2967) (xy 82.041746 -494.0427) (xy 82.041746 -490.6137) (xy 81.787746 -490.3597)
			)
		)
		(polygon
			(pts
				(xy 80.142334 -493.600486) (xy 79.888334 -493.600486) (xy 79.888334 -493.854486) (xy 80.142334 -493.854486)
			)
		)
		(polygon
			(pts
				(xy 75.833732 -493.351312) (xy 75.579732 -493.351312) (xy 75.579732 -493.605312) (xy 75.833732 -493.605312)
			)
		)
		(polygon
			(pts
				(xy 75.224132 -493.351312) (xy 74.970132 -493.351312) (xy 74.970132 -493.605312) (xy 75.224132 -493.605312)
			)
		)
		(polygon
			(pts
				(xy 80.060546 -490.8677) (xy 79.806546 -490.8677) (xy 79.806546 -491.1217) (xy 80.060546 -491.1217)
			)
		)
		(polygon
			(pts
				(xy 79.450946 -490.8677) (xy 79.196946 -490.8677) (xy 79.196946 -491.1217) (xy 79.450946 -491.1217)
			)
		)
	)
	(zone
		(net "P12V")
		(layer "F.Cu")
		(hatch none 0.5)
		(connect_pads
			(clearance 0.5)
		)
		(min_thickness 0.25)
		(fill yes
			(thermal_gap 0.5)
			(thermal_bridge_width 0.5)
			(island_removal_mode 0)
		)
		(polygon
			(pts
				(xy 25.5016 -283.0322) (xy 25.1968 -283.337) (xy 25.1968 -284.099) (xy 25.4762 -284.3784) (xy 25.526746 -284.3784)
				(xy 25.526746 -287.5407) (xy 25.653746 -287.6677) (xy 29.971746 -287.6677) (xy 29.978096 -287.661096)
				(xy 30.346904 -287.661096) (xy 30.353 -287.655) (xy 30.607 -287.655) (xy 30.988 -288.036) (xy 30.988 -288.163)
				(xy 32.512 -288.163) (xy 32.639 -288.036) (xy 32.639 -286.766) (xy 32.385 -286.512) (xy 30.734 -286.512)
				(xy 30.352746 -286.130746) (xy 30.352746 -283.9847) (xy 30.098746 -283.7307) (xy 26.8351 -283.7307)
				(xy 26.1366 -283.0322)
			)
		)
		(polygon
			(pts
				(xy 32.1056 -287.4518) (xy 31.8516 -287.4518) (xy 31.8516 -287.7058) (xy 32.1056 -287.7058)
			)
		)
		(polygon
			(pts
				(xy 31.6738 -287.401) (xy 31.4198 -287.401) (xy 31.4198 -287.655) (xy 31.6738 -287.655)
			)
		)
		(polygon
			(pts
				(xy 30.022546 -285.9151) (xy 29.768546 -285.9151) (xy 29.768546 -286.1691) (xy 30.022546 -286.1691)
			)
		)
		(polygon
			(pts
				(xy 30.022546 -285.3563) (xy 29.768546 -285.3563) (xy 29.768546 -285.6103) (xy 30.022546 -285.6103)
			)
		)
		(polygon
			(pts
				(xy 25.9334 -283.4132) (xy 25.6794 -283.4132) (xy 25.6794 -283.6672) (xy 25.9334 -283.6672)
			)
		)
	)
	(zone
		(net "5V_PRE_6")
		(layer "F.Cu")
		(hatch none 0.5)
		(connect_pads
			(clearance 0.5)
		)
		(min_thickness 0.25)
		(fill yes
			(thermal_gap 0.5)
			(thermal_bridge_width 0.5)
			(island_removal_mode 0)
		)
		(polygon
			(pts
				(xy 36.956492 -381.917956) (xy 36.829492 -382.044956) (xy 36.829492 -382.679956) (xy 36.956492 -382.806956)
				(xy 47.370492 -382.806956) (xy 50.418492 -385.854956) (xy 56.641492 -385.854956) (xy 56.895492 -385.600956)
				(xy 56.895492 -383.187956) (xy 56.641492 -382.933956) (xy 50.799492 -382.933956) (xy 49.783492 -381.917956)
			)
		)
	)
	(zone
		(net "P12V")
		(layer "F.Cu")
		(hatch none 0.5)
		(connect_pads
			(clearance 0.5)
		)
		(min_thickness 0.25)
		(fill yes
			(thermal_gap 0.5)
			(thermal_bridge_width 0.5)
			(island_removal_mode 0)
		)
		(polygon
			(pts
				(xy 45.212 -410.337) (xy 44.831 -410.718) (xy 44.831 -415.4932) (xy 45.291502 -415.953702) (xy 49.812702 -415.953702)
				(xy 50.165 -416.306) (xy 51.816 -416.306) (xy 51.943 -416.179) (xy 51.943 -415.417) (xy 51.816 -415.29)
				(xy 50.418746 -415.29) (xy 49.910746 -414.782) (xy 49.910746 -413.0548) (xy 50.3428 -412.622746)
				(xy 50.3428 -410.972) (xy 49.7078 -410.337)
			)
		)
		(polygon
			(pts
				(xy 51.4096 -415.5948) (xy 51.1556 -415.5948) (xy 51.1556 -415.8488) (xy 51.4096 -415.8488)
			)
		)
		(polygon
			(pts
				(xy 50.9778 -415.544) (xy 50.7238 -415.544) (xy 50.7238 -415.798) (xy 50.9778 -415.798)
			)
		)
		(polygon
			(pts
				(xy 50.3682 -415.544) (xy 50.1142 -415.544) (xy 50.1142 -415.798) (xy 50.3682 -415.798)
			)
		)
		(polygon
			(pts
				(xy 49.466246 -414.328102) (xy 49.212246 -414.328102) (xy 49.212246 -414.582102) (xy 49.466246 -414.582102)
			)
		)
		(polygon
			(pts
				(xy 49.466246 -413.769302) (xy 49.212246 -413.769302) (xy 49.212246 -414.023302) (xy 49.466246 -414.023302)
			)
		)
	)
	(zone
		(layer "F.Cu")
		(hatch none 0.5)
		(connect_pads
			(clearance 0.5)
		)
		(min_thickness 0.25)
		(fill
			(thermal_gap 0.5)
			(thermal_bridge_width 0.5)
			(island_removal_mode 0)
		)
		(polygon
			(pts
				(xy 228.726746 -3.8227) (xy 228.091746 -4.4577) (xy 228.091746 -9.4107) (xy 231.393746 -12.7127)
				(xy 233.933746 -12.7127) (xy 234.314746 -12.3317) (xy 234.314746 -4.4577) (xy 233.679746 -3.8227)
			)
		)
	)
	(zone
		(net "P5V_HDD12")
		(layer "F.Cu")
		(hatch none 0.5)
		(connect_pads
			(clearance 0.5)
		)
		(min_thickness 0.25)
		(fill yes
			(thermal_gap 0.5)
			(thermal_bridge_width 0.5)
			(island_removal_mode 0)
		)
		(polygon
			(pts
				(xy 45.9613 -225.9457) (xy 39.775638 -225.9457) (xy 39.725854 -225.9457) (xy 39.242746 -225.9457)
				(xy 39.115746 -226.0727) (xy 39.115746 -227.8507) (xy 39.496746 -228.2317) (xy 42.798746 -228.2317)
				(xy 43.433746 -228.8667) (xy 43.433746 -230.6447) (xy 44.576746 -231.7877) (xy 44.577 -231.7877)
				(xy 44.95165 -232.16235) (xy 49.253394 -232.16235) (xy 49.374044 -232.283) (xy 51.180746 -234.089702)
				(xy 57.149746 -234.089702) (xy 57.403746 -233.835702) (xy 57.403746 -231.041702) (xy 57.276746 -230.914702)
				(xy 53.847746 -230.914702) (xy 48.878744 -225.9457)
			)
		)
		(polygon
			(pts
				(xy 47.116746 -231.549702) (xy 46.862746 -231.549702) (xy 46.862746 -231.803702) (xy 47.116746 -231.803702)
			)
		)
		(polygon
			(pts
				(xy 45.973746 -231.549702) (xy 45.719746 -231.549702) (xy 45.719746 -231.803702) (xy 45.973746 -231.803702)
			)
		)
		(polygon
			(pts
				(xy 45.973746 -228.755702) (xy 45.719746 -228.755702) (xy 45.719746 -229.009702) (xy 45.973746 -229.009702)
			)
		)
		(polygon
			(pts
				(xy 41.833546 -226.850702) (xy 41.579546 -226.850702) (xy 41.579546 -227.104702) (xy 41.833546 -227.104702)
			)
		)
		(polygon
			(pts
				(xy 40.969946 -226.850702) (xy 40.715946 -226.850702) (xy 40.715946 -227.104702) (xy 40.969946 -227.104702)
			)
		)
	)
	(zone
		(net "5V_PRE_13")
		(layer "F.Cu")
		(hatch none 0.5)
		(connect_pads
			(clearance 0.5)
		)
		(min_thickness 0.25)
		(fill yes
			(thermal_gap 0.5)
			(thermal_bridge_width 0.5)
			(island_removal_mode 0)
		)
		(polygon
			(pts
				(xy 20.700746 -123.2027) (xy 20.573746 -123.3297) (xy 20.573746 -123.9647) (xy 20.700746 -124.0917)
				(xy 23.367746 -124.0917) (xy 23.875746 -124.5997) (xy 25.780746 -124.5997) (xy 26.161746 -124.2187)
				(xy 26.161746 -123.9647) (xy 25.399746 -123.2027)
			)
		)
	)
	(zone
		(net "P12V_HDD14")
		(layer "F.Cu")
		(hatch none 0.5)
		(connect_pads
			(clearance 0.5)
		)
		(min_thickness 0.25)
		(fill yes
			(thermal_gap 0.5)
			(thermal_bridge_width 0.5)
			(island_removal_mode 0)
		)
		(polygon
			(pts
				(xy 81.534 -2.667) (xy 81.1784 -3.0226) (xy 81.1784 -6.7564) (xy 81.0514 -6.8834) (xy 73.0758 -6.8834)
				(xy 72.9234 -7.0358) (xy 72.9234 -7.874) (xy 73.2028 -8.1534) (xy 73.672446 -8.1534) (xy 74.802746 -9.2837)
				(xy 75.6412 -9.2837) (xy 75.6412 -9.2964) (xy 76.073 -9.7282) (xy 76.073 -10.807954) (xy 76.580746 -11.3157)
				(xy 77.723746 -12.4587) (xy 82.803746 -12.4587) (xy 82.816446 -12.446) (xy 83.693 -12.446) (xy 85.217 -10.922)
				(xy 90.690446 -10.922) (xy 92.201746 -9.4107) (xy 92.201746 -3.174746) (xy 91.694 -2.667)
			)
		)
		(polygon
			(pts
				(xy 80.390746 -9.553702) (xy 80.136746 -9.553702) (xy 80.136746 -9.807702) (xy 80.390746 -9.807702)
			)
		)
		(polygon
			(pts
				(xy 79.247746 -9.553702) (xy 78.993746 -9.553702) (xy 78.993746 -9.807702) (xy 79.247746 -9.807702)
			)
		)
		(polygon
			(pts
				(xy 73.989946 -7.648702) (xy 73.735946 -7.648702) (xy 73.735946 -7.902702) (xy 73.989946 -7.902702)
			)
		)
	)
	(zone
		(layer "F.Cu")
		(hatch none 0.5)
		(connect_pads
			(clearance 0)
		)
		(min_thickness 0.25)
		(keepout
			(tracks allowed)
			(vias allowed)
			(pads allowed)
			(copperpour allowed)
			(footprints not_allowed)
		)
		(placement
			(enabled no)
			(sheetname "")
		)
		(fill
			(thermal_gap 0.5)
			(thermal_bridge_width 0.5)
			(island_removal_mode 0)
		)
		(polygon
			(pts
				(arc
					(start 252.499876 -484.000048)
					(mid 248.499884 -480.000056)
					(end 252.499876 -476.000064)
				)
				(arc
					(start 252.499876 -476.000064)
					(mid 256.499868 -480.000056)
					(end 252.499876 -484.000048)
				)
			)
		)
	)
	(zone
		(layer "F.Cu")
		(hatch none 0.5)
		(connect_pads
			(clearance 0)
		)
		(min_thickness 0.25)
		(keepout
			(tracks not_allowed)
			(vias allowed)
			(pads allowed)
			(copperpour not_allowed)
			(footprints allowed)
		)
		(placement
			(enabled no)
			(sheetname "")
		)
		(fill
			(thermal_gap 0.5)
			(thermal_bridge_width 0.5)
			(island_removal_mode 0)
		)
		(polygon
			(pts
				(arc
					(start 28.296362 -235.819442)
					(mid 27.75496 -235.190547)
					(end 27.12593 -235.731812)
				)
				(xy 27.111452 -235.925106)
				(arc
					(start 27.314652 -235.925106)
					(mid 27.382156 -235.919004)
					(end 27.447494 -235.900976)
				)
				(arc
					(start 27.447494 -235.900976)
					(mid 27.939681 -235.593763)
					(end 27.529536 -236.0041)
				)
				(arc
					(start 27.529536 -236.0041)
					(mid 27.437839 -236.03681)
					(end 27.341576 -236.051344)
				)
				(xy 27.341068 -236.052106) (xy 27.102054 -236.052106) (xy 27.086814 -236.255306) (xy 27.486356 -236.255306)
				(arc
					(start 27.488134 -236.257338)
					(mid 27.550589 -236.276632)
					(end 27.603704 -236.314742)
				)
				(arc
					(start 27.603704 -236.314742)
					(mid 27.619356 -236.331411)
					(end 27.63393 -236.349032)
				)
				(arc
					(start 27.63393 -236.349032)
					(mid 27.730811 -236.92052)
					(end 27.495246 -236.390942)
				)
				(arc
					(start 27.495246 -236.390942)
					(mid 27.478117 -236.384472)
					(end 27.45994 -236.382306)
				)
				(xy 27.077416 -236.382306)
				(arc
					(start 27.061414 -236.59719)
					(mid 27.602942 -237.226094)
					(end 28.231846 -236.684566)
				)
			)
		)
	)
	(zone
		(layer "F.Cu")
		(hatch none 0.5)
		(connect_pads
			(clearance 0)
		)
		(min_thickness 0.25)
		(keepout
			(tracks allowed)
			(vias allowed)
			(pads allowed)
			(copperpour allowed)
			(footprints allowed)
		)
		(placement
			(enabled no)
			(sheetname "")
		)
		(fill
			(thermal_gap 0.5)
			(thermal_bridge_width 0.5)
			(island_removal_mode 0)
		)
		(polygon
			(pts
				(xy 15.7988 -469.0364) (xy 15.7988 -466.7758) (xy 17.018 -466.7758) (xy 17.018 -469.0364)
			)
		)
	)
	(zone
		(layer "F.Cu")
		(hatch none 0.5)
		(connect_pads
			(clearance 0)
		)
		(min_thickness 0.25)
		(keepout
			(tracks not_allowed)
			(vias allowed)
			(pads allowed)
			(copperpour not_allowed)
			(footprints allowed)
		)
		(placement
			(enabled no)
			(sheetname "")
		)
		(fill
			(thermal_gap 0.5)
			(thermal_bridge_width 0.5)
			(island_removal_mode 0)
		)
		(polygon
			(pts
				(arc
					(start 223.750124 -163.975796)
					(mid 223.163511 -163.388802)
					(end 222.576644 -163.975542)
				)
				(arc
					(start 222.576644 -164.934392)
					(mid 223.163384 -165.521132)
					(end 223.750124 -164.934392)
				)
				(xy 223.750124 -164.6682) (xy 223.632776 -164.6682)
				(arc
					(start 223.61906 -164.668708)
					(mid 223.520495 -164.692901)
					(end 223.436942 -164.750496)
				)
				(arc
					(start 223.410018 -164.777674)
					(mid 222.956758 -165.141018)
					(end 223.320102 -164.687758)
				)
				(xy 223.347026 -164.660834) (xy 223.34728 -164.66058) (xy 223.365568 -164.642292)
				(arc
					(start 223.366838 -164.642292)
					(mid 223.479618 -164.572229)
					(end 223.6089 -164.541962)
				)
				(xy 223.609662 -164.5412) (xy 223.632268 -164.5412) (xy 223.636332 -164.5412) (xy 223.750124 -164.5412)
				(xy 223.750124 -164.338) (xy 223.557084 -164.338)
				(arc
					(start 223.556068 -164.336984)
					(mid 223.447241 -164.310926)
					(end 223.351852 -164.252402)
				)
				(xy 223.350328 -164.252402)
				(arc
					(start 223.320102 -164.222176)
					(mid 222.956758 -163.768916)
					(end 223.410018 -164.13226)
				)
				(arc
					(start 223.421702 -164.143944)
					(mid 223.495936 -164.193545)
					(end 223.5835 -164.211)
				)
				(xy 223.750124 -164.211)
			)
		)
	)
	(zone
		(layer "F.Cu")
		(hatch none 0.5)
		(connect_pads
			(clearance 0)
		)
		(min_thickness 0.25)
		(keepout
			(tracks allowed)
			(vias allowed)
			(pads allowed)
			(copperpour allowed)
			(footprints not_allowed)
		)
		(placement
			(enabled no)
			(sheetname "")
		)
		(fill
			(thermal_gap 0.5)
			(thermal_bridge_width 0.5)
			(island_removal_mode 0)
		)
		(polygon
			(pts
				(xy 34.99993 -503.00001) (xy 34.99993 -447.28003) (xy 27.999944 -447.28003) (xy 27.999944 -464.829906)
				(xy 16.889984 -464.829906) (xy 16.889984 -503.00001) (xy 25.694894 -503.00001) (xy 25.694894 -506.000004)
				(arc
					(start 0.999998 -506.000004)
					(mid 0.292893 -505.707111)
					(end 0 -505.000006)
				)
				(xy 0 -461.449928) (xy 0.500126 -460.950056)
				(arc
					(start 5.050028 -460.950056)
					(mid 5.999988 -460.000096)
					(end 5.050028 -459.049882)
				)
				(xy 0.500126 -459.049882) (xy 0 -458.55001) (xy 0 -357.449882) (xy 0.500126 -356.95001)
				(arc
					(start 5.050028 -356.95001)
					(mid 5.999988 -356.00005)
					(end 5.050028 -355.05009)
				)
				(xy 0.500126 -355.05009) (xy 0 -354.549964) (xy 0 -306.649882) (xy 0.500126 -306.15001)
				(arc
					(start 5.050028 -306.15001)
					(mid 5.999988 -305.20005)
					(end 5.050028 -304.25009)
				)
				(xy 0.500126 -304.25009) (xy 0 -303.749964) (xy 0 -211.44992) (xy 0.500126 -210.950048)
				(arc
					(start 5.050028 -210.950048)
					(mid 5.999988 -210.000088)
					(end 5.050028 -209.049874)
				)
				(xy 0.500126 -209.049874) (xy 0 -208.550002) (xy 0 -107.449874) (xy 0.500126 -106.950002)
				(arc
					(start 5.050028 -106.950002)
					(mid 5.999988 -106.000042)
					(end 5.050028 -105.050082)
				)
				(xy 0.500126 -105.050082) (xy 0 -104.549956) (xy 0 -56.649874) (xy 0.500126 -56.150002)
				(arc
					(start 5.050028 -56.150002)
					(mid 5.999988 -55.200042)
					(end 5.050028 -54.250082)
				)
				(xy 0.500126 -54.250082) (xy 0 -53.749956) (xy 0 -24.500078) (xy 24.99995 -24.500078) (xy 24.99995 -51.839876)
				(xy 16.889984 -51.839876) (xy 16.889984 -66.8401) (xy 31.999936 -66.8401) (xy 31.999936 -41.170098)
				(xy 43.109896 -41.170098) (xy 43.109896 -8.999982) (xy 24.99995 -8.999982) (xy 24.99995 -23.999952)
				(xy 0 -23.999952)
				(arc
					(start 0 -0.999998)
					(mid 0.292893 -0.292893)
					(end 0.999998 0)
				)
				(xy 212.205062 0) (xy 212.205062 -0.999998) (xy 204.900022 -0.999998) (xy 204.900022 -67.840098)
				(xy 220.009974 -67.840098) (xy 220.009974 -41.170098) (xy 231.119934 -41.170098) (xy 231.119934 -8.999982)
				(xy 220.009974 -8.999982) (xy 220.009974 -0.999998) (xy 212.704934 -0.999998) (xy 212.704934 0)
				(arc
					(start 261.500112 0)
					(mid 262.207217 -0.292893)
					(end 262.50011 -0.999998)
				)
				(xy 262.50011 -361.920028) (xy 261.500112 -362.920026)
				(arc
					(start 260.150102 -362.920026)
					(mid 259.266101 -363.286033)
					(end 258.899914 -364.16996)
				)
				(xy 258.899914 -408.414982) (xy 257.899916 -409.41498)
				(arc
					(start 251.394976 -409.41498)
					(mid 250.859798 -409.950158)
					(end 251.394976 -410.485082)
				)
				(xy 257.899916 -410.485082) (xy 258.899914 -411.48508)
				(arc
					(start 258.899914 -425.829984)
					(mid 259.266101 -426.713911)
					(end 260.150102 -427.079918)
				)
				(xy 261.500112 -427.079918) (xy 262.50011 -428.079916) (xy 262.50011 -436.909972) (xy 220.989906 -436.909972)
				(xy 220.989906 -433.159916) (xy 212.989922 -433.159916) (xy 212.989922 -441.1599) (xy 220.989906 -441.1599)
				(xy 220.989906 -437.410098) (xy 262.50011 -437.410098)
				(arc
					(start 262.50011 -505.000006)
					(mid 262.207217 -505.707111)
					(end 261.500112 -506.000004)
				)
				(xy 26.19502 -506.000004) (xy 26.19502 -503.00001)
			)
		)
	)
	(zone
		(net "P5VC")
		(layer "F.Cu")
		(hatch none 0.5)
		(connect_pads
			(clearance 0.5)
		)
		(min_thickness 0.25)
		(fill yes
			(thermal_gap 0.5)
			(thermal_bridge_width 0.5)
			(island_removal_mode 0)
		)
		(polygon
			(pts
				(xy 87.248746 -25.0317) (xy 86.994746 -25.2857) (xy 86.994746 -29.4767) (xy 86.994746 -30.098746)
				(xy 87.503 -30.607) (xy 94.488 -30.607) (xy 95.123 -29.972) (xy 95.123 -25.527) (xy 94.615 -25.019)
				(xy 92.214446 -25.019) (xy 92.201746 -25.0317)
			)
		)
	)
	(zone
		(net "P5V_HDD14")
		(layer "F.Cu")
		(hatch none 0.5)
		(connect_pads
			(clearance 0.5)
		)
		(min_thickness 0.25)
		(fill yes
			(thermal_gap 0.5)
			(thermal_bridge_width 0.5)
			(island_removal_mode 0)
		)
		(polygon
			(pts
				(xy 80.787748 -15.3797) (xy 73.913746 -15.3797) (xy 73.278746 -16.0147) (xy 73.278746 -17.0307)
				(xy 73.786746 -17.5387) (xy 75.691746 -17.5387) (xy 76.580746 -18.4277) (xy 76.580746 -20.7137)
				(xy 76.961746 -21.0947) (xy 82.279744 -21.0947) (xy 82.789522 -21.604478) (xy 84.454746 -23.269702)
				(xy 90.636344 -23.269702) (xy 90.830146 -23.0759) (xy 90.830146 -20.374102) (xy 90.550746 -20.094702)
				(xy 86.867746 -20.094702) (xy 82.152744 -15.3797)
			)
		)
		(polygon
			(pts
				(xy 80.390746 -18.062702) (xy 80.136746 -18.062702) (xy 80.136746 -18.316702) (xy 80.390746 -18.316702)
			)
		)
		(polygon
			(pts
				(xy 79.247746 -18.062702) (xy 78.993746 -18.062702) (xy 78.993746 -18.316702) (xy 79.247746 -18.316702)
			)
		)
		(polygon
			(pts
				(xy 75.234546 -16.030702) (xy 74.980546 -16.030702) (xy 74.980546 -16.284702) (xy 75.234546 -16.284702)
			)
		)
		(polygon
			(pts
				(xy 74.370946 -16.030702) (xy 74.116946 -16.030702) (xy 74.116946 -16.284702) (xy 74.370946 -16.284702)
			)
		)
	)
	(zone
		(net "12V_PRE_13")
		(layer "F.Cu")
		(hatch none 0.5)
		(connect_pads
			(clearance 0.5)
		)
		(min_thickness 0.25)
		(fill yes
			(thermal_gap 0.5)
			(thermal_bridge_width 0.5)
			(island_removal_mode 0)
		)
		(polygon
			(pts
				(xy 20.599146 -115.6335) (xy 20.548346 -115.6843) (xy 20.548346 -116.4717) (xy 20.649946 -116.5733)
				(xy 23.342346 -116.5733) (xy 23.875746 -117.1067) (xy 25.907746 -117.1067) (xy 26.034746 -116.9797)
				(xy 26.034746 -115.7605) (xy 25.907746 -115.6335)
			)
		)
	)
	(zone
		(net "12V_PRE_8")
		(layer "F.Cu")
		(hatch none 0.5)
		(connect_pads
			(clearance 0.5)
		)
		(min_thickness 0.25)
		(fill yes
			(thermal_gap 0.5)
			(thermal_bridge_width 0.5)
			(island_removal_mode 0)
		)
		(polygon
			(pts
				(xy 36.956746 -183.5277) (xy 36.829746 -183.6547) (xy 36.829746 -184.2897) (xy 37.083746 -184.5437)
				(xy 46.100746 -184.5437) (xy 50.164746 -188.6077) (xy 56.387746 -188.6077) (xy 56.514746 -188.4807)
				(xy 56.514746 -185.9407) (xy 56.387746 -185.8137) (xy 50.291746 -185.8137) (xy 48.005746 -183.5277)
			)
		)
	)
	(zone
		(layer "F.Cu")
		(hatch none 0.5)
		(connect_pads
			(clearance 0)
		)
		(min_thickness 0.25)
		(keepout
			(tracks not_allowed)
			(vias allowed)
			(pads allowed)
			(copperpour not_allowed)
			(footprints allowed)
		)
		(placement
			(enabled no)
			(sheetname "")
		)
		(fill
			(thermal_gap 0.5)
			(thermal_bridge_width 0.5)
			(island_removal_mode 0)
		)
		(polygon
			(pts
				(arc
					(start 7.919212 -352.4377)
					(mid 7.934248 -352.51356)
					(end 7.977124 -352.577908)
				)
				(xy 7.977632 -352.578162)
				(arc
					(start 8.055864 -352.656648)
					(mid 8.419607 -353.109399)
					(end 7.966202 -352.746564)
				)
				(xy 7.887716 -352.668078) (xy 7.887208 -352.66757) (xy 7.869174 -352.649282)
				(arc
					(start 7.869174 -352.647758)
					(mid 7.817169 -352.562319)
					(end 7.793482 -352.465132)
				)
				(xy 7.792212 -352.464116) (xy 7.792212 -352.443288) (xy 7.589012 -352.53168) (xy 7.589012 -352.883216)
				(arc
					(start 7.58825 -352.883724)
					(mid 7.55724 -353.033097)
					(end 7.483094 -353.166426)
				)
				(arc
					(start 7.483094 -353.166426)
					(mid 7.035962 -353.537017)
					(end 7.391146 -353.077526)
				)
				(arc
					(start 7.391146 -353.077526)
					(mid 7.443854 -352.972714)
					(end 7.462012 -352.8568)
				)
				(xy 7.462012 -352.587052) (xy 7.00405 -352.786188) (xy 7.003796 -352.786442)
				(arc
					(start 7.004812 -352.788728)
					(mid 6.70054 -353.560934)
					(end 7.47268 -353.864926)
				)
				(xy 7.473696 -353.867212) (xy 8.447532 -353.443794)
				(arc
					(start 8.446516 -353.441508)
					(mid 8.750808 -352.669348)
					(end 7.978648 -352.365056)
				)
				(xy 7.977632 -352.36277) (xy 7.919212 -352.38817)
			)
		)
	)
	(zone
		(layer "F.Cu")
		(hatch none 0.5)
		(connect_pads
			(clearance 0)
		)
		(min_thickness 0.25)
		(keepout
			(tracks not_allowed)
			(vias allowed)
			(pads allowed)
			(copperpour not_allowed)
			(footprints allowed)
		)
		(placement
			(enabled no)
			(sheetname "")
		)
		(fill
			(thermal_gap 0.5)
			(thermal_bridge_width 0.5)
			(island_removal_mode 0)
		)
		(polygon
			(pts
				(arc
					(start 9.857486 -131.515104)
					(mid 9.270873 -130.92811)
					(end 8.684006 -131.51485)
				)
				(xy 8.684006 -131.767072)
				(arc
					(start 8.762746 -131.767072)
					(mid 8.904505 -131.746605)
					(end 9.03478 -131.687062)
				)
				(arc
					(start 9.03478 -131.687062)
					(mid 9.461419 -131.293572)
					(end 9.134094 -131.772914)
				)
				(arc
					(start 9.134094 -131.772914)
					(mid 8.970812 -131.858736)
					(end 8.78967 -131.893564)
				)
				(xy 8.789162 -131.894072) (xy 8.684006 -131.894072) (xy 8.684006 -132.097272) (xy 8.789162 -132.097272)
				(arc
					(start 8.78967 -132.09778)
					(mid 8.969666 -132.132024)
					(end 9.132316 -132.216398)
				)
				(arc
					(start 9.132316 -132.216398)
					(mid 9.463872 -132.69278)
					(end 9.033764 -132.303012)
				)
				(arc
					(start 9.033764 -132.303012)
					(mid 8.903856 -132.244384)
					(end 8.762746 -132.224272)
				)
				(xy 8.684006 -132.224272)
				(arc
					(start 8.684006 -132.4737)
					(mid 9.270746 -133.06044)
					(end 9.857486 -132.4737)
				)
			)
		)
	)
	(zone
		(layer "F.Cu")
		(hatch none 0.5)
		(connect_pads
			(clearance 0)
		)
		(min_thickness 0.25)
		(keepout
			(tracks allowed)
			(vias allowed)
			(pads allowed)
			(copperpour allowed)
			(footprints not_allowed)
		)
		(placement
			(enabled no)
			(sheetname "")
		)
		(fill
			(thermal_gap 0.5)
			(thermal_bridge_width 0.5)
			(island_removal_mode 0)
		)
		(polygon
			(pts
				(arc
					(start 7.500112 -82.63001)
					(mid 3.50012 -78.630018)
					(end 7.500112 -74.630026)
				)
				(arc
					(start 7.500112 -74.630026)
					(mid 11.500104 -78.630018)
					(end 7.500112 -82.63001)
				)
			)
		)
	)
	(zone
		(net "P5VA")
		(layer "F.Cu")
		(hatch none 0.5)
		(connect_pads
			(clearance 0.5)
		)
		(min_thickness 0.25)
		(fill yes
			(thermal_gap 0.5)
			(thermal_bridge_width 0.5)
			(island_removal_mode 0)
		)
		(polygon
			(pts
				(xy 202.278742 -73.170034) (xy 201.897742 -73.551034) (xy 201.897742 -78.504034) (xy 202.151742 -78.758034)
				(xy 206.342742 -78.758034) (xy 206.723742 -78.377034) (xy 206.723742 -73.424034) (xy 206.469742 -73.170034)
			)
		)
	)
	(zone
		(net "GND")
		(layer "F.Cu")
		(hatch none 0.5)
		(connect_pads
			(clearance 0.5)
		)
		(min_thickness 0.25)
		(fill yes
			(thermal_gap 0.5)
			(thermal_bridge_width 0.5)
			(island_removal_mode 0)
		)
		(polygon
			(pts
				(xy 11.556746 -409.5877) (xy 11.048746 -410.0957) (xy 11.048746 -414.019746) (xy 15.2527 -418.2237)
				(xy 21.843746 -418.2237) (xy 23.367746 -416.6997) (xy 32.893 -416.6997) (xy 32.9819 -416.6108) (xy 32.9946 -416.6108)
				(xy 33.02 -416.5854) (xy 33.02 -415.3154) (xy 33.0327 -415.3027) (xy 33.0327 -410.6164) (xy 32.004 -409.5877)
			)
		)
		(polygon
			(pts
				(xy 26.4922 -415.671) (xy 26.2382 -415.671) (xy 26.2382 -415.925) (xy 26.4922 -415.925)
			)
		)
		(polygon
			(pts
				(xy 25.6286 -415.671) (xy 25.3746 -415.671) (xy 25.3746 -415.925) (xy 25.6286 -415.925)
			)
		)
	)
	(zone
		(net "P5VA")
		(layer "F.Cu")
		(hatch none 0.5)
		(connect_pads
			(clearance 0.5)
		)
		(min_thickness 0.25)
		(fill yes
			(thermal_gap 0.5)
			(thermal_bridge_width 0.5)
			(island_removal_mode 0)
		)
		(polygon
			(pts
				(xy 202.437746 -277.6347) (xy 202.056746 -278.0157) (xy 202.056746 -284.1117) (xy 202.310746 -284.3657)
				(xy 205.231746 -284.3657) (xy 205.232762 -284.366716) (xy 205.99273 -284.366716) (xy 206.501746 -283.8577)
				(xy 206.501746 -278.5237) (xy 205.612746 -277.6347)
			)
		)
	)
	(zone
		(net "P12V")
		(layer "F.Cu")
		(hatch none 0.5)
		(connect_pads
			(clearance 0.5)
		)
		(min_thickness 0.25)
		(fill yes
			(thermal_gap 0.5)
			(thermal_bridge_width 0.5)
			(island_removal_mode 0)
		)
		(polygon
			(pts
				(xy 6.5532 -35.433) (xy 9.525 -35.433) (xy 9.906 -35.052) (xy 9.906 -29.083) (xy 9.144 -28.321)
				(xy 6.5532 -28.321) (xy 6.1976 -28.6766) (xy 6.1976 -35.0774)
			)
		)
		(polygon
			(pts
				(xy 7.239 -30.607) (xy 6.985 -30.607) (xy 6.985 -30.861) (xy 7.239 -30.861)
			)
		)
		(polygon
			(pts
				(xy 7.239 -29.845) (xy 6.985 -29.845) (xy 6.985 -30.099) (xy 7.239 -30.099)
			)
		)
		(polygon
			(pts
				(xy 7.239 -29.337) (xy 6.985 -29.337) (xy 6.985 -29.591) (xy 7.239 -29.591)
			)
		)
		(polygon
			(pts
				(xy 7.239 -28.575) (xy 6.985 -28.575) (xy 6.985 -28.829) (xy 7.239 -28.829)
			)
		)
	)
	(zone
		(layer "F.Cu")
		(hatch none 0.5)
		(connect_pads
			(clearance 0)
		)
		(min_thickness 0.25)
		(keepout
			(tracks not_allowed)
			(vias allowed)
			(pads allowed)
			(copperpour not_allowed)
			(footprints allowed)
		)
		(placement
			(enabled no)
			(sheetname "")
		)
		(fill
			(thermal_gap 0.5)
			(thermal_bridge_width 0.5)
			(island_removal_mode 0)
		)
		(polygon
			(pts
				(arc
					(start 36.486338 -370.618004)
					(mid 36.684383 -370.532966)
					(end 36.895532 -370.489734)
				)
				(xy 36.901374 -370.2812) (xy 36.85413 -370.2812)
				(arc
					(start 36.853622 -370.280692)
					(mid 36.662102 -370.245849)
					(end 36.487862 -370.159026)
				)
				(arc
					(start 36.487862 -370.159026)
					(mid 36.106773 -369.720961)
					(end 36.574984 -370.064284)
				)
				(arc
					(start 36.574984 -370.064284)
					(mid 36.72116 -370.131251)
					(end 36.880292 -370.1542)
				)
				(xy 36.904676 -370.1542) (xy 36.910772 -369.934998) (xy 36.910518 -369.934744)
				(arc
					(start 36.908232 -369.934744)
					(mid 36.337748 -369.332256)
					(end 35.73526 -369.90274)
				)
				(xy 35.73272 -369.90274) (xy 35.707574 -370.823998)
				(arc
					(start 35.710114 -370.823998)
					(mid 36.280598 -371.426486)
					(end 36.883086 -370.856002)
				)
				(xy 36.885626 -370.856002)
				(arc
					(start 36.89223 -370.61775)
					(mid 36.722961 -370.653991)
					(end 36.5633 -370.720874)
				)
				(arc
					(start 36.5633 -370.720874)
					(mid 36.062631 -371.014867)
					(end 36.486338 -370.618004)
				)
			)
		)
	)
	(zone
		(layer "F.Cu")
		(hatch none 0.5)
		(connect_pads
			(clearance 0)
		)
		(min_thickness 0.25)
		(keepout
			(tracks not_allowed)
			(vias allowed)
			(pads allowed)
			(copperpour not_allowed)
			(footprints allowed)
		)
		(placement
			(enabled no)
			(sheetname "")
		)
		(fill
			(thermal_gap 0.5)
			(thermal_bridge_width 0.5)
			(island_removal_mode 0)
		)
		(polygon
			(pts
				(arc
					(start 38.686486 -60.89142)
					(mid 38.099873 -60.304426)
					(end 37.513006 -60.891166)
				)
				(arc
					(start 37.513006 -61.850016)
					(mid 38.099746 -62.436756)
					(end 38.686486 -61.850016)
				)
				(xy 38.686486 -61.61532) (xy 38.499542 -61.61532)
				(arc
					(start 38.493446 -61.615574)
					(mid 38.425414 -61.632244)
					(end 38.367716 -61.671962)
				)
				(arc
					(start 38.34638 -61.693298)
					(mid 37.89312 -62.056642)
					(end 38.256464 -61.603382)
				)
				(xy 38.277546 -61.5823) (xy 38.2778 -61.582046) (xy 38.296088 -61.563758)
				(arc
					(start 38.297866 -61.563758)
					(mid 38.381761 -61.512644)
					(end 38.47719 -61.489336)
				)
				(xy 38.478206 -61.48832) (xy 38.49878 -61.48832) (xy 38.504876 -61.48832) (xy 38.686486 -61.48832)
				(xy 38.686486 -61.28512) (xy 38.488112 -61.28512)
				(arc
					(start 38.486842 -61.283596)
					(mid 38.412665 -61.264792)
					(end 38.346888 -61.225684)
				)
				(xy 38.344856 -61.225684) (xy 38.326314 -61.207142) (xy 38.32606 -61.207142)
				(arc
					(start 38.256464 -61.137546)
					(mid 37.89312 -60.684286)
					(end 38.34638 -61.04763)
				)
				(arc
					(start 38.415976 -61.11748)
					(mid 38.461221 -61.147556)
					(end 38.514528 -61.15812)
				)
				(xy 38.686486 -61.15812)
			)
		)
	)
	(zone
		(layer "F.Cu")
		(hatch none 0.5)
		(connect_pads
			(clearance 0)
		)
		(min_thickness 0.25)
		(keepout
			(tracks not_allowed)
			(vias allowed)
			(pads allowed)
			(copperpour not_allowed)
			(footprints allowed)
		)
		(placement
			(enabled no)
			(sheetname "")
		)
		(fill
			(thermal_gap 0.5)
			(thermal_bridge_width 0.5)
			(island_removal_mode 0)
		)
		(polygon
			(pts
				(arc
					(start 220.782896 -472.907614)
					(mid 220.196283 -472.32062)
					(end 219.609416 -472.90736)
				)
				(arc
					(start 219.609416 -473.86621)
					(mid 220.196156 -474.45295)
					(end 220.782896 -473.86621)
				)
				(xy 220.782896 -473.615258)
				(arc
					(start 220.751146 -473.615258)
					(mid 220.589203 -473.638183)
					(end 220.439996 -473.705174)
				)
				(arc
					(start 220.439996 -473.705174)
					(mid 219.994342 -474.077543)
					(end 220.345762 -473.615258)
				)
				(arc
					(start 220.345762 -473.615258)
					(mid 220.525928 -473.524891)
					(end 220.724222 -473.488766)
				)
				(xy 220.72473 -473.488258) (xy 220.782896 -473.488258) (xy 220.782896 -473.285058) (xy 220.483938 -473.285058)
				(arc
					(start 220.483176 -473.284042)
					(mid 220.365054 -473.255951)
					(end 220.261942 -473.19184)
				)
				(arc
					(start 220.261942 -473.19184)
					(mid 220.063335 -472.646993)
					(end 220.388942 -473.126816)
				)
				(arc
					(start 220.388942 -473.126816)
					(mid 220.447665 -473.15014)
					(end 220.510354 -473.158058)
				)
				(xy 220.782896 -473.158058)
			)
		)
	)
	(zone
		(net "P5VB")
		(layer "F.Cu")
		(hatch none 0.5)
		(connect_pads
			(clearance 0.5)
		)
		(min_thickness 0.25)
		(fill yes
			(thermal_gap 0.5)
			(thermal_bridge_width 0.5)
			(island_removal_mode 0)
		)
		(polygon
			(pts
				(xy 56.133746 -290.8427) (xy 55.625746 -291.3507) (xy 55.625746 -296.4307) (xy 56.641746 -297.4467)
				(xy 68.579746 -297.4467) (xy 69.849746 -296.1767) (xy 69.849746 -291.8587) (xy 68.833746 -290.8427)
			)
		)
	)
	(zone
		(net "12V_PRE_4")
		(layer "F.Cu")
		(hatch none 0.5)
		(connect_pads
			(clearance 0.5)
		)
		(min_thickness 0.25)
		(fill yes
			(thermal_gap 0.5)
			(thermal_bridge_width 0.5)
			(island_removal_mode 0)
		)
		(polygon
			(pts
				(xy 217.931746 -80.6577) (xy 217.550746 -81.0387) (xy 217.550746 -83.7057) (xy 217.804746 -83.9597)
				(xy 219.074746 -83.9597) (xy 221.614746 -81.4197) (xy 224.281746 -81.4197) (xy 224.535746 -81.1657)
				(xy 224.535746 -80.7847) (xy 224.408746 -80.6577)
			)
		)
	)
	(zone
		(layer "F.Cu")
		(hatch none 0.5)
		(connect_pads
			(clearance 0.5)
		)
		(min_thickness 0.25)
		(fill
			(thermal_gap 0.5)
			(thermal_bridge_width 0.5)
			(island_removal_mode 0)
		)
		(polygon
			(pts
				(xy 29.717746 -497.2177) (xy 29.463746 -497.4717) (xy 29.463746 -502.793) (xy 29.464 -502.793) (xy 29.972 -503.301)
				(xy 34.925 -503.301) (xy 35.432746 -502.793254) (xy 35.432746 -497.4717) (xy 35.178746 -497.2177)
			)
		)
	)
	(zone
		(net "P5V_HDD0")
		(layer "F.Cu")
		(hatch none 0.5)
		(connect_pads
			(clearance 0.5)
		)
		(min_thickness 0.25)
		(fill yes
			(thermal_gap 0.5)
			(thermal_bridge_width 0.5)
			(island_removal_mode 0)
		)
		(polygon
			(pts
				(xy 207.772 -482.9556) (xy 207.772 -484.5304) (xy 207.771746 -484.5304) (xy 207.771746 -488.0737)
				(xy 208.146396 -488.448604) (xy 209.416396 -488.448604) (xy 209.419698 -488.445302) (xy 211.578698 -488.445302)
				(xy 211.582 -488.448604) (xy 212.731604 -488.448604) (xy 212.956902 -488.448604) (xy 213.487 -488.978702)
				(xy 220.678756 -488.978702) (xy 221.186756 -488.470702) (xy 224.615756 -488.470702) (xy 224.869756 -488.216702)
				(xy 224.869756 -486.438702) (xy 224.615756 -486.184702) (xy 217.014298 -486.184702) (xy 216.9922 -486.2068)
				(xy 216.9414 -486.2068) (xy 216.9414 -486.184702) (xy 216.360756 -486.184702) (xy 215.979756 -485.803702)
				(xy 215.979756 -483.136702) (xy 215.725756 -482.882702) (xy 213.868 -482.882702) (xy 213.585298 -482.6)
				(xy 213.534498 -482.5492) (xy 208.0514 -482.5492) (xy 207.772 -482.8286)
			)
		)
		(polygon
			(pts
				(xy 218.316556 -487.835702) (xy 218.062556 -487.835702) (xy 218.062556 -488.089702) (xy 218.316556 -488.089702)
			)
		)
		(polygon
			(pts
				(xy 217.452956 -487.835702) (xy 217.198956 -487.835702) (xy 217.198956 -488.089702) (xy 217.452956 -488.089702)
			)
		)
		(polygon
			(pts
				(xy 213.630256 -485.727502) (xy 213.376256 -485.727502) (xy 213.376256 -485.981502) (xy 213.630256 -485.981502)
			)
		)
		(polygon
			(pts
				(xy 213.630256 -482.933502) (xy 213.376256 -482.933502) (xy 213.376256 -483.187502) (xy 213.630256 -483.187502)
			)
		)
		(polygon
			(pts
				(xy 212.487256 -482.933502) (xy 212.233256 -482.933502) (xy 212.233256 -483.187502) (xy 212.487256 -483.187502)
			)
		)
	)
	(zone
		(net "P3V3")
		(layer "F.Cu")
		(hatch none 0.5)
		(connect_pads
			(clearance 0.5)
		)
		(min_thickness 0.25)
		(fill yes
			(thermal_gap 0.5)
			(thermal_bridge_width 0.5)
			(island_removal_mode 0)
		)
		(polygon
			(pts
				(xy 189.864746 -281.8257) (xy 189.610746 -282.0797) (xy 189.610746 -284.7467) (xy 189.991746 -285.1277)
				(xy 190.753746 -285.1277) (xy 191.261746 -285.6357) (xy 191.261746 -286.2707) (xy 191.515746 -286.5247)
				(xy 193.547746 -286.5247) (xy 193.801746 -286.2707) (xy 193.801746 -285.5087) (xy 194.436746 -284.8737)
				(xy 197.357746 -284.8737) (xy 197.484746 -285.0007) (xy 197.484746 -286.3977) (xy 197.738746 -286.6517)
				(xy 197.992746 -286.6517) (xy 198.246746 -286.3977) (xy 198.246746 -285.3817) (xy 199.008746 -284.6197)
				(xy 201.040746 -284.6197) (xy 201.167746 -284.7467) (xy 201.421746 -284.7467) (xy 201.675746 -284.4927)
				(xy 201.675746 -282.3337) (xy 201.167746 -281.8257)
			)
		)
		(polygon
			(pts
				(xy 191.930782 -285.697168) (xy 191.676782 -285.697168) (xy 191.676782 -285.951168) (xy 191.930782 -285.951168)
			)
		)
		(polygon
			(pts
				(xy 198.195946 -284.9753) (xy 197.941946 -284.9753) (xy 197.941946 -285.2293) (xy 198.195946 -285.2293)
			)
		)
		(polygon
			(pts
				(xy 198.1708 -282.321) (xy 197.9168 -282.321) (xy 197.9168 -282.575) (xy 198.1708 -282.575)
			)
		)
		(polygon
			(pts
				(xy 197.5612 -282.321) (xy 197.3072 -282.321) (xy 197.3072 -282.575) (xy 197.5612 -282.575)
			)
		)
		(polygon
			(pts
				(xy 193.5988 -282.321) (xy 193.3448 -282.321) (xy 193.3448 -282.575) (xy 193.5988 -282.575)
			)
		)
		(polygon
			(pts
				(xy 192.9892 -282.321) (xy 192.7352 -282.321) (xy 192.7352 -282.575) (xy 192.9892 -282.575)
			)
		)
	)
	(zone
		(layer "F.Cu")
		(hatch none 0.5)
		(connect_pads
			(clearance 0)
		)
		(min_thickness 0.25)
		(keepout
			(tracks not_allowed)
			(vias allowed)
			(pads allowed)
			(copperpour not_allowed)
			(footprints allowed)
		)
		(placement
			(enabled no)
			(sheetname "")
		)
		(fill
			(thermal_gap 0.5)
			(thermal_bridge_width 0.5)
			(island_removal_mode 0)
		)
		(polygon
			(pts
				(arc
					(start 26.416 -341.6935)
					(mid 26.501556 -341.68484)
					(end 26.58364 -341.65921)
				)
				(arc
					(start 26.58364 -341.503254)
					(mid 25.997027 -340.91626)
					(end 25.41016 -341.503)
				)
				(arc
					(start 25.41016 -342.431116)
					(mid 25.9969 -343.017856)
					(end 26.58364 -342.431116)
				)
				(arc
					(start 26.58364 -342.277192)
					(mid 26.441102 -342.220732)
					(end 26.289 -342.2015)
				)
				(arc
					(start 26.289 -342.2015)
					(mid 26.242971 -342.206182)
					(end 26.19883 -342.220042)
				)
				(arc
					(start 26.19883 -342.220042)
					(mid 25.854078 -342.685929)
					(end 26.071576 -342.148668)
				)
				(arc
					(start 26.071576 -342.148668)
					(mid 26.17414 -342.093564)
					(end 26.289 -342.0745)
				)
				(arc
					(start 26.289 -342.0745)
					(mid 26.439484 -342.090061)
					(end 26.58364 -342.135968)
				)
				(arc
					(start 26.58364 -341.794338)
					(mid 26.500827 -341.813871)
					(end 26.416 -341.8205)
				)
				(arc
					(start 26.416 -341.8205)
					(mid 26.283256 -341.800944)
					(end 26.161746 -341.744046)
				)
				(arc
					(start 26.161746 -341.744046)
					(mid 25.783206 -341.303894)
					(end 26.249884 -341.649304)
				)
				(arc
					(start 26.249884 -341.649304)
					(mid 26.330058 -341.682251)
					(end 26.416 -341.6935)
				)
			)
		)
	)
	(zone
		(layer "F.Cu")
		(hatch none 0.5)
		(connect_pads
			(clearance 0)
		)
		(min_thickness 0.25)
		(keepout
			(tracks not_allowed)
			(vias allowed)
			(pads allowed)
			(copperpour not_allowed)
			(footprints allowed)
		)
		(placement
			(enabled no)
			(sheetname "")
		)
		(fill
			(thermal_gap 0.5)
			(thermal_bridge_width 0.5)
			(island_removal_mode 0)
		)
		(polygon
			(pts
				(arc
					(start 29.968444 -31.997396)
					(mid 29.432631 -31.461202)
					(end 28.896564 -31.997142)
				)
				(xy 28.896564 -32.235648) (xy 29.078936 -32.235648)
				(arc
					(start 29.082746 -32.235648)
					(mid 29.154786 -32.226673)
					(end 29.222446 -32.200342)
				)
				(arc
					(start 29.222446 -32.200342)
					(mid 29.590019 -31.751259)
					(end 29.333698 -32.27197)
				)
				(arc
					(start 29.333698 -32.27197)
					(mid 29.227256 -32.330557)
					(end 29.1084 -32.35579)
				)
				(xy 29.107638 -32.356552) (xy 29.092906 -32.356552) (xy 29.082746 -32.356552) (xy 29.078936 -32.356552)
				(xy 28.896564 -32.356552) (xy 28.896564 -32.565848) (xy 29.205936 -32.565848) (xy 29.209746 -32.565848)
				(xy 29.218128 -32.565848) (xy 29.234638 -32.565848)
				(arc
					(start 29.235908 -32.567118)
					(mid 29.378936 -32.622013)
					(end 29.472382 -32.743394)
				)
				(arc
					(start 29.472382 -32.743394)
					(mid 29.458943 -33.323531)
					(end 29.34208 -32.755078)
				)
				(arc
					(start 29.34208 -32.755078)
					(mid 29.284213 -32.704839)
					(end 29.209746 -32.686752)
				)
				(xy 29.205936 -32.686752) (xy 28.896564 -32.686752)
				(arc
					(start 28.896564 -33.0327)
					(mid 29.432504 -33.56864)
					(end 29.968444 -33.0327)
				)
			)
		)
	)
	(zone
		(net "P12V_HDD14")
		(layer "F.Cu")
		(hatch none 0.5)
		(connect_pads
			(clearance 0.5)
		)
		(min_thickness 0.25)
		(fill yes
			(thermal_gap 0.5)
			(thermal_bridge_width 0.5)
			(island_removal_mode 0)
		)
		(polygon
			(pts
				(xy 21.754846 -8.7376) (xy 20.573746 -9.9187) (xy 20.573746 -11.8237) (xy 20.700746 -11.9507) (xy 24.256746 -11.9507)
				(xy 24.263096 -11.944096) (xy 25.444704 -11.944096) (xy 25.7556 -11.6332) (xy 25.7556 -9.1948) (xy 25.2984 -8.7376)
			)
		)
	)
	(zone
		(layer "F.Cu")
		(hatch none 0.5)
		(connect_pads
			(clearance 0)
		)
		(min_thickness 0.25)
		(keepout
			(tracks not_allowed)
			(vias allowed)
			(pads allowed)
			(copperpour not_allowed)
			(footprints allowed)
		)
		(placement
			(enabled no)
			(sheetname "")
		)
		(fill
			(thermal_gap 0.5)
			(thermal_bridge_width 0.5)
			(island_removal_mode 0)
		)
		(polygon
			(pts
				(arc
					(start 6.593586 -165.812216)
					(mid 6.415091 -165.873313)
					(end 6.227572 -165.894004)
				)
				(xy 6.22046 -165.893496) (xy 6.232144 -166.097204) (xy 6.5278 -166.097204)
				(arc
					(start 6.528562 -166.09822)
					(mid 6.662308 -166.132136)
					(end 6.775704 -166.210742)
				)
				(arc
					(start 6.775704 -166.210742)
					(mid 6.865371 -166.33316)
					(end 6.91388 -166.476934)
				)
				(arc
					(start 6.91388 -166.476934)
					(mid 6.866719 -167.05573)
					(end 6.785102 -166.480744)
				)
				(arc
					(start 6.785102 -166.480744)
					(mid 6.748225 -166.38365)
					(end 6.685788 -166.300658)
				)
				(arc
					(start 6.685788 -166.300658)
					(mid 6.601183 -166.244127)
					(end 6.501384 -166.224204)
				)
				(xy 6.239256 -166.224204) (xy 6.272022 -166.797228)
				(arc
					(start 6.274562 -166.796974)
					(mid 6.89102 -167.346884)
					(end 7.44093 -166.730426)
				)
				(xy 7.44347 -166.730172) (xy 7.413752 -166.210742) (xy 7.376922 -165.563804) (xy 7.376668 -165.563804)
				(arc
					(start 7.374382 -165.563804)
					(mid 6.757924 -165.013894)
					(end 6.208014 -165.630352)
				)
				(xy 6.205474 -165.630606) (xy 6.213348 -165.768528)
				(arc
					(start 6.227572 -165.767004)
					(mid 6.377009 -165.751569)
					(end 6.52018 -165.706044)
				)
				(arc
					(start 6.52018 -165.706044)
					(mid 7.031444 -165.430927)
					(end 6.593586 -165.812216)
				)
			)
		)
	)
	(zone
		(layer "F.Cu")
		(hatch none 0.5)
		(connect_pads
			(clearance 0)
		)
		(min_thickness 0.25)
		(keepout
			(tracks allowed)
			(vias allowed)
			(pads allowed)
			(copperpour allowed)
			(footprints not_allowed)
		)
		(placement
			(enabled no)
			(sheetname "")
		)
		(fill
			(thermal_gap 0.5)
			(thermal_bridge_width 0.5)
			(island_removal_mode 0)
		)
		(polygon
			(pts
				(arc
					(start 252.499876 -267.5001)
					(mid 256.499868 -271.500092)
					(end 252.499876 -275.500084)
				)
				(arc
					(start 252.499876 -275.500084)
					(mid 248.499884 -271.500092)
					(end 252.499876 -267.5001)
				)
			)
		)
	)
	(zone
		(layer "F.Cu")
		(hatch none 0.5)
		(connect_pads
			(clearance 0)
		)
		(min_thickness 0.25)
		(keepout
			(tracks not_allowed)
			(vias allowed)
			(pads allowed)
			(copperpour not_allowed)
			(footprints allowed)
		)
		(placement
			(enabled no)
			(sheetname "")
		)
		(fill
			(thermal_gap 0.5)
			(thermal_bridge_width 0.5)
			(island_removal_mode 0)
		)
		(polygon
			(pts
				(arc
					(start 13.388086 -176.752504)
					(mid 12.823063 -176.149766)
					(end 12.220194 -176.714658)
				)
				(arc
					(start 12.213336 -176.923446)
					(mid 12.378123 -176.901699)
					(end 12.5349 -176.846484)
				)
				(arc
					(start 12.5349 -176.846484)
					(mid 13.042407 -176.564311)
					(end 12.609576 -176.951386)
				)
				(arc
					(start 12.609576 -176.951386)
					(mid 12.414989 -177.023417)
					(end 12.209272 -177.050446)
				)
				(arc
					(start 12.202668 -177.25771)
					(mid 12.400823 -177.296199)
					(end 12.58697 -177.374296)
				)
				(arc
					(start 12.58697 -177.374296)
					(mid 13.00927 -177.772818)
					(end 12.509754 -177.476912)
				)
				(arc
					(start 12.509754 -177.476912)
					(mid 12.358571 -177.416084)
					(end 12.198604 -177.384964)
				)
				(arc
					(start 12.192254 -177.578004)
					(mid 12.757404 -178.180746)
					(end 13.360146 -177.615596)
				)
			)
		)
	)
	(zone
		(net "GND")
		(layer "F.Cu")
		(hatch none 0.5)
		(connect_pads
			(clearance 0.5)
		)
		(min_thickness 0.25)
		(fill yes
			(thermal_gap 0.5)
			(thermal_bridge_width 0.5)
			(island_removal_mode 0)
		)
		(polygon
			(pts
				(xy 225.679 -438.277) (xy 225.425 -438.531) (xy 225.425 -439.0136) (xy 224.7646 -439.674) (xy 224.7646 -441.0964)
				(xy 225.2472 -441.579) (xy 226.6442 -441.579) (xy 227.0252 -441.198) (xy 227.0252 -438.404) (xy 226.8982 -438.277)
			)
		)
		(polygon
			(pts
				(xy 226.161854 -438.9247) (xy 225.907854 -438.9247) (xy 225.907854 -439.1787) (xy 226.161854 -439.1787)
			)
		)
	)
	(zone
		(net "P12V_HDD6")
		(layer "F.Cu")
		(hatch none 0.5)
		(connect_pads
			(clearance 0.5)
		)
		(min_thickness 0.25)
		(fill yes
			(thermal_gap 0.5)
			(thermal_bridge_width 0.5)
			(island_removal_mode 0)
		)
		(polygon
			(pts
				(xy 37.083492 -390.807956) (xy 36.829492 -391.061956) (xy 36.829492 -393.982956) (xy 37.083492 -394.236956)
				(xy 40.893492 -394.236956) (xy 43.814492 -397.157956) (xy 61.468 -397.157956) (xy 61.6966 -397.386556)
				(xy 61.6966 -402.0312) (xy 63.0301 -403.3647) (xy 71.881746 -403.3647) (xy 72.0852 -403.160992)
				(xy 72.0852 -397.980154) (xy 72.008746 -397.9037) (xy 69.9008 -397.9037) (xy 69.469 -397.4719) (xy 69.469 -396.367)
				(xy 69.468746 -396.366746) (xy 69.468746 -391.6807) (xy 68.617846 -390.8298) (xy 63.9318 -390.8298)
				(xy 63.445644 -391.315956) (xy 57.657492 -391.315956) (xy 57.276492 -391.696956) (xy 57.276492 -394.109956)
				(xy 56.895492 -394.490956) (xy 46.354492 -394.490956) (xy 42.671492 -390.807956)
			)
		)
		(polygon
			(pts
				(xy 61.086746 -393.9667) (xy 60.832746 -393.9667) (xy 60.832746 -394.2207) (xy 61.086746 -394.2207)
			)
		)
		(polygon
			(pts
				(xy 59.943746 -393.9667) (xy 59.689746 -393.9667) (xy 59.689746 -394.2207) (xy 59.943746 -394.2207)
			)
		)
		(polygon
			(pts
				(xy 64.8716 -391.5918) (xy 64.6176 -391.5918) (xy 64.6176 -391.8458) (xy 64.8716 -391.8458)
			)
		)
		(polygon
			(pts
				(xy 64.008 -391.5918) (xy 63.754 -391.5918) (xy 63.754 -391.8458) (xy 64.008 -391.8458)
			)
		)
	)
	(zone
		(layer "F.Cu")
		(hatch none 0.5)
		(connect_pads
			(clearance 0.5)
		)
		(min_thickness 0.25)
		(fill
			(thermal_gap 0.5)
			(thermal_bridge_width 0.5)
			(island_removal_mode 0)
		)
		(polygon
			(pts
				(xy 212.597746 -20.2057) (xy 212.216746 -20.5867) (xy 212.216746 -32.0167) (xy 213.105746 -32.9057)
				(xy 229.869746 -32.9057) (xy 229.996746 -32.7787) (xy 229.996746 -31.5087) (xy 229.742746 -31.2547)
				(xy 228.726746 -31.2547) (xy 227.678996 -30.20695) (xy 227.678996 -29.762196) (xy 227.678996 -23.47595)
				(xy 224.408746 -20.2057)
			)
		)
		(polygon
			(pts
				(xy 229.361746 -31.8135) (xy 229.107746 -31.8135) (xy 229.107746 -32.0675) (xy 229.082346 -32.1945)
				(xy 229.082346 -32.4485) (xy 229.336346 -32.4485) (xy 229.336346 -32.1945) (xy 229.361746 -32.0675)
			)
		)
	)
	(zone
		(layer "F.Cu")
		(hatch none 0.5)
		(connect_pads
			(clearance 0.5)
		)
		(min_thickness 0.25)
		(fill
			(thermal_gap 0.5)
			(thermal_bridge_width 0.5)
			(island_removal_mode 0)
		)
		(polygon
			(pts
				(xy 235.457746 -7.7597) (xy 234.949746 -8.2677) (xy 234.949746 -16.7767) (xy 235.711746 -17.5387)
				(xy 237.108746 -17.5387) (xy 237.743746 -18.1737) (xy 237.743746 -21.7297) (xy 237.870746 -21.8567)
				(xy 240.664746 -21.8567) (xy 241.299746 -22.4917) (xy 241.299746 -22.8727) (xy 241.553746 -23.1267)
				(xy 242.315746 -23.1267) (xy 242.442746 -22.9997) (xy 242.442746 -8.6487) (xy 241.553746 -7.7597)
			)
		)
		(polygon
			(pts
				(xy 241.680746 -22.1869) (xy 241.426746 -22.1869) (xy 241.426746 -22.4409) (xy 241.680746 -22.4409)
			)
		)
	)
	(zone
		(layer "F.Cu")
		(hatch none 0.5)
		(connect_pads
			(clearance 0)
		)
		(min_thickness 0.25)
		(keepout
			(tracks allowed)
			(vias allowed)
			(pads allowed)
			(copperpour allowed)
			(footprints not_allowed)
		)
		(placement
			(enabled no)
			(sheetname "")
		)
		(fill
			(thermal_gap 0.5)
			(thermal_bridge_width 0.5)
			(island_removal_mode 0)
		)
		(polygon
			(pts
				(arc
					(start 69.000116 -373.000016)
					(mid 73.000108 -377.000008)
					(end 69.000116 -381)
				)
				(arc
					(start 69.000116 -381)
					(mid 65.000124 -377.000008)
					(end 69.000116 -373.000016)
				)
			)
		)
	)
	(zone
		(net "P5VB")
		(layer "F.Cu")
		(hatch none 0.5)
		(connect_pads
			(clearance 0.5)
		)
		(min_thickness 0.25)
		(fill yes
			(thermal_gap 0.5)
			(thermal_bridge_width 0.5)
			(island_removal_mode 0)
		)
		(polygon
			(pts
				(xy 67.944746 -177.5587) (xy 67.690746 -177.8127) (xy 67.690746 -183.6547) (xy 67.944746 -183.9087)
				(xy 72.135746 -183.9087) (xy 72.516746 -183.5277) (xy 72.516746 -177.6857) (xy 72.389746 -177.5587)
			)
		)
	)
	(zone
		(net "5V_PRE_7")
		(layer "F.Cu")
		(hatch none 0.5)
		(connect_pads
			(clearance 0.5)
		)
		(min_thickness 0.25)
		(fill yes
			(thermal_gap 0.5)
			(thermal_bridge_width 0.5)
			(island_removal_mode 0)
		)
		(polygon
			(pts
				(xy 54.7878 -278.5618) (xy 54.3306 -279.019) (xy 37.1348 -279.019) (xy 37.0586 -279.0952) (xy 37.0586 -279.6794)
				(xy 37.211 -279.8318) (xy 50.2666 -279.8318) (xy 52.8066 -282.3718) (xy 56.9722 -282.3718) (xy 57.2516 -282.0924)
				(xy 57.2516 -279.0698) (xy 56.7436 -278.5618)
			)
		)
		(polygon
			(pts
				(xy 56.388 -281.4574) (xy 56.134 -281.4574) (xy 56.134 -281.7114) (xy 56.388 -281.7114)
			)
		)
		(polygon
			(pts
				(xy 55.245 -281.4574) (xy 54.991 -281.4574) (xy 54.991 -281.7114) (xy 55.245 -281.7114)
			)
		)
	)
	(zone
		(net "P3V3_EN")
		(layer "F.Cu")
		(hatch none 0.5)
		(connect_pads
			(clearance 0.5)
		)
		(min_thickness 0.25)
		(fill yes
			(thermal_gap 0.5)
			(thermal_bridge_width 0.5)
			(island_removal_mode 0)
		)
		(polygon
			(pts
				(xy 224.155 -434.848) (xy 224.028 -434.975) (xy 224.028 -436.753) (xy 223.901 -436.88) (xy 223.901 -438.15)
				(xy 223.52 -438.531) (xy 223.52 -439.039) (xy 223.647 -439.166) (xy 225.044 -439.166) (xy 225.298 -438.912)
				(xy 225.298 -438.277) (xy 225.552 -438.023) (xy 226.06 -438.023) (xy 226.441 -437.642) (xy 226.441 -436.88)
				(xy 226.187 -436.626) (xy 225.806 -436.626) (xy 225.552 -436.372) (xy 225.552 -435.356) (xy 225.044 -434.848)
			)
		)
		(polygon
			(pts
				(xy 224.739454 -438.3659) (xy 224.485454 -438.3659) (xy 224.485454 -438.6199) (xy 224.739454 -438.6199)
			)
		)
		(polygon
			(pts
				(xy 224.256854 -438.3659) (xy 224.002854 -438.3659) (xy 224.002854 -438.6199) (xy 224.256854 -438.6199)
			)
		)
		(polygon
			(pts
				(xy 225.679 -437.5658) (xy 225.425 -437.5658) (xy 225.425 -437.8198) (xy 225.679 -437.8198)
			)
		)
	)
	(zone
		(layer "F.Cu")
		(hatch none 0.5)
		(connect_pads
			(clearance 0)
		)
		(min_thickness 0.25)
		(keepout
			(tracks not_allowed)
			(vias allowed)
			(pads allowed)
			(copperpour not_allowed)
			(footprints allowed)
		)
		(placement
			(enabled no)
			(sheetname "")
		)
		(fill
			(thermal_gap 0.5)
			(thermal_bridge_width 0.5)
			(island_removal_mode 0)
		)
		(polygon
			(pts
				(arc
					(start 7.908544 -383.743708)
					(mid 7.92437 -383.593369)
					(end 7.971028 -383.449576)
				)
				(arc
					(start 7.675626 -383.436368)
					(mid 7.063238 -383.996311)
					(end 7.623048 -384.608832)
				)
				(arc
					(start 8.485886 -384.647186)
					(mid 9.09828 -384.087116)
					(end 8.53821 -383.474722)
				)
				(xy 8.524748 -383.474214)
				(arc
					(start 8.443722 -383.554986)
					(mid 8.386028 -383.641615)
					(end 8.365744 -383.743708)
				)
				(arc
					(start 8.365744 -383.808224)
					(mid 8.724868 -384.260917)
					(end 8.250682 -383.930652)
				)
				(arc
					(start 8.250682 -383.930652)
					(mid 8.244217 -383.904997)
					(end 8.240268 -383.878836)
				)
				(xy 8.238744 -383.877566) (xy 8.238744 -383.717292)
				(arc
					(start 8.23976 -383.71653)
					(mid 8.268849 -383.592867)
					(end 8.335772 -383.484882)
				)
				(xy 8.335772 -383.483358) (xy 8.35279 -383.466594)
				(arc
					(start 8.109458 -383.455672)
					(mid 8.054329 -383.595023)
					(end 8.035544 -383.743708)
				)
				(arc
					(start 8.035544 -383.743708)
					(mid 8.010367 -383.872575)
					(end 7.938516 -383.982468)
				)
				(arc
					(start 7.938516 -383.982468)
					(mid 7.37926 -384.13377)
					(end 7.882382 -383.846578)
				)
				(arc
					(start 7.882382 -383.846578)
					(mid 7.901895 -383.796779)
					(end 7.908544 -383.743708)
				)
			)
		)
	)
	(zone
		(layer "F.Cu")
		(hatch none 0.5)
		(connect_pads
			(clearance 0)
		)
		(min_thickness 0.25)
		(keepout
			(tracks not_allowed)
			(vias allowed)
			(pads allowed)
			(copperpour not_allowed)
			(footprints allowed)
		)
		(placement
			(enabled no)
			(sheetname "")
		)
		(fill
			(thermal_gap 0.5)
			(thermal_bridge_width 0.5)
			(island_removal_mode 0)
		)
		(polygon
			(pts
				(arc
					(start 29.138626 -344.885518)
					(mid 28.463364 -344.403151)
					(end 27.980894 -345.078304)
				)
				(xy 27.995118 -345.163902) (xy 28.011628 -345.262708)
				(arc
					(start 28.093162 -345.262708)
					(mid 28.230397 -345.245249)
					(end 28.358846 -345.193874)
				)
				(arc
					(start 28.358846 -345.193874)
					(mid 28.701567 -344.72624)
					(end 28.48483 -345.263978)
				)
				(arc
					(start 28.48483 -345.263978)
					(mid 28.311612 -345.353238)
					(end 28.120086 -345.3892)
				)
				(xy 28.119578 -345.389708) (xy 28.03271 -345.389708) (xy 28.066746 -345.592908) (xy 28.300172 -345.592908)
				(arc
					(start 28.30068 -345.593416)
					(mid 28.398027 -345.604521)
					(end 28.492704 -345.629738)
				)
				(arc
					(start 28.492704 -345.629738)
					(mid 28.951147 -345.986275)
					(end 28.424632 -345.741244)
				)
				(arc
					(start 28.424632 -345.741244)
					(mid 28.349949 -345.725235)
					(end 28.273756 -345.719908)
				)
				(xy 28.087828 -345.719908)
				(arc
					(start 28.12288 -345.93022)
					(mid 28.798266 -346.412566)
					(end 29.280612 -345.73718)
				)
			)
		)
	)
	(zone
		(net "P12V_HDD1")
		(layer "F.Cu")
		(hatch none 0.5)
		(connect_pads
			(clearance 0.5)
		)
		(min_thickness 0.25)
		(fill yes
			(thermal_gap 0.5)
			(thermal_bridge_width 0.5)
			(island_removal_mode 0)
		)
		(polygon
			(pts
				(xy 205.358746 -388.5057) (xy 204.469746 -389.3947) (xy 204.469746 -392.5697) (xy 204.469746 -392.6967)
				(xy 204.215746 -392.9507) (xy 202.183746 -392.9507) (xy 201.929746 -393.2047) (xy 201.929746 -398.0307)
				(xy 202.310746 -398.4117) (xy 211.8233 -398.4117) (xy 212.4202 -397.8148) (xy 212.4202 -393.5095)
				(xy 212.598 -393.3317) (xy 224.027746 -393.3317) (xy 224.535746 -392.8237) (xy 224.535746 -390.9187)
				(xy 224.408746 -390.7917) (xy 220.852746 -390.7917) (xy 220.090746 -391.5537) (xy 217.8558 -391.5537)
				(xy 214.8078 -388.5057)
			)
		)
		(polygon
			(pts
				(xy 219.583 -392.3284) (xy 219.329 -392.3284) (xy 219.329 -392.5824) (xy 219.583 -392.5824)
			)
		)
		(polygon
			(pts
				(xy 214.713058 -390.981184) (xy 214.459058 -390.981184) (xy 214.459058 -391.235184) (xy 214.713058 -391.235184)
			)
		)
		(polygon
			(pts
				(xy 213.570058 -390.981184) (xy 213.316058 -390.981184) (xy 213.316058 -391.235184) (xy 213.570058 -391.235184)
			)
		)
	)
	(zone
		(layer "F.Cu")
		(hatch none 0.5)
		(connect_pads
			(clearance 0)
		)
		(min_thickness 0.25)
		(keepout
			(tracks allowed)
			(vias allowed)
			(pads allowed)
			(copperpour allowed)
			(footprints not_allowed)
		)
		(placement
			(enabled no)
			(sheetname "")
		)
		(fill
			(thermal_gap 0.5)
			(thermal_bridge_width 0.5)
			(island_removal_mode 0)
		)
		(polygon
			(pts
				(arc
					(start 69.000116 -64.000126)
					(mid 73.000108 -68.000118)
					(end 69.000116 -72.00011)
				)
				(arc
					(start 69.000116 -72.00011)
					(mid 65.000124 -68.000118)
					(end 69.000116 -64.000126)
				)
			)
		)
	)
	(zone
		(net "12V_PRE_11")
		(layer "F.Cu")
		(hatch none 0.5)
		(connect_pads
			(clearance 0.5)
		)
		(min_thickness 0.25)
		(fill yes
			(thermal_gap 0.5)
			(thermal_bridge_width 0.5)
			(island_removal_mode 0)
		)
		(polygon
			(pts
				(xy 26.034746 -317.274702) (xy 23.621746 -319.687702) (xy 23.621746 -321.211702) (xy 23.240746 -321.592702)
				(xy 20.446746 -321.592702) (xy 20.319746 -321.719702) (xy 20.319746 -322.481702) (xy 20.446746 -322.608702)
				(xy 24.383746 -322.608702) (xy 26.542746 -320.449702) (xy 27.431746 -320.449702) (xy 27.685746 -320.195702)
				(xy 27.685746 -317.528702) (xy 27.431746 -317.274702)
			)
		)
		(polygon
			(pts
				(xy 26.415746 -320.068702) (xy 26.161746 -320.068702) (xy 26.161746 -320.322702) (xy 26.415746 -320.322702)
			)
		)
	)
	(zone
		(net "P3V3")
		(layer "F.Cu")
		(hatch none 0.5)
		(connect_pads
			(clearance 0.5)
		)
		(min_thickness 0.25)
		(fill yes
			(thermal_gap 0.5)
			(thermal_bridge_width 0.5)
			(island_removal_mode 0)
		)
		(polygon
			(pts
				(xy 32.257746 -106.5657) (xy 32.003746 -106.8197) (xy 32.003746 -110.692946) (xy 32.4358 -111.125)
				(xy 32.918146 -111.125) (xy 33.273746 -111.4806) (xy 33.273746 -112.2807) (xy 33.400746 -112.4077)
				(xy 35.178746 -112.4077) (xy 35.432746 -112.1537) (xy 36.067746 -112.1537) (xy 36.194746 -112.0267)
				(xy 36.194746 -111.3917) (xy 36.829746 -110.7567) (xy 37.083746 -110.7567) (xy 37.210746 -110.6297)
				(xy 37.210746 -109.4867) (xy 36.956746 -109.2327) (xy 34.670746 -109.2327) (xy 34.3916 -108.953554)
				(xy 34.3916 -106.8832) (xy 34.0741 -106.5657)
			)
		)
		(polygon
			(pts
				(xy 35.788346 -111.458502) (xy 35.534346 -111.458502) (xy 35.534346 -111.712502) (xy 35.788346 -111.712502)
			)
		)
		(polygon
			(pts
				(xy 32.766 -110.3122) (xy 32.512 -110.3122) (xy 32.512 -110.5662) (xy 32.766 -110.5662)
			)
		)
		(polygon
			(pts
				(xy 32.766 -109.7026) (xy 32.512 -109.7026) (xy 32.512 -109.9566) (xy 32.766 -109.9566)
			)
		)
		(polygon
			(pts
				(xy 33.959546 -108.639102) (xy 33.705546 -108.639102) (xy 33.705546 -108.893102) (xy 33.959546 -108.893102)
			)
		)
		(polygon
			(pts
				(xy 33.959546 -108.080302) (xy 33.705546 -108.080302) (xy 33.705546 -108.334302) (xy 33.959546 -108.334302)
			)
		)
		(polygon
			(pts
				(xy 33.959546 -107.623102) (xy 33.705546 -107.623102) (xy 33.705546 -107.877102) (xy 33.959546 -107.877102)
			)
		)
		(polygon
			(pts
				(xy 33.959546 -107.064302) (xy 33.705546 -107.064302) (xy 33.705546 -107.318302) (xy 33.959546 -107.318302)
			)
		)
	)
	(zone
		(layer "F.Cu")
		(hatch none 0.5)
		(connect_pads
			(clearance 0)
		)
		(min_thickness 0.25)
		(keepout
			(tracks not_allowed)
			(vias allowed)
			(pads allowed)
			(copperpour not_allowed)
			(footprints allowed)
		)
		(placement
			(enabled no)
			(sheetname "")
		)
		(fill
			(thermal_gap 0.5)
			(thermal_bridge_width 0.5)
			(island_removal_mode 0)
		)
		(polygon
			(pts
				(arc
					(start 28.330652 -338.66201)
					(mid 27.743912 -338.07527)
					(end 27.157172 -338.66201)
				)
				(xy 27.157172 -338.912708)
				(arc
					(start 27.178254 -338.912708)
					(mid 27.343674 -338.886908)
					(end 27.493468 -338.812124)
				)
				(arc
					(start 27.493468 -338.812124)
					(mid 27.955927 -338.460662)
					(end 27.581606 -338.904834)
				)
				(arc
					(start 27.581606 -338.904834)
					(mid 27.403376 -339.000741)
					(end 27.20467 -339.0392)
				)
				(xy 27.204162 -339.039708) (xy 27.157172 -339.039708) (xy 27.157172 -339.242908) (xy 27.204162 -339.242908)
				(arc
					(start 27.20467 -339.243416)
					(mid 27.403284 -339.281989)
					(end 27.581352 -339.378036)
				)
				(arc
					(start 27.581352 -339.378036)
					(mid 27.9562 -339.821579)
					(end 27.493214 -339.471)
				)
				(arc
					(start 27.493214 -339.471)
					(mid 27.343354 -339.395905)
					(end 27.177746 -339.369908)
				)
				(xy 27.157172 -339.369908)
				(arc
					(start 27.157172 -339.620606)
					(mid 27.743785 -340.2076)
					(end 28.330652 -339.62086)
				)
			)
		)
	)
	(zone
		(layer "F.Cu")
		(hatch none 0.5)
		(connect_pads
			(clearance 0)
		)
		(min_thickness 0.25)
		(keepout
			(tracks not_allowed)
			(vias allowed)
			(pads allowed)
			(copperpour not_allowed)
			(footprints allowed)
		)
		(placement
			(enabled no)
			(sheetname "")
		)
		(fill
			(thermal_gap 0.5)
			(thermal_bridge_width 0.5)
			(island_removal_mode 0)
		)
		(polygon
			(pts
				(arc
					(start 15.827502 -135.675116)
					(mid 15.241651 -135.087614)
					(end 14.654022 -135.673338)
				)
				(xy 14.654022 -135.767064)
				(arc
					(start 14.863064 -135.767064)
					(mid 14.912097 -135.76453)
					(end 14.9606 -135.756904)
				)
				(arc
					(start 14.9606 -135.756904)
					(mid 15.494464 -135.529785)
					(end 15.025624 -135.871458)
				)
				(arc
					(start 15.025624 -135.871458)
					(mid 14.958443 -135.886419)
					(end 14.889988 -135.893556)
				)
				(xy 14.88948 -135.894064) (xy 14.653768 -135.894064) (xy 14.653514 -136.097264)
				(arc
					(start 14.863318 -136.097264)
					(mid 14.922539 -136.095015)
					(end 14.981428 -136.088374)
				)
				(xy 14.985492 -136.08431)
				(arc
					(start 15.008606 -136.08431)
					(mid 15.176872 -136.117825)
					(end 15.28699 -136.24941)
				)
				(arc
					(start 15.28699 -136.24941)
					(mid 15.262608 -136.828918)
					(end 15.149068 -136.260078)
				)
				(arc
					(start 15.149068 -136.260078)
					(mid 15.101283 -136.221385)
					(end 15.041118 -136.20877)
				)
				(xy 15.038324 -136.211564)
				(arc
					(start 15.015718 -136.211564)
					(mid 14.953061 -136.219799)
					(end 14.889988 -136.223756)
				)
				(xy 14.889734 -136.224264) (xy 14.65326 -136.224264)
				(arc
					(start 14.653006 -136.536938)
					(mid 15.238984 -137.12444)
					(end 15.826486 -136.538462)
				)
				(xy 15.826486 -136.5377) (xy 15.826486 -136.536938)
			)
		)
	)
	(zone
		(net "GND")
		(layer "F.Cu")
		(hatch none 0.5)
		(connect_pads
			(clearance 0.5)
		)
		(min_thickness 0.25)
		(fill yes
			(thermal_gap 0.5)
			(thermal_bridge_width 0.5)
			(island_removal_mode 0)
		)
		(polygon
			(pts
				(xy 189.991746 -177.0507) (xy 189.610746 -177.4317) (xy 189.610746 -179.4637) (xy 189.864746 -179.7177)
				(xy 199.389746 -179.7177) (xy 200.024746 -179.0827) (xy 200.024746 -177.3047) (xy 199.770746 -177.0507)
			)
		)
		(polygon
			(pts
				(xy 197.9168 -178.943) (xy 197.6628 -178.943) (xy 197.6628 -179.197) (xy 197.9168 -179.197)
			)
		)
		(polygon
			(pts
				(xy 197.3072 -178.943) (xy 197.0532 -178.943) (xy 197.0532 -179.197) (xy 197.3072 -179.197)
			)
		)
		(polygon
			(pts
				(xy 192.3288 -178.943) (xy 192.0748 -178.943) (xy 192.0748 -179.197) (xy 192.3288 -179.197)
			)
		)
		(polygon
			(pts
				(xy 191.7192 -178.943) (xy 191.4652 -178.943) (xy 191.4652 -179.197) (xy 191.7192 -179.197)
			)
		)
	)
	(zone
		(layer "F.Cu")
		(hatch none 0.5)
		(connect_pads
			(clearance 0)
		)
		(min_thickness 0.25)
		(keepout
			(tracks not_allowed)
			(vias allowed)
			(pads allowed)
			(copperpour not_allowed)
			(footprints allowed)
		)
		(placement
			(enabled no)
			(sheetname "")
		)
		(fill
			(thermal_gap 0.5)
			(thermal_bridge_width 0.5)
			(island_removal_mode 0)
		)
		(polygon
			(pts
				(arc
					(start 7.787386 -413.383222)
					(mid 7.8135 -413.273065)
					(end 7.853934 -413.167322)
				)
				(arc
					(start 7.215886 -413.544512)
					(mid 7.007016 -414.313851)
					(end 7.778242 -414.516062)
				)
				(arc
					(start 8.581898 -414.041336)
					(mid 8.848306 -413.660682)
					(end 8.736584 -413.20974)
				)
				(arc
					(start 8.444484 -413.20974)
					(mid 8.392553 -413.227559)
					(end 8.362442 -413.273494)
				)
				(arc
					(start 8.362442 -413.273494)
					(mid 8.295609 -413.84996)
					(end 8.232902 -413.272986)
				)
				(xy 8.232902 -413.267906)
				(arc
					(start 8.23468 -413.266128)
					(mid 8.294797 -413.144635)
					(end 8.41629 -413.084518)
				)
				(xy 8.418068 -413.08274)
				(arc
					(start 8.595106 -413.08274)
					(mid 8.349049 -412.999136)
					(end 8.091678 -413.035242)
				)
				(arc
					(start 8.091678 -413.035242)
					(mid 7.976851 -413.204607)
					(end 7.913624 -413.399224)
				)
				(arc
					(start 7.913624 -413.399224)
					(mid 7.867355 -413.651878)
					(end 7.737856 -413.873696)
				)
				(arc
					(start 7.737856 -413.873696)
					(mid 7.288181 -414.241301)
					(end 7.646924 -413.784542)
				)
				(arc
					(start 7.646924 -413.784542)
					(mid 7.750658 -413.601197)
					(end 7.786624 -413.393636)
				)
			)
		)
	)
	(zone
		(layer "F.Cu")
		(hatch none 0.5)
		(connect_pads
			(clearance 0.5)
		)
		(min_thickness 0.25)
		(fill
			(thermal_gap 0.5)
			(thermal_bridge_width 0.5)
			(island_removal_mode 0)
		)
		(polygon
			(pts
				(xy 52.0954 -13.2842) (xy 51.8668 -13.5128) (xy 51.8668 -21.1328) (xy 52.197 -21.463) (xy 54.8132 -21.463)
				(xy 55.118 -21.1582) (xy 55.118 -14.224) (xy 54.1782 -13.2842)
			)
		)
	)
	(zone
		(net "P12V")
		(layer "F.Cu")
		(hatch none 0.5)
		(connect_pads
			(clearance 0.5)
		)
		(min_thickness 0.25)
		(fill yes
			(thermal_gap 0.5)
			(thermal_bridge_width 0.5)
			(island_removal_mode 0)
		)
		(polygon
			(pts
				(xy 8.001 -189.484) (xy 13.462 -189.484) (xy 14.097 -188.849) (xy 14.097 -180.848) (xy 12.7 -179.451)
				(xy 8.255 -179.451) (xy 6.985 -180.721) (xy 6.985 -188.468)
			)
		)
	)
	(zone
		(layer "F.Cu")
		(hatch none 0.5)
		(connect_pads
			(clearance 0)
		)
		(min_thickness 0.25)
		(keepout
			(tracks not_allowed)
			(vias allowed)
			(pads allowed)
			(copperpour not_allowed)
			(footprints allowed)
		)
		(placement
			(enabled no)
			(sheetname "")
		)
		(fill
			(thermal_gap 0.5)
			(thermal_bridge_width 0.5)
			(island_removal_mode 0)
		)
		(polygon
			(pts
				(arc
					(start 31.776416 -63.3222)
					(mid 31.243159 -62.69972)
					(end 30.608016 -63.217806)
				)
				(xy 30.605476 -63.217552) (xy 30.503368 -64.11595) (xy 30.503622 -64.116204)
				(arc
					(start 30.505908 -64.116458)
					(mid 31.022544 -64.765682)
					(end 31.671768 -64.249046)
				)
				(xy 31.674308 -64.2493) (xy 31.727648 -63.7794)
				(arc
					(start 31.451042 -63.7794)
					(mid 31.375862 -63.794448)
					(end 31.312104 -63.837058)
				)
				(xy 31.23565 -63.913512)
				(arc
					(start 31.225236 -63.924434)
					(mid 31.017221 -64.465954)
					(end 31.091632 -63.890652)
				)
				(arc
					(start 31.091632 -63.890652)
					(mid 31.108562 -63.86639)
					(end 31.127192 -63.843408)
				)
				(xy 31.127192 -63.842138) (xy 31.145734 -63.823596) (xy 31.222188 -63.747142) (xy 31.24073 -63.7286)
				(arc
					(start 31.242508 -63.7286)
					(mid 31.32724 -63.677057)
					(end 31.42361 -63.65367)
				)
				(xy 31.424626 -63.6524) (xy 31.742126 -63.6524) (xy 31.76524 -63.4492)
				(arc
					(start 31.431992 -63.4492)
					(mid 30.918149 -63.180145)
					(end 31.480506 -63.3222)
				)
			)
		)
	)
	(zone
		(net "12V_PRE_12")
		(layer "F.Cu")
		(hatch none 0.5)
		(connect_pads
			(clearance 0.5)
		)
		(min_thickness 0.25)
		(fill yes
			(thermal_gap 0.5)
			(thermal_bridge_width 0.5)
			(island_removal_mode 0)
		)
		(polygon
			(pts
				(xy 23.240746 -218.3257) (xy 22.859746 -218.7067) (xy 20.700746 -218.7067) (xy 20.573746 -218.8337)
				(xy 20.573746 -219.0877) (xy 20.827746 -219.3417) (xy 23.367746 -219.3417) (xy 23.748746 -219.7227)
				(xy 24.891746 -219.7227) (xy 25.145746 -219.4687) (xy 25.145746 -218.5797) (xy 24.891746 -218.3257)
			)
		)
	)
	(zone
		(net "P12V_HDD0")
		(layer "F.Cu")
		(hatch none 0.5)
		(connect_pads
			(clearance 0.5)
		)
		(min_thickness 0.25)
		(fill yes
			(thermal_gap 0.5)
			(thermal_bridge_width 0.5)
			(island_removal_mode 0)
		)
		(polygon
			(pts
				(xy 204.431646 -491.6678) (xy 204.215746 -491.8837) (xy 204.215746 -495.935) (xy 203.327 -495.935)
				(xy 203.3143 -495.9477) (xy 201.548746 -495.9477) (xy 201.294746 -496.2017) (xy 201.294746 -501.0277)
				(xy 201.802746 -501.5357) (xy 211.6963 -501.5357) (xy 212.0646 -501.1674) (xy 212.0646 -498.1194)
				(xy 212.4964 -497.6876) (xy 219.747846 -497.6876) (xy 219.849446 -497.586) (xy 219.963746 -497.4717)
				(xy 221.487746 -495.9477) (xy 224.281746 -495.9477) (xy 224.535746 -495.6937) (xy 224.535746 -494.0427)
				(xy 224.408746 -493.9157) (xy 220.090746 -493.9157) (xy 219.074746 -494.9317) (xy 217.0176 -494.9317)
				(xy 216.3572 -494.2713) (xy 216.3572 -492.2266) (xy 216.3572 -491.871) (xy 216.0778 -491.5916) (xy 204.507846 -491.5916)
			)
		)
		(polygon
			(pts
				(xy 220.1418 -496.4176) (xy 219.8878 -496.4176) (xy 219.8878 -496.6716) (xy 220.1418 -496.6716)
			)
		)
		(polygon
			(pts
				(xy 219.2782 -496.4176) (xy 219.0242 -496.4176) (xy 219.0242 -496.6716) (xy 219.2782 -496.6716)
			)
		)
		(polygon
			(pts
				(xy 214.375746 -494.1697) (xy 214.121746 -494.1697) (xy 214.121746 -494.4237) (xy 214.375746 -494.4237)
			)
		)
		(polygon
			(pts
				(xy 213.232746 -494.1697) (xy 212.978746 -494.1697) (xy 212.978746 -494.4237) (xy 213.232746 -494.4237)
			)
		)
	)
	(zone
		(net "12V_PRE_2")
		(layer "F.Cu")
		(hatch none 0.5)
		(connect_pads
			(clearance 0.5)
		)
		(min_thickness 0.25)
		(fill yes
			(thermal_gap 0.5)
			(thermal_bridge_width 0.5)
			(island_removal_mode 0)
		)
		(polygon
			(pts
				(xy 217.550746 -285.3817) (xy 217.296746 -285.6357) (xy 217.296746 -288.3027) (xy 217.423746 -288.4297)
				(xy 219.201746 -288.4297) (xy 220.217746 -287.4137) (xy 224.408746 -287.4137) (xy 224.535746 -287.2867)
				(xy 224.535746 -286.7787) (xy 224.408746 -286.6517) (xy 221.360746 -286.6517) (xy 220.090746 -285.3817)
			)
		)
	)
	(zone
		(net "P3V3")
		(layer "F.Cu")
		(hatch none 0.5)
		(connect_pads
			(clearance 0.5)
		)
		(min_thickness 0.25)
		(fill yes
			(thermal_gap 0.5)
			(thermal_bridge_width 0.5)
			(island_removal_mode 0)
		)
		(polygon
			(pts
				(xy 101.218746 -376.3137) (xy 87.502746 -390.0297) (xy 72.389746 -390.0297) (xy 71.627746 -390.7917)
				(xy 71.627746 -392.9507) (xy 71.754746 -393.0777) (xy 74.040746 -393.0777) (xy 74.929746 -393.9667)
				(xy 77.215746 -393.9667) (xy 77.596746 -394.3477) (xy 77.596746 -395.3637) (xy 80.136746 -395.3637)
				(xy 80.263746 -395.2367) (xy 80.263746 -393.7127) (xy 80.644746 -393.3317) (xy 83.184746 -393.3317)
				(xy 83.438746 -393.5857) (xy 91.820746 -393.5857) (xy 102.361746 -383.0447) (xy 143.890746 -383.0447)
				(xy 144.525746 -382.4097) (xy 144.525746 -377.5837) (xy 143.255746 -376.3137)
			)
		)
		(polygon
			(pts
				(xy 78.307946 -394.4493) (xy 78.053946 -394.4493) (xy 78.053946 -394.7033) (xy 78.307946 -394.7033)
			)
		)
		(polygon
			(pts
				(xy 75.8698 -393.2174) (xy 75.6158 -393.2174) (xy 75.6158 -393.4714) (xy 75.8698 -393.4714)
			)
		)
		(polygon
			(pts
				(xy 75.2602 -393.2174) (xy 75.0062 -393.2174) (xy 75.0062 -393.4714) (xy 75.2602 -393.4714)
			)
		)
		(polygon
			(pts
				(xy 78.993746 -390.5123) (xy 78.739746 -390.5123) (xy 78.739746 -390.7663) (xy 78.993746 -390.7663)
			)
		)
		(polygon
			(pts
				(xy 78.384146 -390.5123) (xy 78.130146 -390.5123) (xy 78.130146 -390.7663) (xy 78.384146 -390.7663)
			)
		)
	)
	(zone
		(net "12V_PRE_5")
		(layer "F.Cu")
		(hatch none 0.5)
		(connect_pads
			(clearance 0.5)
		)
		(min_thickness 0.25)
		(fill yes
			(thermal_gap 0.5)
			(thermal_bridge_width 0.5)
			(island_removal_mode 0)
		)
		(polygon
			(pts
				(xy 52.069746 -492.0107) (xy 51.434746 -492.6457) (xy 37.083746 -492.6457) (xy 36.956746 -492.7727)
				(xy 36.956746 -493.1537) (xy 37.210746 -493.4077) (xy 52.069746 -493.4077) (xy 53.720746 -495.0587)
				(xy 56.006746 -495.0587) (xy 56.260746 -494.8047) (xy 56.260746 -492.5187) (xy 55.752746 -492.0107)
			)
		)
	)
	(zone
		(layer "F.Cu")
		(hatch none 0.5)
		(connect_pads
			(clearance 0)
		)
		(min_thickness 0.25)
		(keepout
			(tracks not_allowed)
			(vias allowed)
			(pads allowed)
			(copperpour not_allowed)
			(footprints allowed)
		)
		(placement
			(enabled no)
			(sheetname "")
		)
		(fill
			(thermal_gap 0.5)
			(thermal_bridge_width 0.5)
			(island_removal_mode 0)
		)
		(polygon
			(pts
				(arc
					(start 22.225508 -444.181992)
					(mid 21.613876 -443.62116)
					(end 21.053044 -444.232792)
				)
				(xy 21.05533 -444.283338) (xy 21.062442 -444.4492)
				(arc
					(start 21.208746 -444.4492)
					(mid 21.315106 -444.435012)
					(end 21.413978 -444.39332)
				)
				(arc
					(start 21.413978 -444.39332)
					(mid 21.815713 -443.974586)
					(end 21.521166 -444.4746)
				)
				(arc
					(start 21.521166 -444.4746)
					(mid 21.385761 -444.545807)
					(end 21.23567 -444.575438)
				)
				(xy 21.235162 -444.5762) (xy 21.06803 -444.5762) (xy 21.076666 -444.7794) (xy 21.12772 -444.7794)
				(xy 21.12899 -444.7794) (xy 21.154136 -444.7794)
				(arc
					(start 21.15439 -444.779908)
					(mid 21.218789 -444.784299)
					(end 21.28266 -444.793624)
				)
				(arc
					(start 21.28266 -444.793624)
					(mid 21.382359 -444.818739)
					(end 21.47824 -444.855854)
				)
				(arc
					(start 21.47824 -444.855854)
					(mid 21.917532 -445.23536)
					(end 21.405088 -444.962534)
				)
				(arc
					(start 21.405088 -444.962534)
					(mid 21.333366 -444.936663)
					(end 21.259292 -444.918592)
				)
				(arc
					(start 21.259292 -444.918592)
					(mid 21.194422 -444.909494)
					(end 21.12899 -444.9064)
				)
				(xy 21.082254 -444.9064) (xy 21.089366 -445.073532)
				(arc
					(start 21.090382 -445.095376)
					(mid 21.701887 -445.656457)
					(end 22.262846 -445.04483)
				)
			)
		)
	)
	(zone
		(layer "F.Cu")
		(hatch none 0.5)
		(connect_pads
			(clearance 0)
		)
		(min_thickness 0.25)
		(keepout
			(tracks not_allowed)
			(vias allowed)
			(pads allowed)
			(copperpour not_allowed)
			(footprints allowed)
		)
		(placement
			(enabled no)
			(sheetname "")
		)
		(fill
			(thermal_gap 0.5)
			(thermal_bridge_width 0.5)
			(island_removal_mode 0)
		)
		(polygon
			(pts
				(arc
					(start 7.266686 -97.49917)
					(mid 6.680073 -96.912176)
					(end 6.093206 -97.498916)
				)
				(xy 6.093206 -97.766632)
				(arc
					(start 6.563106 -97.766632)
					(mid 6.656028 -97.207795)
					(end 6.83895 -97.744026)
				)
				(arc
					(start 6.83895 -97.744026)
					(mid 6.769262 -97.843904)
					(end 6.65734 -97.891854)
				)
				(xy 6.655562 -97.893632) (xy 6.093206 -97.893632) (xy 6.093206 -98.096832) (xy 6.172962 -98.096832)
				(arc
					(start 6.17347 -98.09734)
					(mid 6.353464 -98.131602)
					(end 6.516116 -98.215958)
				)
				(arc
					(start 6.516116 -98.215958)
					(mid 6.892433 -98.658251)
					(end 6.428232 -98.30943)
				)
				(arc
					(start 6.428232 -98.30943)
					(mid 6.29375 -98.245696)
					(end 6.146546 -98.223832)
				)
				(xy 6.093206 -98.223832)
				(arc
					(start 6.093206 -98.457766)
					(mid 6.679946 -99.044506)
					(end 7.266686 -98.457766)
				)
			)
		)
	)
	(zone
		(layer "F.Cu")
		(hatch none 0.5)
		(connect_pads
			(clearance 0)
		)
		(min_thickness 0.25)
		(keepout
			(tracks not_allowed)
			(vias allowed)
			(pads allowed)
			(copperpour not_allowed)
			(footprints allowed)
		)
		(placement
			(enabled no)
			(sheetname "")
		)
		(fill
			(thermal_gap 0.5)
			(thermal_bridge_width 0.5)
			(island_removal_mode 0)
		)
		(polygon
			(pts
				(arc
					(start 7.291578 -107.502198)
					(mid 6.683756 -106.937556)
					(end 6.119114 -107.545378)
				)
				(xy 6.116574 -107.545378) (xy 6.117336 -107.569)
				(arc
					(start 6.416802 -107.569)
					(mid 6.975151 -107.411954)
					(end 6.46938 -107.696)
				)
				(xy 6.122162 -107.696) (xy 6.129528 -107.8992) (xy 6.339332 -107.8992)
				(arc
					(start 6.340094 -107.899962)
					(mid 6.544361 -107.957624)
					(end 6.704838 -108.096558)
				)
				(arc
					(start 6.704838 -108.096558)
					(mid 6.835518 -108.661908)
					(end 6.577838 -108.142024)
				)
				(arc
					(start 6.577838 -108.142024)
					(mid 6.45748 -108.056432)
					(end 6.312916 -108.0262)
				)
				(xy 6.134354 -108.0262) (xy 6.148324 -108.408216) (xy 6.148578 -108.40847)
				(arc
					(start 6.150864 -108.40847)
					(mid 6.758686 -108.973112)
					(end 7.323328 -108.36529)
				)
				(xy 7.325868 -108.36529) (xy 7.294118 -107.502198)
			)
		)
	)
	(zone
		(layer "F.Cu")
		(hatch none 0.5)
		(connect_pads
			(clearance 0)
		)
		(min_thickness 0.25)
		(keepout
			(tracks not_allowed)
			(vias allowed)
			(pads allowed)
			(copperpour not_allowed)
			(footprints allowed)
		)
		(placement
			(enabled no)
			(sheetname "")
		)
		(fill
			(thermal_gap 0.5)
			(thermal_bridge_width 0.5)
			(island_removal_mode 0)
		)
		(polygon
			(pts
				(arc
					(start 7.782814 -367.585498)
					(mid 7.786067 -367.459391)
					(end 7.858506 -367.356136)
				)
				(arc
					(start 7.613396 -367.345214)
					(mid 7.573498 -367.489475)
					(end 7.586472 -367.638584)
				)
				(arc
					(start 7.586472 -367.638838)
					(mid 7.593721 -367.719434)
					(end 7.572756 -367.797588)
				)
				(arc
					(start 7.572756 -367.797588)
					(mid 7.048988 -368.033664)
					(end 7.45363 -367.625884)
				)
				(arc
					(start 7.45363 -367.625884)
					(mid 7.44682 -367.480857)
					(end 7.478268 -367.339118)
				)
				(arc
					(start 7.312914 -367.331752)
					(mid 6.753606 -367.843308)
					(end 7.265162 -368.402616)
				)
				(arc
					(start 8.127746 -368.441224)
					(mid 8.680045 -367.996934)
					(end 8.308594 -367.39322)
				)
				(arc
					(start 8.308594 -367.39322)
					(mid 8.152712 -367.425526)
					(end 7.993888 -367.4364)
				)
				(arc
					(start 7.993888 -367.4364)
					(mid 7.920909 -367.472247)
					(end 7.905242 -367.55197)
				)
				(arc
					(start 7.905242 -367.55197)
					(mid 7.914297 -367.573799)
					(end 7.92861 -367.59261)
				)
				(arc
					(start 7.995412 -367.659158)
					(mid 8.358756 -368.112418)
					(end 7.905496 -367.749074)
				)
				(xy 7.839202 -367.68278) (xy 7.838694 -367.682272) (xy 7.82066 -367.663984)
				(arc
					(start 7.82066 -367.661698)
					(mid 7.797985 -367.62546)
					(end 7.782814 -367.585498)
				)
			)
		)
	)
	(zone
		(net "5V_PRE_13")
		(layer "F.Cu")
		(hatch none 0.5)
		(connect_pads
			(clearance 0.5)
		)
		(min_thickness 0.25)
		(fill yes
			(thermal_gap 0.5)
			(thermal_bridge_width 0.5)
			(island_removal_mode 0)
		)
		(polygon
			(pts
				(xy 34.670746 -127.5207) (xy 34.162746 -128.0287) (xy 34.162746 -130.4417) (xy 34.416746 -130.6957)
				(xy 37.464746 -130.6957) (xy 37.591746 -130.5687) (xy 37.591746 -128.5367) (xy 36.575746 -127.5207)
			)
		)
	)
	(zone
		(net "P12V")
		(layer "F.Cu")
		(hatch none 0.5)
		(connect_pads
			(clearance 0.5)
		)
		(min_thickness 0.25)
		(fill yes
			(thermal_gap 0.5)
			(thermal_bridge_width 0.5)
			(island_removal_mode 0)
		)
		(polygon
			(pts
				(xy 1.143 -278.257) (xy 0.762254 -278.637746) (xy 0.762254 -284.734254) (xy 1.016 -284.988) (xy 3.683 -284.988)
				(xy 4.191 -284.48) (xy 4.191 -278.511) (xy 3.937 -278.257) (xy 3.429 -278.257) (xy 3.429 -278.511)
				(xy 3.175 -278.511) (xy 3.175 -278.257)
			)
		)
		(polygon
			(pts
				(xy 3.429 -280.289) (xy 3.175 -280.289) (xy 3.175 -280.543) (xy 3.429 -280.543)
			)
		)
		(polygon
			(pts
				(xy 3.429 -279.527) (xy 3.175 -279.527) (xy 3.175 -279.781) (xy 3.429 -279.781)
			)
		)
		(polygon
			(pts
				(xy 3.429 -279.019) (xy 3.175 -279.019) (xy 3.175 -279.273) (xy 3.429 -279.273)
			)
		)
	)
	(zone
		(layer "F.Cu")
		(hatch none 0.5)
		(connect_pads
			(clearance 0)
		)
		(min_thickness 0.25)
		(keepout
			(tracks not_allowed)
			(vias allowed)
			(pads allowed)
			(copperpour not_allowed)
			(footprints allowed)
		)
		(placement
			(enabled no)
			(sheetname "")
		)
		(fill
			(thermal_gap 0.5)
			(thermal_bridge_width 0.5)
			(island_removal_mode 0)
		)
		(polygon
			(pts
				(arc
					(start 8.810498 -376.880374)
					(mid 9.287002 -376.291094)
					(end 8.697722 -375.81459)
				)
				(xy 8.697468 -375.81205)
				(arc
					(start 8.507476 -375.832116)
					(mid 8.461191 -375.917057)
					(end 8.445246 -376.012456)
				)
				(arc
					(start 8.445246 -376.012456)
					(mid 8.461818 -376.105909)
					(end 8.509508 -376.18797)
				)
				(arc
					(start 8.509508 -376.18797)
					(mid 9.029856 -376.444272)
					(end 8.46328 -376.32005)
				)
				(arc
					(start 8.46328 -376.32005)
					(mid 8.356345 -376.182485)
					(end 8.318246 -376.012456)
				)
				(arc
					(start 8.318246 -376.012456)
					(mid 8.326616 -375.92886)
					(end 8.35152 -375.848626)
				)
				(arc
					(start 8.073644 -375.87809)
					(mid 8.012269 -376.017949)
					(end 7.968742 -376.164348)
				)
				(arc
					(start 7.968742 -376.164348)
					(mid 7.841985 -376.731082)
					(end 7.841742 -376.150378)
				)
				(arc
					(start 7.841742 -376.150378)
					(mid 7.87724 -376.020012)
					(end 7.925562 -375.893838)
				)
				(xy 7.817104 -375.905268)
				(arc
					(start 7.817358 -375.907808)
					(mid 7.340854 -376.497088)
					(end 7.930134 -376.973592)
				)
				(xy 7.930388 -376.976132) (xy 8.810498 -376.882914) (xy 8.810752 -376.88266)
			)
		)
	)
	(zone
		(layer "F.Cu")
		(hatch none 0.5)
		(connect_pads
			(clearance 0)
		)
		(min_thickness 0.25)
		(keepout
			(tracks not_allowed)
			(vias allowed)
			(pads allowed)
			(copperpour not_allowed)
			(footprints allowed)
		)
		(placement
			(enabled no)
			(sheetname "")
		)
		(fill
			(thermal_gap 0.5)
			(thermal_bridge_width 0.5)
			(island_removal_mode 0)
		)
		(polygon
			(pts
				(arc
					(start 32.082486 -266.8651)
					(mid 31.495746 -266.27836)
					(end 30.909006 -266.8651)
				)
				(arc
					(start 30.909006 -267.728446)
					(mid 31.123353 -268.182117)
					(end 31.610046 -268.304264)
				)
				(arc
					(start 31.610046 -268.15796)
					(mid 31.604514 -268.081114)
					(end 31.588202 -268.005814)
				)
				(arc
					(start 31.588202 -268.005814)
					(mid 31.343184 -267.479321)
					(end 31.699708 -267.937742)
				)
				(arc
					(start 31.704534 -267.951966)
					(mid 31.726646 -268.04041)
					(end 31.736538 -268.131036)
				)
				(xy 31.737046 -268.131544)
				(arc
					(start 31.737046 -268.263624)
					(mid 31.846975 -268.198814)
					(end 31.940246 -268.111732)
				)
				(arc
					(start 31.940246 -267.3477)
					(mid 31.891001 -267.150655)
					(end 31.754826 -266.999974)
				)
				(arc
					(start 31.754826 -266.999974)
					(mid 31.212718 -266.792202)
					(end 31.787846 -266.871196)
				)
				(arc
					(start 31.787846 -266.871196)
					(mid 31.985265 -267.059987)
					(end 32.066484 -267.320776)
				)
				(xy 32.067246 -267.321284)
				(arc
					(start 32.067246 -267.861542)
					(mid 32.078666 -267.795557)
					(end 32.082486 -267.7287)
				)
			)
		)
	)
	(zone
		(layer "F.Cu")
		(hatch none 0.5)
		(connect_pads
			(clearance 0.5)
		)
		(min_thickness 0.25)
		(fill
			(thermal_gap 0.5)
			(thermal_bridge_width 0.5)
			(island_removal_mode 0)
		)
		(polygon
			(pts
				(xy 27.939746 -9.7917) (xy 27.431746 -10.2997) (xy 27.431746 -17.6657) (xy 28.193746 -18.4277) (xy 51.307746 -18.4277)
				(xy 51.561746 -18.1737) (xy 51.561746 -14.9987) (xy 46.354746 -9.7917)
			)
		)
		(polygon
			(pts
				(xy 44.856146 -17.7165) (xy 44.602146 -17.7165) (xy 44.602146 -17.9705) (xy 44.856146 -17.9705)
			)
		)
		(polygon
			(pts
				(xy 44.297346 -17.7165) (xy 44.043346 -17.7165) (xy 44.043346 -17.9705) (xy 44.297346 -17.9705)
			)
		)
		(polygon
			(pts
				(xy 46.786546 -17.6657) (xy 46.532546 -17.6657) (xy 46.532546 -17.9197) (xy 46.786546 -17.9197)
			)
		)
		(polygon
			(pts
				(xy 46.176946 -17.6657) (xy 45.643546 -17.6657) (xy 45.643546 -17.9197) (xy 46.176946 -17.9197)
			)
		)
		(polygon
			(pts
				(xy 45.287946 -17.6657) (xy 45.033946 -17.6657) (xy 45.033946 -17.9197) (xy 45.287946 -17.9197)
			)
		)
	)
	(zone
		(net "P12V")
		(layer "F.Cu")
		(hatch none 0.5)
		(connect_pads
			(clearance 0.5)
		)
		(min_thickness 0.25)
		(fill yes
			(thermal_gap 0.5)
			(thermal_bridge_width 0.5)
			(island_removal_mode 0)
		)
		(polygon
			(pts
				(xy 223.8248 -441.5282) (xy 223.647 -441.706) (xy 223.647 -443.3316) (xy 223.7994 -443.484) (xy 225.3996 -443.484)
				(xy 225.5266 -443.357) (xy 225.5266 -442.341) (xy 224.7138 -441.5282)
			)
		)
		(polygon
			(pts
				(xy 224.7646 -442.4426) (xy 224.5106 -442.4426) (xy 224.5106 -442.6966) (xy 224.7646 -442.6966)
			)
		)
	)
	(zone
		(net "P5VC")
		(layer "F.Cu")
		(hatch none 0.5)
		(connect_pads
			(clearance 0.5)
		)
		(min_thickness 0.25)
		(fill yes
			(thermal_gap 0.5)
			(thermal_bridge_width 0.5)
			(island_removal_mode 0)
		)
		(polygon
			(pts
				(xy 53.974746 -234.978702) (xy 53.720746 -235.232702) (xy 53.720746 -240.947702) (xy 54.228746 -241.455702)
				(xy 57.403746 -241.455702) (xy 59.308746 -239.550702) (xy 59.308746 -235.359702) (xy 58.927746 -234.978702)
			)
		)
	)
	(zone
		(layer "F.Cu")
		(hatch none 0.5)
		(connect_pads
			(clearance 0)
		)
		(min_thickness 0.25)
		(keepout
			(tracks not_allowed)
			(vias allowed)
			(pads allowed)
			(copperpour not_allowed)
			(footprints allowed)
		)
		(placement
			(enabled no)
			(sheetname "")
		)
		(fill
			(thermal_gap 0.5)
			(thermal_bridge_width 0.5)
			(island_removal_mode 0)
		)
		(polygon
			(pts
				(arc
					(start 11.140186 -438.466484)
					(mid 11.102833 -438.462349)
					(end 11.066018 -438.4548)
				)
				(arc
					(start 11.066018 -438.662318)
					(mid 11.116391 -438.6686)
					(end 11.16711 -438.6707)
				)
				(xy 11.202416 -438.6707)
				(arc
					(start 11.202924 -438.671462)
					(mid 11.358214 -438.705656)
					(end 11.494516 -438.78754)
				)
				(arc
					(start 11.494516 -438.78754)
					(mid 11.860726 -439.238385)
					(end 11.405108 -438.878218)
				)
				(arc
					(start 11.405108 -438.878218)
					(mid 11.297427 -438.818418)
					(end 11.176 -438.7977)
				)
				(xy 11.140948 -438.7977)
				(arc
					(start 11.140694 -438.797192)
					(mid 11.103276 -438.794959)
					(end 11.066018 -438.790842)
				)
				(arc
					(start 11.066018 -439.032904)
					(mid 11.652631 -439.619898)
					(end 12.239498 -439.033158)
				)
				(arc
					(start 12.239498 -438.105042)
					(mid 11.652758 -437.518302)
					(end 11.066018 -438.105042)
				)
				(arc
					(start 11.066018 -438.321704)
					(mid 11.115828 -438.335764)
					(end 11.167364 -438.3405)
				)
				(arc
					(start 11.176 -438.3405)
					(mid 11.297447 -438.319838)
					(end 11.405108 -438.259982)
				)
				(arc
					(start 11.405108 -438.259982)
					(mid 11.860687 -437.899854)
					(end 11.494516 -438.35066)
				)
				(arc
					(start 11.494516 -438.35066)
					(mid 11.358207 -438.432527)
					(end 11.202924 -438.466738)
				)
				(xy 11.202416 -438.4675) (xy 11.140948 -438.4675)
			)
		)
	)
	(zone
		(layer "F.Cu")
		(hatch none 0.5)
		(connect_pads
			(clearance 0)
		)
		(min_thickness 0.25)
		(keepout
			(tracks allowed)
			(vias allowed)
			(pads allowed)
			(copperpour allowed)
			(footprints allowed)
		)
		(placement
			(enabled no)
			(sheetname "")
		)
		(fill
			(thermal_gap 0.5)
			(thermal_bridge_width 0.5)
			(island_removal_mode 0)
		)
		(polygon
			(pts
				(xy 172.869352 -459.48981) (xy 172.869352 -460.37881) (xy 172.996352 -460.50581) (xy 174.520352 -460.50581)
				(xy 174.647352 -460.37881) (xy 174.647352 -459.36281) (xy 174.520352 -459.23581) (xy 173.123352 -459.23581)
			)
		)
	)
	(zone
		(net "P12V")
		(layer "F.Cu")
		(hatch none 0.5)
		(connect_pads
			(clearance 0.5)
		)
		(min_thickness 0.25)
		(fill yes
			(thermal_gap 0.5)
			(thermal_bridge_width 0.5)
			(island_removal_mode 0)
		)
		(polygon
			(pts
				(xy 34.416746 -309.6387) (xy 34.162746 -309.8927) (xy 34.162746 -311.2897) (xy 33.908746 -311.5437)
				(xy 32.130746 -311.5437) (xy 32.003746 -311.6707) (xy 32.003746 -312.1787) (xy 32.130746 -312.3057)
				(xy 33.908746 -312.3057) (xy 34.289746 -312.6867) (xy 34.289746 -313.1947) (xy 34.543746 -313.4487)
				(xy 37.972746 -313.4487) (xy 38.226746 -313.1947) (xy 38.226746 -309.8927) (xy 37.972746 -309.6387)
			)
		)
	)
	(zone
		(net "P12V")
		(layer "F.Cu")
		(hatch none 0.5)
		(connect_pads
			(clearance 0.5)
		)
		(min_thickness 0.25)
		(fill yes
			(thermal_gap 0.5)
			(thermal_bridge_width 0.5)
			(island_removal_mode 0)
		)
		(polygon
			(pts
				(xy 43.3832 -110.0836) (xy 43.295824 -110.170976) (xy 43.295824 -111.524796) (xy 43.06062 -111.76)
				(xy 43.06062 -112.018826) (xy 43.044618 -112.034828) (xy 43.052746 -112.042702) (xy 43.052746 -113.0427)
				(xy 42.798746 -113.2967) (xy 41.274746 -113.2967) (xy 41.147746 -113.4237) (xy 41.147746 -113.8047)
				(xy 41.274746 -113.9317) (xy 42.925746 -113.9317) (xy 43.052746 -114.0587) (xy 43.052746 -114.201702)
				(xy 43.179746 -114.328702) (xy 46.989746 -114.328702) (xy 47.243746 -114.074702) (xy 47.243746 -110.518702)
				(xy 46.808644 -110.0836)
			)
		)
	)
	(zone
		(layer "F.Cu")
		(hatch none 0.5)
		(connect_pads
			(clearance 0)
		)
		(min_thickness 0.25)
		(keepout
			(tracks not_allowed)
			(vias allowed)
			(pads allowed)
			(copperpour not_allowed)
			(footprints allowed)
		)
		(placement
			(enabled no)
			(sheetname "")
		)
		(fill
			(thermal_gap 0.5)
			(thermal_bridge_width 0.5)
			(island_removal_mode 0)
		)
		(polygon
			(pts
				(arc
					(start 7.315454 -111.576612)
					(mid 6.710553 -111.008664)
					(end 6.142482 -111.613442)
				)
				(xy 6.147308 -111.767112)
				(arc
					(start 6.349746 -111.767112)
					(mid 6.41469 -111.761242)
					(end 6.477508 -111.743744)
				)
				(arc
					(start 6.477508 -111.743744)
					(mid 6.93871 -111.391579)
					(end 6.571234 -111.840772)
				)
				(arc
					(start 6.571234 -111.840772)
					(mid 6.47683 -111.87723)
					(end 6.376924 -111.89335)
				)
				(xy 6.376162 -111.894112) (xy 6.151372 -111.894112) (xy 6.157722 -112.097312) (xy 6.376162 -112.097312)
				(arc
					(start 6.37667 -112.098074)
					(mid 6.514085 -112.125642)
					(end 6.638036 -112.191038)
				)
				(arc
					(start 6.638036 -112.191038)
					(mid 6.932748 -112.690973)
					(end 6.530594 -112.272572)
				)
				(arc
					(start 6.530594 -112.272572)
					(mid 6.443335 -112.236583)
					(end 6.349746 -112.224312)
				)
				(xy 6.161786 -112.224312)
				(arc
					(start 6.16966 -112.476788)
					(mid 6.774688 -113.044732)
					(end 7.342632 -112.439704)
				)
			)
		)
	)
	(zone
		(net "P12V")
		(layer "F.Cu")
		(hatch none 0.5)
		(connect_pads
			(clearance 0.5)
		)
		(min_thickness 0.25)
		(fill yes
			(thermal_gap 0.5)
			(thermal_bridge_width 0.5)
			(island_removal_mode 0)
		)
		(polygon
			(pts
				(xy 49.657 -211.328) (xy 49.403 -211.582) (xy 49.403 -211.991702) (xy 49.276 -212.118702) (xy 49.275746 -212.118702)
				(xy 49.156874 -212.237574) (xy 49.156874 -213.634828) (xy 49.148746 -213.642702) (xy 49.148746 -214.3887)
				(xy 49.009046 -214.5284) (xy 47.0408 -214.5284) (xy 46.9138 -214.6554) (xy 46.9138 -215.074754)
				(xy 47.116746 -215.2777) (xy 49.021746 -215.2777) (xy 49.136046 -215.392) (xy 53.467 -215.392) (xy 53.721 -215.138)
				(xy 53.721 -211.963) (xy 53.086 -211.328)
			)
		)
	)
	(zone
		(layer "F.Cu")
		(hatch none 0.5)
		(connect_pads
			(clearance 0)
		)
		(min_thickness 0.25)
		(keepout
			(tracks allowed)
			(vias allowed)
			(pads allowed)
			(copperpour allowed)
			(footprints allowed)
		)
		(placement
			(enabled no)
			(sheetname "")
		)
		(fill
			(thermal_gap 0.5)
			(thermal_bridge_width 0.5)
			(island_removal_mode 0)
		)
		(polygon
			(pts
				(xy 9.270746 -498.4877) (xy 10.413746 -498.4877) (xy 10.540746 -498.3607) (xy 10.540746 -496.9637)
				(xy 10.413746 -496.8367) (xy 9.143746 -496.8367) (xy 9.016746 -496.9637) (xy 9.016746 -498.2337)
			)
		)
	)
	(zone
		(net "P3V3")
		(layer "F.Cu")
		(hatch none 0.5)
		(connect_pads
			(clearance 0.5)
		)
		(min_thickness 0.25)
		(fill yes
			(thermal_gap 0.5)
			(thermal_bridge_width 0.5)
			(island_removal_mode 0)
		)
		(polygon
			(pts
				(xy 76.834746 -81.2927) (xy 76.707746 -81.4197) (xy 76.707746 -82.0547) (xy 76.580746 -82.1817)
				(xy 71.754746 -82.1817) (xy 71.627746 -82.3087) (xy 71.627746 -83.5787) (xy 71.881746 -83.8327)
				(xy 77.723746 -83.8327) (xy 78.104746 -84.2137) (xy 78.104746 -85.1027) (xy 78.231746 -85.2297)
				(xy 80.644746 -85.2297) (xy 80.771746 -85.1027) (xy 80.771746 -84.3407) (xy 81.025746 -84.0867)
				(xy 84.073746 -84.0867) (xy 84.454746 -84.4677) (xy 84.454746 -85.8647) (xy 84.708746 -86.1187)
				(xy 143.255746 -86.1187) (xy 143.890746 -85.4837) (xy 143.890746 -81.9277) (xy 143.255746 -81.2927)
			)
		)
		(polygon
			(pts
				(xy 85.038692 -85.220556) (xy 84.784692 -85.220556) (xy 84.784692 -85.474556) (xy 85.038692 -85.474556)
			)
		)
		(polygon
			(pts
				(xy 85.038692 -84.763356) (xy 84.784692 -84.763356) (xy 84.784692 -85.017356) (xy 85.038692 -85.017356)
			)
		)
		(polygon
			(pts
				(xy 78.815946 -84.4423) (xy 78.561946 -84.4423) (xy 78.561946 -84.6963) (xy 78.815946 -84.6963)
			)
		)
		(polygon
			(pts
				(xy 85.038692 -84.204556) (xy 84.784692 -84.204556) (xy 84.784692 -84.458556) (xy 85.038692 -84.458556)
			)
		)
		(polygon
			(pts
				(xy 75.4888 -83.185) (xy 75.2348 -83.185) (xy 75.2348 -83.439) (xy 75.4888 -83.439)
			)
		)
		(polygon
			(pts
				(xy 74.8792 -83.185) (xy 74.6252 -83.185) (xy 74.6252 -83.439) (xy 74.8792 -83.439)
			)
		)
		(polygon
			(pts
				(xy 79.883 -81.7372) (xy 79.629 -81.7372) (xy 79.629 -81.9912) (xy 79.883 -81.9912)
			)
		)
		(polygon
			(pts
				(xy 79.2734 -81.7372) (xy 79.0194 -81.7372) (xy 79.0194 -81.9912) (xy 79.2734 -81.9912)
			)
		)
	)
	(zone
		(layer "F.Cu")
		(hatch none 0.5)
		(connect_pads
			(clearance 0)
		)
		(min_thickness 0.25)
		(keepout
			(tracks not_allowed)
			(vias allowed)
			(pads allowed)
			(copperpour not_allowed)
			(footprints allowed)
		)
		(placement
			(enabled no)
			(sheetname "")
		)
		(fill
			(thermal_gap 0.5)
			(thermal_bridge_width 0.5)
			(island_removal_mode 0)
		)
		(polygon
			(pts
				(arc
					(start 223.169734 -267.599414)
					(mid 223.385909 -267.480444)
					(end 223.624902 -267.419074)
				)
				(xy 223.641666 -267.208) (xy 223.44634 -267.208)
				(arc
					(start 223.445832 -267.207492)
					(mid 223.363613 -267.198463)
					(end 223.283272 -267.17879)
				)
				(arc
					(start 223.283272 -267.17879)
					(mid 222.819404 -266.829699)
					(end 223.34982 -267.06576)
				)
				(arc
					(start 223.34982 -267.06576)
					(mid 223.410819 -267.077153)
					(end 223.472756 -267.081)
				)
				(xy 223.651572 -267.081)
				(arc
					(start 223.656144 -267.024866)
					(mid 223.11779 -266.393432)
					(end 222.48622 -266.931648)
				)
				(arc
					(start 222.417894 -267.792708)
					(mid 222.956374 -268.424152)
					(end 223.587818 -267.885672)
				)
				(arc
					(start 223.614488 -267.548868)
					(mid 223.427115 -267.600891)
					(end 223.256348 -267.693902)
				)
				(arc
					(start 223.256348 -267.693902)
					(mid 222.78741 -268.036548)
					(end 223.169734 -267.599414)
				)
			)
		)
	)
	(zone
		(layer "F.Cu")
		(hatch none 0.5)
		(connect_pads
			(clearance 0)
		)
		(min_thickness 0.25)
		(keepout
			(tracks not_allowed)
			(vias allowed)
			(pads allowed)
			(copperpour not_allowed)
			(footprints allowed)
		)
		(placement
			(enabled no)
			(sheetname "")
		)
		(fill
			(thermal_gap 0.5)
			(thermal_bridge_width 0.5)
			(island_removal_mode 0)
		)
		(polygon
			(pts
				(arc
					(start 216.693242 -269.682468)
					(mid 216.549844 -269.216014)
					(end 216.1032 -269.019274)
				)
				(arc
					(start 215.1888 -269.032228)
					(mid 214.610442 -269.62735)
					(end 215.205564 -270.205708)
				)
				(arc
					(start 216.11971 -270.192754)
					(mid 216.240323 -270.17846)
					(end 216.355422 -270.139668)
				)
				(xy 215.97493 -270.139668)
				(arc
					(start 215.974676 -270.13916)
					(mid 215.65656 -270.070981)
					(end 215.383364 -269.894304)
				)
				(xy 215.382602 -269.894304) (xy 215.36406 -269.875762)
				(arc
					(start 215.3539 -269.865602)
					(mid 214.990556 -269.412342)
					(end 215.443816 -269.775686)
				)
				(arc
					(start 215.453976 -269.785846)
					(mid 215.705097 -269.953703)
					(end 216.001346 -270.012668)
				)
				(arc
					(start 216.534492 -270.012668)
					(mid 216.608756 -269.917661)
					(end 216.662 -269.809468)
				)
				(arc
					(start 216.321132 -269.809468)
					(mid 215.857788 -269.461468)
					(end 216.393522 -269.682468)
				)
			)
		)
	)
	(zone
		(layer "F.Cu")
		(hatch none 0.5)
		(connect_pads
			(clearance 0.5)
		)
		(min_thickness 0.25)
		(fill
			(thermal_gap 0.5)
			(thermal_bridge_width 0.5)
			(island_removal_mode 0)
		)
		(polygon
			(pts
				(xy 27.558746 -18.9357) (xy 27.304746 -19.1897) (xy 27.304746 -29.0957) (xy 28.320746 -30.1117)
				(xy 47.497746 -30.1117) (xy 47.624746 -29.9847) (xy 47.624746 -27.4447) (xy 45.973746 -25.7937)
				(xy 45.973746 -25.0317) (xy 45.846746 -24.9047) (xy 44.322746 -24.9047) (xy 43.433746 -24.0157)
				(xy 43.433746 -19.5707) (xy 42.798746 -18.9357)
			)
		)
		(polygon
			(pts
				(xy 46.964346 -29.4005) (xy 46.710346 -29.4005) (xy 46.710346 -29.6545) (xy 46.964346 -29.6545)
			)
		)
		(polygon
			(pts
				(xy 45.465746 -25.3365) (xy 45.211746 -25.3365) (xy 45.211746 -25.5905) (xy 45.465746 -25.5905)
			)
		)
	)
	(zone
		(layer "F.Cu")
		(hatch none 0.5)
		(connect_pads
			(clearance 0)
		)
		(min_thickness 0.25)
		(keepout
			(tracks not_allowed)
			(vias allowed)
			(pads allowed)
			(copperpour not_allowed)
			(footprints allowed)
		)
		(placement
			(enabled no)
			(sheetname "")
		)
		(fill
			(thermal_gap 0.5)
			(thermal_bridge_width 0.5)
			(island_removal_mode 0)
		)
		(polygon
			(pts
				(arc
					(start 5.923788 -348.22384)
					(mid 5.91081 -348.222494)
					(end 5.898388 -348.218506)
				)
				(arc
					(start 5.894578 -348.491048)
					(mid 6.470396 -349.08363)
					(end 7.062978 -348.507812)
				)
				(xy 7.071614 -347.89364)
				(arc
					(start 7.075932 -347.594174)
					(mid 6.500241 -347.001594)
					(end 5.907532 -347.577156)
				)
				(arc
					(start 5.904738 -347.76664)
					(mid 6.066933 -347.748691)
					(end 6.22173 -347.697044)
				)
				(arc
					(start 6.22173 -347.697044)
					(mid 6.730502 -347.41682)
					(end 6.295898 -347.8022)
				)
				(arc
					(start 6.295898 -347.8022)
					(mid 6.104627 -347.870259)
					(end 5.90296 -347.89364)
				)
				(arc
					(start 5.900166 -348.101412)
					(mid 5.911757 -348.09799)
					(end 5.923788 -348.09684)
				)
				(arc
					(start 5.923788 -348.09684)
					(mid 6.135038 -348.136335)
					(end 6.317742 -348.249494)
				)
				(xy 6.318758 -348.249494)
				(arc
					(start 6.32206 -348.252796)
					(mid 6.685604 -348.705856)
					(end 6.23189 -348.34322)
				)
				(arc
					(start 6.23189 -348.34322)
					(mid 6.088992 -348.254731)
					(end 5.923788 -348.22384)
				)
			)
		)
	)
	(zone
		(layer "F.Cu")
		(hatch none 0.5)
		(connect_pads
			(clearance 0)
		)
		(min_thickness 0.25)
		(keepout
			(tracks not_allowed)
			(vias allowed)
			(pads allowed)
			(copperpour not_allowed)
			(footprints allowed)
		)
		(placement
			(enabled no)
			(sheetname "")
		)
		(fill
			(thermal_gap 0.5)
			(thermal_bridge_width 0.5)
			(island_removal_mode 0)
		)
		(polygon
			(pts
				(arc
					(start 27.24023 -365.912654)
					(mid 26.644981 -365.334548)
					(end 26.06675 -365.929672)
				)
				(arc
					(start 26.083006 -367.02365)
					(mid 26.678382 -367.601754)
					(end 27.256486 -367.006378)
				)
				(xy 27.25547 -366.944148)
				(arc
					(start 26.95321 -366.944148)
					(mid 26.412621 -367.15418)
					(end 26.88463 -366.817148)
				)
				(xy 27.253692 -366.817148) (xy 27.250644 -366.613948) (xy 27.115262 -366.613948)
				(arc
					(start 27.114754 -366.613186)
					(mid 26.930556 -366.571932)
					(end 26.771092 -366.470946)
				)
				(xy 26.770076 -366.470946) (xy 26.751788 -366.452404) (xy 26.751534 -366.452404) (xy 26.711402 -366.412272)
				(arc
					(start 26.711402 -366.411002)
					(mid 26.645569 -366.316535)
					(end 26.604214 -366.209072)
				)
				(arc
					(start 26.604214 -366.209072)
					(mid 26.636814 -365.62932)
					(end 26.734262 -366.201706)
				)
				(arc
					(start 26.734262 -366.201706)
					(mid 26.768854 -366.276348)
					(end 26.81986 -366.340898)
				)
				(arc
					(start 26.84145 -366.362488)
					(mid 26.979182 -366.454581)
					(end 27.141678 -366.486948)
				)
				(xy 27.248866 -366.486948)
			)
		)
	)
	(zone
		(net "P3V3_LX")
		(layer "F.Cu")
		(hatch none 0.5)
		(connect_pads
			(clearance 0.5)
		)
		(min_thickness 0.25)
		(fill yes
			(thermal_gap 0.5)
			(thermal_bridge_width 0.5)
			(island_removal_mode 0)
		)
		(polygon
			(pts
				(xy 214.7316 -433.3748) (xy 214.4014 -433.705) (xy 214.4014 -436.0672) (xy 214.7316 -436.3974) (xy 222.6818 -436.3974)
				(xy 222.8088 -436.2704) (xy 222.8088 -434.975) (xy 222.6818 -434.848) (xy 220.9546 -434.848) (xy 220.9292 -434.8734)
				(xy 220.8276 -434.8734) (xy 220.8022 -434.848) (xy 220.4212 -434.848) (xy 218.948 -433.3748)
			)
		)
		(polygon
			(pts
				(xy 221.462854 -435.3941) (xy 221.208854 -435.3941) (xy 221.208854 -435.6481) (xy 221.462854 -435.6481)
			)
		)
		(polygon
			(pts
				(xy 220.853254 -435.3941) (xy 220.599254 -435.3941) (xy 220.599254 -435.6481) (xy 220.853254 -435.6481)
			)
		)
	)
	(zone
		(net "5V_PRE_2")
		(layer "F.Cu")
		(hatch none 0.5)
		(connect_pads
			(clearance 0.5)
		)
		(min_thickness 0.25)
		(fill yes
			(thermal_gap 0.5)
			(thermal_bridge_width 0.5)
			(island_removal_mode 0)
		)
		(polygon
			(pts
				(xy 216.365582 -276.959568) (xy 216.111582 -277.213568) (xy 216.111582 -279.753568) (xy 216.365582 -280.007568)
				(xy 224.112582 -280.007568) (xy 224.366582 -279.753568) (xy 224.366582 -279.245568) (xy 224.112582 -278.991568)
				(xy 220.683582 -278.991568) (xy 218.651582 -276.959568)
			)
		)
	)
	(zone
		(layer "F.Cu")
		(hatch none 0.5)
		(connect_pads
			(clearance 0)
		)
		(min_thickness 0.25)
		(keepout
			(tracks not_allowed)
			(vias allowed)
			(pads allowed)
			(copperpour not_allowed)
			(footprints allowed)
		)
		(placement
			(enabled no)
			(sheetname "")
		)
		(fill
			(thermal_gap 0.5)
			(thermal_bridge_width 0.5)
			(island_removal_mode 0)
		)
		(polygon
			(pts
				(arc
					(start 7.819644 -363.810804)
					(mid 7.850558 -363.708695)
					(end 7.861046 -363.602524)
				)
				(xy 7.861046 -363.524038) (xy 7.375398 -363.918246)
				(arc
					(start 7.376922 -363.920278)
					(mid 7.291324 -364.745524)
					(end 8.11657 -364.831122)
				)
				(xy 8.118094 -364.833154) (xy 8.805672 -364.275116) (xy 8.805672 -364.274608)
				(arc
					(start 8.804148 -364.27283)
					(mid 8.96496 -363.567199)
					(end 8.318246 -363.242352)
				)
				(arc
					(start 8.318246 -363.38383)
					(mid 8.324016 -363.463013)
					(end 8.341106 -363.540548)
				)
				(arc
					(start 8.341106 -363.540548)
					(mid 8.587535 -364.066391)
					(end 8.229854 -363.608874)
				)
				(arc
					(start 8.229854 -363.608874)
					(mid 8.203397 -363.51124)
					(end 8.191754 -363.410754)
				)
				(xy 8.191246 -363.410246)
				(arc
					(start 8.191246 -363.2835)
					(mid 8.125378 -363.318713)
					(end 8.0645 -363.361986)
				)
				(xy 8.062976 -363.359954) (xy 7.988046 -363.420914) (xy 7.988046 -363.628432)
				(arc
					(start 7.987538 -363.62894)
					(mid 7.975152 -363.733289)
					(end 7.946644 -363.834426)
				)
				(xy 7.947152 -363.835188) (xy 7.936992 -363.859572) (xy 7.846314 -364.078012)
				(arc
					(start 7.83844 -364.098332)
					(mid 7.719642 -364.666468)
					(end 7.7089 -364.08614)
				)
				(xy 7.719568 -364.054136) (xy 7.71906 -364.053374) (xy 7.728966 -364.029498) (xy 7.72922 -364.02899)
			)
		)
	)
	(zone
		(net "12V_PRE_10")
		(layer "F.Cu")
		(hatch none 0.5)
		(connect_pads
			(clearance 0.5)
		)
		(min_thickness 0.25)
		(fill yes
			(thermal_gap 0.5)
			(thermal_bridge_width 0.5)
			(island_removal_mode 0)
		)
		(polygon
			(pts
				(xy 26.161746 -420.017702) (xy 23.494746 -422.684702) (xy 23.494746 -424.208702) (xy 23.113746 -424.589702)
				(xy 20.319746 -424.589702) (xy 20.192746 -424.716702) (xy 20.192746 -425.478702) (xy 20.319746 -425.605702)
				(xy 24.256746 -425.605702) (xy 26.796746 -423.065702) (xy 27.939746 -423.065702) (xy 28.193746 -422.811702)
				(xy 28.193746 -420.271702) (xy 27.939746 -420.017702)
			)
		)
	)
	(zone
		(layer "F.Cu")
		(hatch none 0.5)
		(connect_pads
			(clearance 0)
		)
		(min_thickness 0.25)
		(keepout
			(tracks not_allowed)
			(vias allowed)
			(pads allowed)
			(copperpour not_allowed)
			(footprints allowed)
		)
		(placement
			(enabled no)
			(sheetname "")
		)
		(fill
			(thermal_gap 0.5)
			(thermal_bridge_width 0.5)
			(island_removal_mode 0)
		)
		(polygon
			(pts
				(arc
					(start 16.094456 -120.381014)
					(mid 15.937609 -120.30314)
					(end 15.770606 -120.250458)
				)
				(arc
					(start 15.770098 -120.508268)
					(mid 16.355822 -121.096024)
					(end 16.943578 -120.5103)
				)
				(xy 16.943578 -120.509284) (xy 16.943578 -120.508268)
				(arc
					(start 16.945102 -119.646954)
					(mid 16.359505 -119.059198)
					(end 15.771622 -119.644668)
				)
				(xy 15.771368 -119.770144) (xy 15.90802 -119.770144)
				(arc
					(start 15.91183 -119.770144)
					(mid 15.998563 -119.763479)
					(end 16.08328 -119.743728)
				)
				(arc
					(start 16.08328 -119.743728)
					(mid 16.606328 -119.491425)
					(end 16.148812 -119.849138)
				)
				(arc
					(start 16.148812 -119.849138)
					(mid 16.044643 -119.878124)
					(end 15.93723 -119.89054)
				)
				(xy 15.936722 -119.891048) (xy 15.925038 -119.891048) (xy 15.912084 -119.891048) (xy 15.91183 -119.891048)
				(xy 15.90802 -119.891048) (xy 15.771114 -119.891048) (xy 15.77086 -120.100344) (xy 15.77086 -120.100598)
				(arc
					(start 15.77086 -120.12676)
					(mid 15.977082 -120.188662)
					(end 16.16964 -120.285002)
				)
				(arc
					(start 16.16964 -120.285002)
					(mid 16.586696 -120.689021)
					(end 16.094456 -120.381014)
				)
			)
		)
	)
	(zone
		(net "GND")
		(layer "F.Cu")
		(hatch none 0.5)
		(connect_pads
			(clearance 0.5)
		)
		(min_thickness 0.25)
		(fill yes
			(thermal_gap 0.5)
			(thermal_bridge_width 0.5)
			(island_removal_mode 0)
		)
		(polygon
			(pts
				(xy 0.762254 -309.6006) (xy 0.762254 -342.316054) (xy 1.3208 -342.8746) (xy 5.1816 -342.8746) (xy 6.2484 -341.8078)
				(xy 6.2484 -309.753) (xy 5.8928 -309.3974) (xy 0.965454 -309.3974)
			)
		)
	)
	(zone
		(layer "F.Cu")
		(hatch none 0.5)
		(connect_pads
			(clearance 0.5)
		)
		(min_thickness 0.25)
		(fill
			(thermal_gap 0.5)
			(thermal_bridge_width 0.5)
			(island_removal_mode 0)
		)
		(polygon
			(pts
				(xy 47.624746 -4.7117) (xy 46.735746 -5.6007) (xy 46.735746 -9.4107) (xy 49.656746 -12.3317) (xy 53.085746 -12.3317)
				(xy 53.847746 -11.5697) (xy 53.847746 -5.2197) (xy 53.339746 -4.7117)
			)
		)
	)
	(zone
		(layer "F.Cu")
		(hatch none 0.5)
		(connect_pads
			(clearance 0)
		)
		(min_thickness 0.25)
		(keepout
			(tracks not_allowed)
			(vias allowed)
			(pads allowed)
			(copperpour not_allowed)
			(footprints allowed)
		)
		(placement
			(enabled no)
			(sheetname "")
		)
		(fill
			(thermal_gap 0.5)
			(thermal_bridge_width 0.5)
			(island_removal_mode 0)
		)
		(polygon
			(pts
				(arc
					(start 22.528022 -238.079788)
					(mid 22.014434 -237.428024)
					(end 21.36267 -237.941612)
				)
				(xy 21.310854 -238.379)
				(arc
					(start 21.486368 -238.379)
					(mid 21.627991 -238.350829)
					(end 21.747988 -238.270542)
				)
				(arc
					(start 21.772372 -238.246158)
					(mid 22.058104 -237.741171)
					(end 21.899118 -238.299244)
				)
				(xy 21.837904 -238.360458) (xy 21.819362 -238.379)
				(arc
					(start 21.818092 -238.379)
					(mid 21.676465 -238.468119)
					(end 21.513292 -238.505238)
				)
				(xy 21.512784 -238.506) (xy 21.295868 -238.506) (xy 21.269706 -238.726218)
				(arc
					(start 21.588984 -238.726218)
					(mid 22.124212 -238.950327)
					(end 21.552154 -238.853218)
				)
				(arc
					(start 21.25726 -238.853218)
					(mid 21.801287 -239.454125)
					(end 22.426422 -238.938054)
				)
			)
		)
	)
	(zone
		(layer "F.Cu")
		(hatch none 0.5)
		(connect_pads
			(clearance 0)
		)
		(min_thickness 0.25)
		(keepout
			(tracks allowed)
			(vias allowed)
			(pads allowed)
			(copperpour allowed)
			(footprints not_allowed)
		)
		(placement
			(enabled no)
			(sheetname "")
		)
		(fill
			(thermal_gap 0.5)
			(thermal_bridge_width 0.5)
			(island_removal_mode 0)
		)
		(polygon
			(pts
				(arc
					(start 4.500118 -479.400108)
					(mid 8.50011 -483.4001)
					(end 4.500118 -487.400092)
				)
				(arc
					(start 4.500118 -487.400092)
					(mid 0.500126 -483.4001)
					(end 4.500118 -479.400108)
				)
			)
		)
	)
	(zone
		(layer "F.Cu")
		(hatch none 0.5)
		(connect_pads
			(clearance 0)
		)
		(min_thickness 0.25)
		(keepout
			(tracks not_allowed)
			(vias allowed)
			(pads allowed)
			(copperpour not_allowed)
			(footprints allowed)
		)
		(placement
			(enabled no)
			(sheetname "")
		)
		(fill
			(thermal_gap 0.5)
			(thermal_bridge_width 0.5)
			(island_removal_mode 0)
		)
		(polygon
			(pts
				(arc
					(start 32.463486 -161.429954)
					(mid 31.876873 -160.84296)
					(end 31.290006 -161.4297)
				)
				(arc
					(start 31.290006 -161.506916)
					(mid 31.38075 -161.509596)
					(end 31.470092 -161.525712)
				)
				(xy 31.589472 -161.525712)
				(arc
					(start 31.600902 -161.525458)
					(mid 32.12181 -161.270945)
					(end 31.676594 -161.642298)
				)
				(arc
					(start 31.676594 -161.642298)
					(mid 31.646939 -161.648202)
					(end 31.616904 -161.651696)
				)
				(xy 31.615888 -161.652712) (xy 31.435294 -161.652712)
				(arc
					(start 31.429198 -161.646362)
					(mid 31.360046 -161.635199)
					(end 31.290006 -161.63417)
				)
				(arc
					(start 31.290006 -161.838132)
					(mid 31.34106 -161.837689)
					(end 31.391352 -161.846514)
				)
				(arc
					(start 31.391352 -161.846514)
					(mid 31.54418 -161.90861)
					(end 31.677864 -162.005264)
				)
				(xy 31.678626 -162.005264)
				(arc
					(start 31.720028 -162.046666)
					(mid 32.083372 -162.499926)
					(end 31.630112 -162.136582)
				)
				(arc
					(start 31.607252 -162.113722)
					(mid 31.491994 -162.025042)
					(end 31.357824 -161.968942)
				)
				(arc
					(start 31.357824 -161.968942)
					(mid 31.324071 -161.963689)
					(end 31.290006 -161.966148)
				)
				(arc
					(start 31.290006 -162.2933)
					(mid 31.876746 -162.88004)
					(end 32.463486 -162.2933)
				)
			)
		)
	)
	(zone
		(net "P12V_HDD12")
		(layer "F.Cu")
		(hatch none 0.5)
		(connect_pads
			(clearance 0.5)
		)
		(min_thickness 0.25)
		(fill yes
			(thermal_gap 0.5)
			(thermal_bridge_width 0.5)
			(island_removal_mode 0)
		)
		(polygon
			(pts
				(xy 20.827746 -215.7857) (xy 20.573746 -216.0397) (xy 20.573746 -218.0717) (xy 20.700746 -218.1987)
				(xy 24.891746 -218.1987) (xy 25.272746 -217.8177) (xy 25.272746 -216.1667) (xy 24.891746 -215.7857)
			)
		)
	)
	(zone
		(layer "F.Cu")
		(hatch none 0.5)
		(connect_pads
			(clearance 0)
		)
		(min_thickness 0.25)
		(keepout
			(tracks allowed)
			(vias allowed)
			(pads allowed)
			(copperpour allowed)
			(footprints not_allowed)
		)
		(placement
			(enabled no)
			(sheetname "")
		)
		(fill
			(thermal_gap 0.5)
			(thermal_bridge_width 0.5)
			(island_removal_mode 0)
		)
		(polygon
			(pts
				(xy 212.989922 -441.1599) (xy 212.989922 -433.159916) (xy 220.989906 -433.159916) (xy 220.989906 -441.1599)
			)
		)
	)
	(zone
		(net "12V_PRE_7")
		(layer "F.Cu")
		(hatch none 0.5)
		(connect_pads
			(clearance 0.5)
		)
		(min_thickness 0.25)
		(fill yes
			(thermal_gap 0.5)
			(thermal_bridge_width 0.5)
			(island_removal_mode 0)
		)
		(polygon
			(pts
				(xy 35.940746 -286.6517) (xy 32.765746 -289.8267) (xy 28.574746 -289.8267) (xy 28.320746 -290.0807)
				(xy 28.320746 -290.8427) (xy 28.701746 -291.2237) (xy 32.765746 -291.2237) (xy 36.575746 -287.4137)
				(xy 39.496746 -287.4137) (xy 39.623746 -287.2867) (xy 39.623746 -286.7787) (xy 39.496746 -286.6517)
			)
		)
	)
	(zone
		(layer "F.Cu")
		(hatch none 0.5)
		(connect_pads
			(clearance 0)
		)
		(min_thickness 0.25)
		(keepout
			(tracks not_allowed)
			(vias allowed)
			(pads allowed)
			(copperpour not_allowed)
			(footprints allowed)
		)
		(placement
			(enabled no)
			(sheetname "")
		)
		(fill
			(thermal_gap 0.5)
			(thermal_bridge_width 0.5)
			(island_removal_mode 0)
		)
		(polygon
			(pts
				(xy 8.036052 -423.5704) (xy 8.036052 -423.57421) (xy 8.036052 -423.69359)
				(arc
					(start 8.036052 -423.6974)
					(mid 8.051236 -423.783858)
					(end 8.09498 -423.85996)
				)
				(arc
					(start 8.09498 -423.85996)
					(mid 8.459175 -424.312826)
					(end 8.00862 -423.945812)
				)
				(xy 8.00735 -423.944288)
				(arc
					(start 8.00735 -423.943272)
					(mid 7.943675 -423.840626)
					(end 7.91591 -423.723054)
				)
				(xy 7.915148 -423.722292) (xy 7.915148 -423.707052) (xy 7.915148 -423.6974) (xy 7.915148 -423.69359)
				(xy 7.915148 -423.57421) (xy 7.915148 -423.5704) (xy 7.915148 -423.562018) (xy 7.915148 -423.545508)
				(xy 7.915402 -423.545254) (xy 7.707376 -423.532808) (xy 7.705852 -423.570146) (xy 7.705852 -423.573956)
				(xy 7.705852 -423.69359) (xy 7.705852 -423.6974) (xy 7.705852 -423.70629) (xy 7.705852 -423.722292)
				(arc
					(start 7.704836 -423.723308)
					(mid 7.683078 -423.813178)
					(end 7.635494 -423.892472)
				)
				(arc
					(start 7.635494 -423.892472)
					(mid 7.186625 -424.261273)
					(end 7.54888 -423.807128)
				)
				(arc
					(start 7.54888 -423.807128)
					(mid 7.575704 -423.755153)
					(end 7.584948 -423.6974)
				)
				(xy 7.584948 -423.69359) (xy 7.584948 -423.573956) (xy 7.584948 -423.570146) (xy 7.584948 -423.5577)
				(xy 7.584948 -423.545254) (xy 7.585456 -423.544746) (xy 7.586472 -423.525442) (xy 7.46506 -423.518076)
				(xy 7.423912 -423.515536)
				(arc
					(start 7.423658 -423.518076)
					(mid 6.856476 -424.020742)
					(end 7.359142 -424.587924)
				)
				(xy 7.358888 -424.590464) (xy 8.22071 -424.642788) (xy 8.220964 -424.642534)
				(arc
					(start 8.221218 -424.640248)
					(mid 8.7884 -424.137582)
					(end 8.285734 -423.5704)
				)
				(xy 8.285988 -423.56786) (xy 8.037068 -423.552874)
			)
		)
	)
	(zone
		(net "P5V_HDD8")
		(layer "F.Cu")
		(hatch none 0.5)
		(connect_pads
			(clearance 0.5)
		)
		(min_thickness 0.25)
		(fill yes
			(thermal_gap 0.5)
			(thermal_bridge_width 0.5)
			(island_removal_mode 0)
		)
		(polygon
			(pts
				(xy 59.2328 -176.657) (xy 57.657746 -178.232054) (xy 57.657746 -180.0987) (xy 57.149746 -180.6067)
				(xy 52.069746 -180.6067) (xy 48.640746 -177.1777) (xy 36.956746 -177.1777) (xy 36.829746 -177.3047)
				(xy 36.829746 -179.0827) (xy 37.083746 -179.3367) (xy 39.4208 -179.3367) (xy 40.9067 -180.8226)
				(xy 46.482 -180.8226) (xy 48.9331 -183.2737) (xy 54.3179 -183.2737) (xy 54.737 -183.2737) (xy 61.8363 -183.2737)
				(xy 62.1538 -182.9562) (xy 64.0715 -182.9562) (xy 65.0113 -183.896) (xy 65.9384 -183.896) (xy 66.293746 -183.540654)
				(xy 66.293746 -179.3367) (xy 65.912746 -178.9557) (xy 63.627 -178.9557) (xy 63.3984 -178.7271) (xy 63.3984 -176.911)
				(xy 63.1444 -176.657)
			)
		)
		(polygon
			(pts
				(xy 56.057546 -182.1307) (xy 55.803546 -182.1307) (xy 55.803546 -182.3847) (xy 56.057546 -182.3847)
			)
		)
		(polygon
			(pts
				(xy 55.193946 -182.1307) (xy 54.939946 -182.1307) (xy 54.939946 -182.3847) (xy 55.193946 -182.3847)
			)
		)
		(polygon
			(pts
				(xy 60.070746 -179.8447) (xy 59.816746 -179.8447) (xy 59.816746 -180.0987) (xy 60.070746 -180.0987)
			)
		)
		(polygon
			(pts
				(xy 61.213746 -177.0507) (xy 60.959746 -177.0507) (xy 60.959746 -177.3047) (xy 61.213746 -177.3047)
			)
		)
		(polygon
			(pts
				(xy 60.070746 -177.0507) (xy 59.816746 -177.0507) (xy 59.816746 -177.3047) (xy 60.070746 -177.3047)
			)
		)
	)
	(zone
		(net "P3V3")
		(layer "F.Cu")
		(hatch none 0.5)
		(connect_pads
			(clearance 0.5)
		)
		(min_thickness 0.25)
		(fill yes
			(thermal_gap 0.5)
			(thermal_bridge_width 0.5)
			(island_removal_mode 0)
		)
		(polygon
			(pts
				(xy 191.5414 -488.1118) (xy 191.134746 -488.518454) (xy 191.134746 -492.3917) (xy 191.261746 -492.5187)
				(xy 193.547746 -492.5187) (xy 193.801746 -492.2647) (xy 193.801746 -491.3757) (xy 194.309746 -490.8677)
				(xy 197.230746 -490.8677) (xy 197.357746 -490.9947) (xy 197.357746 -492.6457) (xy 197.484746 -492.7727)
				(xy 197.865746 -492.7727) (xy 197.992746 -492.6457) (xy 197.992746 -491.7567) (xy 199.389746 -490.3597)
				(xy 200.024746 -490.3597) (xy 200.659746 -490.9947) (xy 200.659746 -492.1377) (xy 200.786746 -492.2647)
				(xy 201.040746 -492.2647) (xy 201.167746 -492.1377) (xy 201.167746 -488.4166) (xy 200.862946 -488.1118)
			)
		)
		(polygon
			(pts
				(xy 191.798956 -491.772702) (xy 191.544956 -491.772702) (xy 191.544956 -492.026702) (xy 191.798956 -492.026702)
			)
		)
		(polygon
			(pts
				(xy 198.068946 -491.0963) (xy 197.814946 -491.0963) (xy 197.814946 -491.3503) (xy 198.068946 -491.3503)
			)
		)
		(polygon
			(pts
				(xy 199.6948 -488.569) (xy 199.4408 -488.569) (xy 199.4408 -488.823) (xy 199.6948 -488.823)
			)
		)
		(polygon
			(pts
				(xy 199.0852 -488.569) (xy 198.8312 -488.569) (xy 198.8312 -488.823) (xy 199.0852 -488.823)
			)
		)
		(polygon
			(pts
				(xy 193.3448 -488.569) (xy 193.0908 -488.569) (xy 193.0908 -488.823) (xy 193.3448 -488.823)
			)
		)
		(polygon
			(pts
				(xy 192.7352 -488.569) (xy 192.4812 -488.569) (xy 192.4812 -488.823) (xy 192.7352 -488.823)
			)
		)
	)
	(zone
		(net "P5VA")
		(layer "F.Cu")
		(hatch none 0.5)
		(connect_pads
			(clearance 0.5)
		)
		(min_thickness 0.25)
		(fill yes
			(thermal_gap 0.5)
			(thermal_bridge_width 0.5)
			(island_removal_mode 0)
		)
		(polygon
			(pts
				(xy 201.913744 -484.34371) (xy 201.532744 -484.72471) (xy 201.532744 -489.67771) (xy 201.786744 -489.93171)
				(xy 205.977744 -489.93171) (xy 206.358744 -489.55071) (xy 206.358744 -484.59771) (xy 206.104744 -484.34371)
			)
		)
	)
	(zone
		(net "P12V")
		(layer "F.Cu")
		(hatch none 0.5)
		(connect_pads
			(clearance 0.5)
		)
		(min_thickness 0.25)
		(fill yes
			(thermal_gap 0.5)
			(thermal_bridge_width 0.5)
			(island_removal_mode 0)
		)
		(polygon
			(pts
				(xy 73.659492 -397.792956) (xy 73.278492 -398.173956) (xy 73.278492 -401.094956) (xy 73.518268 -401.334732)
				(xy 73.533 -401.32) (xy 77.089 -401.32) (xy 77.343 -401.574) (xy 77.343 -402.209) (xy 77.47 -402.336)
				(xy 79.121 -402.336) (xy 79.248 -402.209) (xy 79.248 -401.828) (xy 78.231492 -400.811492) (xy 78.231492 -398.046956)
				(xy 77.977492 -397.792956)
			)
		)
		(polygon
			(pts
				(xy 78.7146 -401.6248) (xy 78.4606 -401.6248) (xy 78.4606 -401.8788) (xy 78.7146 -401.8788)
			)
		)
		(polygon
			(pts
				(xy 78.2828 -401.574) (xy 78.0288 -401.574) (xy 78.0288 -401.828) (xy 78.2828 -401.828)
			)
		)
		(polygon
			(pts
				(xy 77.774546 -399.7071) (xy 77.520546 -399.7071) (xy 77.520546 -399.9611) (xy 77.774546 -399.9611)
			)
		)
		(polygon
			(pts
				(xy 77.774546 -399.1483) (xy 77.520546 -399.1483) (xy 77.520546 -399.4023) (xy 77.774546 -399.4023)
			)
		)
	)
	(zone
		(layer "F.Cu")
		(hatch none 0.5)
		(connect_pads
			(clearance 0)
		)
		(min_thickness 0.25)
		(keepout
			(tracks allowed)
			(vias allowed)
			(pads allowed)
			(copperpour allowed)
			(footprints allowed)
		)
		(placement
			(enabled no)
			(sheetname "")
		)
		(fill
			(thermal_gap 0.5)
			(thermal_bridge_width 0.5)
			(island_removal_mode 0)
		)
		(polygon
			(pts
				(xy 239.648746 -23.5077) (xy 240.029746 -23.1267) (xy 240.029746 -22.1107) (xy 239.902746 -21.9837)
				(xy 238.251746 -21.9837) (xy 238.124746 -22.1107) (xy 238.124746 -22.3647) (xy 238.124746 -22.9997)
				(xy 238.124746 -23.3807) (xy 238.378746 -23.6347) (xy 239.521746 -23.6347)
			)
		)
	)
	(zone
		(layer "F.Cu")
		(hatch none 0.5)
		(connect_pads
			(clearance 0)
		)
		(min_thickness 0.25)
		(keepout
			(tracks allowed)
			(vias allowed)
			(pads allowed)
			(copperpour allowed)
			(footprints allowed)
		)
		(placement
			(enabled no)
			(sheetname "")
		)
		(fill
			(thermal_gap 0.5)
			(thermal_bridge_width 0.5)
			(island_removal_mode 0)
		)
		(polygon
			(pts
				(xy 19.684746 -338.9757) (xy 21.462746 -338.9757) (xy 21.716746 -338.9757) (xy 21.970746 -339.2297)
				(xy 21.970746 -341.6427) (xy 21.843746 -341.7697) (xy 21.208746 -341.7697) (xy 19.938746 -341.7697)
				(xy 19.557746 -341.7697) (xy 19.303746 -341.5157) (xy 19.303746 -339.3567)
			)
		)
	)
	(zone
		(net "12V_PRE_1")
		(layer "F.Cu")
		(hatch none 0.5)
		(connect_pads
			(clearance 0.5)
		)
		(min_thickness 0.25)
		(fill yes
			(thermal_gap 0.5)
			(thermal_bridge_width 0.5)
			(island_removal_mode 0)
		)
		(polygon
			(pts
				(xy 218.058746 -388.1247) (xy 217.804746 -388.3787) (xy 217.804746 -391.0457) (xy 218.058746 -391.2997)
				(xy 219.836746 -391.2997) (xy 220.725746 -390.4107) (xy 224.408746 -390.4107) (xy 224.535746 -390.2837)
				(xy 224.535746 -389.6487) (xy 224.408746 -389.5217) (xy 220.979746 -389.5217) (xy 219.582746 -388.1247)
			)
		)
	)
	(zone
		(layer "F.Cu")
		(hatch none 0.5)
		(connect_pads
			(clearance 0)
		)
		(min_thickness 0.25)
		(keepout
			(tracks allowed)
			(vias allowed)
			(pads allowed)
			(copperpour allowed)
			(footprints allowed)
		)
		(placement
			(enabled no)
			(sheetname "")
		)
		(fill
			(thermal_gap 0.5)
			(thermal_bridge_width 0.5)
			(island_removal_mode 0)
		)
		(polygon
			(pts
				(xy 57.784746 -20.2057) (xy 57.784746 -19.0627) (xy 57.657746 -18.9357) (xy 56.006746 -18.9357)
				(xy 55.752746 -19.1897) (xy 55.752746 -20.2057) (xy 55.879746 -20.3327) (xy 57.657746 -20.3327)
			)
		)
	)
	(zone
		(layer "F.Cu")
		(hatch none 0.5)
		(connect_pads
			(clearance 0)
		)
		(min_thickness 0.25)
		(keepout
			(tracks allowed)
			(vias allowed)
			(pads allowed)
			(copperpour allowed)
			(footprints not_allowed)
		)
		(placement
			(enabled no)
			(sheetname "")
		)
		(fill
			(thermal_gap 0.5)
			(thermal_bridge_width 0.5)
			(island_removal_mode 0)
		)
		(polygon
			(pts
				(arc
					(start 69.000116 -484.000048)
					(mid 65.000124 -480.000056)
					(end 69.000116 -476.000064)
				)
				(arc
					(start 69.000116 -476.000064)
					(mid 73.000108 -480.000056)
					(end 69.000116 -484.000048)
				)
			)
		)
	)
	(zone
		(net "P3V3")
		(layer "F.Cu")
		(hatch none 0.5)
		(connect_pads
			(clearance 0.5)
		)
		(min_thickness 0.25)
		(fill yes
			(thermal_gap 0.5)
			(thermal_bridge_width 0.5)
			(island_removal_mode 0)
		)
		(polygon
			(pts
				(xy 190.753746 -384.8227) (xy 189.610746 -385.9657) (xy 189.610746 -387.6167) (xy 189.991746 -387.9977)
				(xy 191.642746 -387.9977) (xy 192.023746 -388.3787) (xy 192.023746 -389.0137) (xy 192.277746 -389.2677)
				(xy 194.436746 -389.2677) (xy 194.690746 -389.0137) (xy 194.690746 -387.4897) (xy 194.944746 -387.2357)
				(xy 197.738746 -387.2357) (xy 197.992746 -387.4897) (xy 197.992746 -389.2677) (xy 198.119746 -389.3947)
				(xy 198.373746 -389.3947) (xy 198.627746 -389.1407) (xy 198.627746 -387.9977) (xy 199.135746 -387.4897)
				(xy 200.913746 -387.4897) (xy 201.167746 -387.7437) (xy 201.167746 -388.8867) (xy 201.294746 -389.0137)
				(xy 201.548746 -389.0137) (xy 201.929746 -388.6327) (xy 201.929746 -387.6167) (xy 200.913746 -386.6007)
				(xy 200.913746 -385.2037) (xy 200.532746 -384.8227)
			)
		)
		(polygon
			(pts
				(xy 192.691258 -388.542784) (xy 192.437258 -388.542784) (xy 192.437258 -388.796784) (xy 192.691258 -388.796784)
			)
		)
		(polygon
			(pts
				(xy 193.9798 -385.445) (xy 193.7258 -385.445) (xy 193.7258 -385.699) (xy 193.9798 -385.699)
			)
		)
		(polygon
			(pts
				(xy 193.3702 -385.445) (xy 193.1162 -385.445) (xy 193.1162 -385.699) (xy 193.3702 -385.699)
			)
		)
		(polygon
			(pts
				(xy 199.3646 -385.3688) (xy 199.1106 -385.3688) (xy 199.1106 -385.6228) (xy 199.3646 -385.6228)
			)
		)
		(polygon
			(pts
				(xy 198.755 -385.3688) (xy 198.501 -385.3688) (xy 198.501 -385.6228) (xy 198.755 -385.6228)
			)
		)
	)
	(zone
		(net "P12V")
		(layer "F.Cu")
		(hatch none 0.5)
		(connect_pads
			(clearance 0.5)
		)
		(min_thickness 0.25)
		(fill yes
			(thermal_gap 0.5)
			(thermal_bridge_width 0.5)
			(island_removal_mode 0)
		)
		(polygon
			(pts
				(xy 241.8588 -363.5502) (xy 240.792 -364.617) (xy 240.792 -383.3114) (xy 241.2746 -383.794) (xy 257.683 -383.794)
				(xy 258.1148 -383.3622) (xy 258.1148 -363.9312) (xy 257.7338 -363.5502)
			)
		)
	)
	(zone
		(net "P12V")
		(layer "F.Cu")
		(hatch none 0.5)
		(connect_pads
			(clearance 0.5)
		)
		(min_thickness 0.25)
		(fill yes
			(thermal_gap 0.5)
			(thermal_bridge_width 0.5)
			(island_removal_mode 0)
		)
		(polygon
			(pts
				(xy 196.469 -291.437568) (xy 196.328284 -291.578284) (xy 196.328284 -293.624) (xy 196.088 -293.864284)
				(xy 196.088 -293.878) (xy 195.961 -294.005) (xy 193.548 -294.005) (xy 193.421 -294.132) (xy 193.421 -294.64)
				(xy 193.929 -295.148) (xy 195.072 -295.148) (xy 195.453 -295.529) (xy 195.453 -297.688) (xy 195.58 -297.815)
				(xy 198.501 -297.815) (xy 199.601582 -296.714418) (xy 199.601582 -291.818568) (xy 199.220582 -291.437568)
			)
		)
		(polygon
			(pts
				(xy 195.2498 -294.513) (xy 194.9958 -294.513) (xy 194.9958 -294.767) (xy 195.2498 -294.767)
			)
		)
		(polygon
			(pts
				(xy 194.6402 -294.513) (xy 194.3862 -294.513) (xy 194.3862 -294.767) (xy 194.6402 -294.767)
			)
		)
		(polygon
			(pts
				(xy 194.2084 -294.4622) (xy 193.9544 -294.4622) (xy 193.9544 -294.7162) (xy 194.2084 -294.7162)
			)
		)
	)
	(zone
		(net "P12V_HDD12")
		(layer "F.Cu")
		(hatch none 0.5)
		(connect_pads
			(clearance 0.5)
		)
		(min_thickness 0.25)
		(fill yes
			(thermal_gap 0.5)
			(thermal_bridge_width 0.5)
			(island_removal_mode 0)
		)
		(polygon
			(pts
				(xy 54.4068 -209.8548) (xy 54.101746 -210.159854) (xy 54.101746 -216.07145) (xy 53.34 -216.833196)
				(xy 49.370996 -216.833196) (xy 48.640746 -217.5637) (xy 39.369746 -217.5637) (xy 39.115746 -217.8177)
				(xy 39.115746 -219.5957) (xy 39.242746 -219.7227) (xy 43.560746 -219.7227) (xy 44.068746 -220.2307)
				(xy 44.068746 -222.1357) (xy 45.211746 -223.2787) (xy 50.9778 -223.2787) (xy 59.0931 -223.2787)
				(xy 59.2074 -223.1644) (xy 59.689746 -222.682054) (xy 59.689746 -211.632546) (xy 57.912 -209.8548)
			)
		)
		(polygon
			(pts
				(xy 47.116746 -220.246702) (xy 46.862746 -220.246702) (xy 46.862746 -220.500702) (xy 47.116746 -220.500702)
			)
		)
		(polygon
			(pts
				(xy 45.973746 -220.246702) (xy 45.719746 -220.246702) (xy 45.719746 -220.500702) (xy 45.973746 -220.500702)
			)
		)
		(polygon
			(pts
				(xy 41.960546 -218.341702) (xy 41.706546 -218.341702) (xy 41.706546 -218.595702) (xy 41.960546 -218.595702)
			)
		)
		(polygon
			(pts
				(xy 41.096946 -218.341702) (xy 40.842946 -218.341702) (xy 40.842946 -218.595702) (xy 41.096946 -218.595702)
			)
		)
	)
	(zone
		(net "12V_PRE_12")
		(layer "F.Cu")
		(hatch none 0.5)
		(connect_pads
			(clearance 0.5)
		)
		(min_thickness 0.25)
		(fill yes
			(thermal_gap 0.5)
			(thermal_bridge_width 0.5)
			(island_removal_mode 0)
		)
		(polygon
			(pts
				(xy 39.496746 -220.1037) (xy 39.242746 -220.3577) (xy 39.242746 -222.8977) (xy 39.623746 -223.2787)
				(xy 42.798746 -223.2787) (xy 43.052746 -223.0247) (xy 43.052746 -220.4847) (xy 42.671746 -220.1037)
			)
		)
		(polygon
			(pts
				(xy 42.417746 -220.246702) (xy 42.163746 -220.246702) (xy 42.163746 -220.500702) (xy 42.417746 -220.500702)
			)
		)
		(polygon
			(pts
				(xy 41.274746 -220.246702) (xy 41.020746 -220.246702) (xy 41.020746 -220.500702) (xy 41.274746 -220.500702)
			)
		)
	)
	(zone
		(net "P5V_HDD10")
		(layer "F.Cu")
		(hatch none 0.5)
		(connect_pads
			(clearance 0.5)
		)
		(min_thickness 0.25)
		(fill yes
			(thermal_gap 0.5)
			(thermal_bridge_width 0.5)
			(island_removal_mode 0)
		)
		(polygon
			(pts
				(xy 25.223724 -425.908724) (xy 23.367746 -427.764702) (xy 23.367746 -429.288702) (xy 23.113746 -429.542702)
				(xy 20.446746 -429.542702) (xy 20.319746 -429.669702) (xy 20.319746 -431.701702) (xy 20.446746 -431.828702)
				(xy 23.748746 -431.828702) (xy 25.399746 -430.177702) (xy 25.399746 -428.780702) (xy 26.034746 -428.145702)
				(xy 28.447746 -428.145702) (xy 28.701746 -428.399702) (xy 28.701746 -431.320702) (xy 28.955746 -431.574702)
				(xy 32.765746 -431.574702) (xy 33.073848 -431.2666) (xy 34.108644 -431.2666) (xy 36.702746 -433.860702)
				(xy 42.671746 -433.860702) (xy 42.925746 -433.606702) (xy 42.925746 -430.812702) (xy 42.798746 -430.685702)
				(xy 40.2082 -430.685702) (xy 35.431476 -425.908724)
			)
		)
		(polygon
			(pts
				(xy 32.638746 -428.526702) (xy 32.384746 -428.526702) (xy 32.384746 -428.780702) (xy 32.638746 -428.780702)
			)
		)
		(polygon
			(pts
				(xy 31.495746 -428.526702) (xy 31.241746 -428.526702) (xy 31.241746 -428.780702) (xy 31.495746 -428.780702)
			)
		)
		(polygon
			(pts
				(xy 27.355546 -426.748702) (xy 27.101546 -426.748702) (xy 27.101546 -427.002702) (xy 27.355546 -427.002702)
			)
		)
		(polygon
			(pts
				(xy 26.491946 -426.748702) (xy 26.237946 -426.748702) (xy 26.237946 -427.002702) (xy 26.491946 -427.002702)
			)
		)
	)
	(zone
		(layer "F.Cu")
		(hatch none 0.5)
		(connect_pads
			(clearance 0)
		)
		(min_thickness 0.25)
		(keepout
			(tracks allowed)
			(vias allowed)
			(pads allowed)
			(copperpour allowed)
			(footprints allowed)
		)
		(placement
			(enabled no)
			(sheetname "")
		)
		(fill
			(thermal_gap 0.5)
			(thermal_bridge_width 0.5)
			(island_removal_mode 0)
		)
		(polygon
			(pts
				(xy 46.482 -212.8012) (xy 46.482 -210.9978) (xy 47.5488 -210.9978) (xy 47.5742 -210.9978) (xy 47.6758 -211.0994)
				(xy 47.6758 -212.7758) (xy 47.6504 -212.8012) (xy 47.5488 -212.8012)
			)
		)
	)
	(zone
		(net "P5VB")
		(layer "F.Cu")
		(hatch none 0.5)
		(connect_pads
			(clearance 0.5)
		)
		(min_thickness 0.25)
		(fill yes
			(thermal_gap 0.5)
			(thermal_bridge_width 0.5)
			(island_removal_mode 0)
		)
		(polygon
			(pts
				(xy 67.817746 -74.4347) (xy 67.436746 -74.8157) (xy 67.436492 -74.8157) (xy 67.436492 -79.3877)
				(xy 67.436746 -79.3877) (xy 67.436746 -80.2767) (xy 67.690746 -80.5307) (xy 71.500746 -80.5307)
				(xy 71.507096 -80.524096) (xy 73.399904 -80.524096) (xy 73.66 -80.264) (xy 73.66 -75.184) (xy 72.963786 -74.487786)
				(xy 71.43496 -74.487786) (xy 71.381874 -74.4347)
			)
		)
	)
	(zone
		(layer "F.Cu")
		(hatch none 0.5)
		(connect_pads
			(clearance 0)
		)
		(min_thickness 0.25)
		(keepout
			(tracks not_allowed)
			(vias allowed)
			(pads allowed)
			(copperpour not_allowed)
			(footprints allowed)
		)
		(placement
			(enabled no)
			(sheetname "")
		)
		(fill
			(thermal_gap 0.5)
			(thermal_bridge_width 0.5)
			(island_removal_mode 0)
		)
		(polygon
			(pts
				(xy 32.003746 -372.5164) (xy 32.034226 -372.514622) (xy 31.982156 -372.061232)
				(arc
					(start 31.979616 -372.061486)
					(mid 31.386018 -371.590316)
					(end 30.914848 -372.183914)
				)
				(xy 30.912308 -372.184168) (xy 31.034736 -373.248428) (xy 31.03499 -373.248682)
				(arc
					(start 31.037276 -373.248428)
					(mid 31.56851 -373.723104)
					(end 32.10179 -373.250714)
				)
				(arc
					(start 31.854648 -373.250714)
					(mid 31.277683 -373.187214)
					(end 31.854648 -373.123714)
				)
				(xy 32.10433 -373.123714) (xy 32.048704 -372.64086) (xy 32.030924 -372.642384) (xy 32.030162 -372.6434)
				(xy 31.92526 -372.6434)
				(arc
					(start 31.924752 -372.642892)
					(mid 31.709181 -372.592431)
					(end 31.52648 -372.467378)
				)
				(arc
					(start 31.52648 -372.467378)
					(mid 31.502118 -372.441055)
					(end 31.479744 -372.413022)
				)
				(arc
					(start 31.479744 -372.413022)
					(mid 31.349064 -371.847672)
					(end 31.606744 -372.367556)
				)
				(arc
					(start 31.616396 -372.377462)
					(mid 31.77021 -372.4803)
					(end 31.951676 -372.5164)
				)
			)
		)
	)
	(zone
		(net "5V_PRE_14")
		(layer "F.Cu")
		(hatch none 0.5)
		(connect_pads
			(clearance 0.5)
		)
		(min_thickness 0.25)
		(fill yes
			(thermal_gap 0.5)
			(thermal_bridge_width 0.5)
			(island_removal_mode 0)
		)
		(polygon
			(pts
				(xy 73.151746 -18.0467) (xy 72.897746 -18.3007) (xy 72.897746 -20.7137) (xy 73.278746 -21.0947)
				(xy 75.564746 -21.0947) (xy 75.691746 -20.9677) (xy 75.691746 -18.4277) (xy 75.310746 -18.0467)
			)
		)
	)
	(zone
		(net "5V_PRE_3")
		(layer "F.Cu")
		(hatch none 0.5)
		(connect_pads
			(clearance 0.5)
		)
		(min_thickness 0.25)
		(fill yes
			(thermal_gap 0.5)
			(thermal_bridge_width 0.5)
			(island_removal_mode 0)
		)
		(polygon
			(pts
				(xy 216.457784 -173.960028) (xy 216.203784 -174.214028) (xy 216.203784 -176.754028) (xy 216.457784 -177.008028)
				(xy 224.204784 -177.008028) (xy 224.458784 -176.754028) (xy 224.458784 -176.246028) (xy 224.204784 -175.992028)
				(xy 220.775784 -175.992028) (xy 218.743784 -173.960028)
			)
		)
	)
	(zone
		(net "P5V_HDD11")
		(layer "F.Cu")
		(hatch none 0.5)
		(connect_pads
			(clearance 0.5)
		)
		(min_thickness 0.25)
		(fill yes
			(thermal_gap 0.5)
			(thermal_bridge_width 0.5)
			(island_removal_mode 0)
		)
		(polygon
			(pts
				(xy 32.765746 -322.8467) (xy 32.511746 -323.1007) (xy 25.161748 -323.1007) (xy 23.494746 -324.767702)
				(xy 23.494746 -326.291702) (xy 23.240746 -326.545702) (xy 20.573746 -326.545702) (xy 20.446746 -326.672702)
				(xy 20.446746 -328.704702) (xy 20.573746 -328.831702) (xy 23.875746 -328.831702) (xy 25.526746 -327.180702)
				(xy 25.526746 -325.783702) (xy 25.907746 -325.402702) (xy 27.939746 -325.402702) (xy 28.320746 -325.783702)
				(xy 28.320746 -328.577702) (xy 28.701746 -328.958702) (xy 37.182298 -328.958702) (xy 37.719 -328.422)
				(xy 37.719 -326.3646) (xy 38.0619 -326.0217) (xy 42.417746 -326.0217) (xy 42.671746 -325.7677) (xy 42.671746 -323.2277)
				(xy 42.290746 -322.8467)
			)
		)
		(polygon
			(pts
				(xy 31.114746 -325.783702) (xy 30.860746 -325.783702) (xy 30.860746 -326.037702) (xy 31.114746 -326.037702)
			)
		)
		(polygon
			(pts
				(xy 27.101546 -323.751702) (xy 26.847546 -323.751702) (xy 26.847546 -324.005702) (xy 27.101546 -324.005702)
			)
		)
		(polygon
			(pts
				(xy 26.237946 -323.751702) (xy 25.983946 -323.751702) (xy 25.983946 -324.005702) (xy 26.237946 -324.005702)
			)
		)
	)
	(zone
		(net "5V_PRE_8")
		(layer "F.Cu")
		(hatch none 0.5)
		(connect_pads
			(clearance 0.5)
		)
		(min_thickness 0.25)
		(fill yes
			(thermal_gap 0.5)
			(thermal_bridge_width 0.5)
			(island_removal_mode 0)
		)
		(polygon
			(pts
				(xy 37.083746 -176.0347) (xy 36.829746 -176.2887) (xy 36.829746 -176.5427) (xy 37.083746 -176.7967)
				(xy 48.767746 -176.7967) (xy 52.069746 -180.0987) (xy 56.387746 -180.0987) (xy 56.641746 -179.8447)
				(xy 56.641746 -177.4317) (xy 56.514746 -177.3047) (xy 51.180746 -177.3047) (xy 49.910746 -176.0347)
			)
		)
	)
	(zone
		(net "5V_PRE_4")
		(layer "F.Cu")
		(hatch none 0.5)
		(connect_pads
			(clearance 0.5)
		)
		(min_thickness 0.25)
		(fill yes
			(thermal_gap 0.5)
			(thermal_bridge_width 0.5)
			(island_removal_mode 0)
		)
		(polygon
			(pts
				(xy 216.732612 -72.370696) (xy 216.732612 -74.910696) (xy 216.986612 -75.164696) (xy 218.942412 -75.164696)
				(xy 220.085412 -74.021696) (xy 224.530412 -74.021696) (xy 224.657412 -73.894696) (xy 224.657412 -73.132696)
				(xy 224.530412 -73.005696) (xy 221.101412 -73.005696) (xy 220.212412 -72.116696) (xy 218.2114 -72.116696)
				(xy 216.986612 -72.116696)
			)
		)
	)
	(zone
		(layer "F.Cu")
		(hatch none 0.5)
		(connect_pads
			(clearance 0)
		)
		(min_thickness 0.25)
		(keepout
			(tracks not_allowed)
			(vias allowed)
			(pads allowed)
			(copperpour not_allowed)
			(footprints allowed)
		)
		(placement
			(enabled no)
			(sheetname "")
		)
		(fill
			(thermal_gap 0.5)
			(thermal_bridge_width 0.5)
			(island_removal_mode 0)
		)
		(polygon
			(pts
				(arc
					(start 37.223192 -163.920678)
					(mid 36.636579 -163.333684)
					(end 36.049712 -163.920424)
				)
				(arc
					(start 36.049712 -164.879274)
					(mid 36.636452 -165.466014)
					(end 37.223192 -164.879274)
				)
				(xy 37.223192 -164.6174)
				(arc
					(start 36.961826 -164.6174)
					(mid 36.890701 -164.627234)
					(end 36.82492 -164.656008)
				)
				(arc
					(start 36.82492 -164.656008)
					(mid 36.508163 -165.141474)
					(end 36.69792 -164.593778)
				)
				(arc
					(start 36.69792 -164.593778)
					(mid 36.807552 -164.522407)
					(end 36.934648 -164.491416)
				)
				(xy 36.93541 -164.4904) (xy 37.223192 -164.4904) (xy 37.223192 -164.2872) (xy 36.913312 -164.2872)
				(arc
					(start 36.912296 -164.286184)
					(mid 36.803313 -164.2609)
					(end 36.707064 -164.203888)
				)
				(arc
					(start 36.707064 -164.203888)
					(mid 36.498056 -163.663161)
					(end 36.834064 -164.135562)
				)
				(arc
					(start 36.834064 -164.135562)
					(mid 36.885483 -164.153947)
					(end 36.939728 -164.1602)
				)
				(xy 37.223192 -164.1602)
			)
		)
	)
	(zone
		(net "12V_PRE_13")
		(layer "F.Cu")
		(hatch none 0.5)
		(connect_pads
			(clearance 0.5)
		)
		(min_thickness 0.25)
		(fill yes
			(thermal_gap 0.5)
			(thermal_bridge_width 0.5)
			(island_removal_mode 0)
		)
		(polygon
			(pts
				(xy 33.6042 -119.126) (xy 33.273746 -119.456454) (xy 33.273746 -121.9327) (xy 33.781746 -122.4407)
				(xy 36.194746 -122.4407) (xy 36.448746 -122.1867) (xy 36.448746 -119.252746) (xy 36.322 -119.126)
			)
		)
		(polygon
			(pts
				(xy 35.305746 -121.8057) (xy 35.051746 -121.8057) (xy 35.051746 -122.0597) (xy 35.305746 -122.0597)
			)
		)
	)
	(zone
		(net "P5V_HDD3")
		(layer "F.Cu")
		(hatch none 0.5)
		(connect_pads
			(clearance 0.5)
		)
		(min_thickness 0.25)
		(fill yes
			(thermal_gap 0.5)
			(thermal_bridge_width 0.5)
			(island_removal_mode 0)
		)
		(polygon
			(pts
				(xy 207.137 -173.9138) (xy 206.6036 -174.4472) (xy 206.6036 -175.8442) (xy 207.263746 -176.504346)
				(xy 207.263746 -179.5907) (xy 207.771746 -180.0987) (xy 212.8139 -180.0987) (xy 214.282528 -180.0987)
				(xy 214.3252 -180.056028) (xy 220.267784 -180.056028) (xy 220.775784 -179.548028) (xy 224.204784 -179.548028)
				(xy 224.458784 -179.294028) (xy 224.458784 -177.516028) (xy 224.204784 -177.262028) (xy 215.949784 -177.262028)
				(xy 215.568784 -176.881028) (xy 215.568784 -174.214028) (xy 215.314784 -173.960028) (xy 215.268556 -173.9138)
				(xy 210.0326 -173.9138)
			)
		)
		(polygon
			(pts
				(xy 217.905584 -178.913028) (xy 217.651584 -178.913028) (xy 217.651584 -179.167028) (xy 217.905584 -179.167028)
			)
		)
		(polygon
			(pts
				(xy 217.041984 -178.913028) (xy 216.787984 -178.913028) (xy 216.787984 -179.167028) (xy 217.041984 -179.167028)
			)
		)
		(polygon
			(pts
				(xy 213.092284 -176.830228) (xy 212.838284 -176.830228) (xy 212.838284 -177.084228) (xy 213.092284 -177.084228)
			)
		)
		(polygon
			(pts
				(xy 211.949284 -176.830228) (xy 211.695284 -176.830228) (xy 211.695284 -177.084228) (xy 211.949284 -177.084228)
			)
		)
	)
	(zone
		(layers "F.Cu" "B.Cu")
		(hatch none 0.5)
		(connect_pads
			(clearance 0)
		)
		(min_thickness 0.25)
		(keepout
			(tracks not_allowed)
			(vias allowed)
			(pads allowed)
			(copperpour not_allowed)
			(footprints allowed)
		)
		(placement
			(enabled no)
			(sheetname "")
		)
		(fill yes
			(thermal_gap 0.5)
			(thermal_bridge_width 0.5)
			(island_removal_mode 0)
		)
		(polygon
			(pts
				(xy 8.228584 -357.926386)
				(arc
					(start 8.064246 -357.930196)
					(mid 8.081461 -358.089989)
					(end 8.13181 -358.242616)
				)
				(arc
					(start 8.13181 -358.242616)
					(mid 8.410291 -358.751968)
					(end 8.026146 -358.316784)
				)
				(arc
					(start 8.026146 -358.316784)
					(mid 7.960729 -358.132349)
					(end 7.937246 -357.93807)
				)
				(xy 7.937246 -357.933244)
				(arc
					(start 7.73303 -357.93807)
					(mid 7.69412 -358.157437)
					(end 7.600188 -358.359456)
				)
				(arc
					(start 7.600188 -358.359456)
					(mid 7.17541 -358.755277)
					(end 7.502652 -358.275636)
				)
				(arc
					(start 7.502652 -358.275636)
					(mid 7.574479 -358.114622)
					(end 7.605776 -357.941118)
				)
				(xy 7.351776 -357.947214)
				(arc
					(start 7.351776 -357.949754)
					(mid 6.7818 -358.54767)
					(end 7.379716 -359.117646)
				)
				(xy 7.379716 -359.120186) (xy 8.25627 -359.099358) (xy 8.256524 -359.099104)
				(arc
					(start 8.256524 -359.096818)
					(mid 8.8265 -358.498902)
					(end 8.228584 -357.928926)
				)
			)
		)
	)
	(zone
		(layers "F.Cu" "B.Cu" "In1.Cu" "In2.Cu" "In3.Cu" "In4.Cu" "In5.Cu" "In6.Cu")
		(name "Route Keepin")
		(hatch none 0.5)
		(connect_pads
			(clearance 0)
		)
		(min_thickness 0.25)
		(keepout
			(tracks allowed)
			(vias allowed)
			(pads allowed)
			(copperpour allowed)
			(footprints allowed)
		)
		(placement
			(enabled no)
			(sheetname "")
		)
		(fill
			(thermal_gap 0.5)
			(thermal_bridge_width 0.5)
			(island_removal_mode 0)
		)
		(polygon
			(pts
				(arc
					(start 258.137914 -364.16996)
					(mid 258.727106 -362.747398)
					(end 260.149594 -362.158026)
				)
				(xy 261.18439 -362.158026) (xy 261.73811 -361.604306)
				(arc
					(start 261.73811 -0.999998)
					(mid 261.668402 -0.831708)
					(end 261.500112 -0.762)
				)
				(arc
					(start 0.999998 -0.762)
					(mid 0.831708 -0.831708)
					(end 0.762 -0.999998)
				)
				(xy 0.762 -53.434234) (xy 0.815848 -53.488082)
				(arc
					(start 5.050028 -53.488082)
					(mid 6.761988 -55.200042)
					(end 5.050028 -56.912002)
				)
				(xy 0.815594 -56.912002) (xy 0.762 -56.965596) (xy 0.762 -104.234234) (xy 0.815848 -104.288082)
				(arc
					(start 5.050028 -104.288082)
					(mid 6.761988 -106.000042)
					(end 5.050028 -107.712002)
				)
				(xy 0.815594 -107.712002) (xy 0.762 -107.765596) (xy 0.762 -208.23428) (xy 0.815594 -208.287874)
				(arc
					(start 5.050028 -208.287874)
					(mid 6.762242 -210.000088)
					(end 5.050028 -211.712048)
				)
				(xy 0.815594 -211.712048) (xy 0.762 -211.765642) (xy 0.762 -303.434242) (xy 0.815848 -303.48809)
				(arc
					(start 5.050028 -303.48809)
					(mid 6.761988 -305.20005)
					(end 5.050028 -306.91201)
				)
				(xy 0.815594 -306.91201) (xy 0.762 -306.965604) (xy 0.762 -354.234242) (xy 0.815848 -354.28809)
				(arc
					(start 5.050028 -354.28809)
					(mid 6.761988 -356.00005)
					(end 5.050028 -357.71201)
				)
				(xy 0.815594 -357.71201) (xy 0.762 -357.765604) (xy 0.762 -458.234288) (xy 0.815594 -458.287882)
				(arc
					(start 5.050028 -458.287882)
					(mid 6.762242 -460.000096)
					(end 5.050028 -461.712056)
				)
				(xy 0.815594 -461.712056) (xy 0.762 -461.76565)
				(arc
					(start 0.762 -505.000006)
					(mid 0.831708 -505.168296)
					(end 0.999998 -505.238004)
				)
				(arc
					(start 261.500112 -505.238004)
					(mid 261.668402 -505.168296)
					(end 261.73811 -505.000006)
				)
				(xy 261.73811 -428.395638) (xy 261.18439 -427.841918)
				(arc
					(start 260.149594 -427.841918)
					(mid 258.727106 -427.252546)
					(end 258.137914 -425.829984)
				)
				(xy 258.137914 -411.800802) (xy 257.584194 -411.247082)
				(arc
					(start 251.394976 -411.247082)
					(mid 250.098052 -409.950158)
					(end 251.394976 -408.65298)
				)
				(xy 257.584194 -408.65298) (xy 258.137914 -408.09926)
			)
		)
	)
	(zone
		(layers "F.Cu" "B.Cu" "In1.Cu" "In2.Cu" "In3.Cu" "In4.Cu" "In5.Cu" "In6.Cu")
		(name "Package Keepin")
		(hatch none 0.5)
		(connect_pads
			(clearance 0)
		)
		(min_thickness 0.25)
		(keepout
			(tracks allowed)
			(vias allowed)
			(pads allowed)
			(copperpour allowed)
			(footprints allowed)
		)
		(placement
			(enabled no)
			(sheetname "")
		)
		(fill
			(thermal_gap 0.5)
			(thermal_bridge_width 0.5)
			(island_removal_mode 0)
		)
		(polygon
			(pts
				(arc
					(start 254.835914 -364.16996)
					(mid 255.828699 -361.077136)
					(end 258.43611 -359.139998)
				)
				(xy 258.43611 -4.064) (xy 4.064 -4.064) (xy 4.064 -50.186082)
				(arc
					(start 5.050028 -50.186082)
					(mid 10.063988 -55.200042)
					(end 5.050028 -60.214002)
				)
				(xy 4.064 -60.214002) (xy 4.064 -100.986082)
				(arc
					(start 5.050028 -100.986082)
					(mid 10.063988 -106.000042)
					(end 5.050028 -111.014002)
				)
				(xy 4.064 -111.014002) (xy 4.064 -204.985874)
				(arc
					(start 5.050028 -204.985874)
					(mid 10.064242 -210.000088)
					(end 5.050028 -215.014048)
				)
				(xy 4.064 -215.014048) (xy 4.064 -300.18609)
				(arc
					(start 5.050028 -300.18609)
					(mid 10.063988 -305.20005)
					(end 5.050028 -310.21401)
				)
				(xy 4.064 -310.21401) (xy 4.064 -350.98609)
				(arc
					(start 5.050028 -350.98609)
					(mid 10.063988 -356.00005)
					(end 5.050028 -361.01401)
				)
				(xy 4.064 -361.01401) (xy 4.064 -454.985882)
				(arc
					(start 5.050028 -454.985882)
					(mid 10.064242 -460.000096)
					(end 5.050028 -465.014056)
				)
				(xy 4.064 -465.014056) (xy 4.064 -501.936004) (xy 258.43611 -501.936004)
				(arc
					(start 258.43611 -430.859946)
					(mid 255.828735 -428.922782)
					(end 254.835914 -425.829984)
				)
				(xy 254.835914 -414.549082)
				(arc
					(start 251.394976 -414.549082)
					(mid 246.796052 -409.950158)
					(end 251.394976 -405.35098)
				)
				(xy 254.835914 -405.35098)
			)
		)
	)
	(zone
		(layers "F.Cu" "In5.Cu")
		(hatch none 0.5)
		(connect_pads
			(clearance 0)
		)
		(min_thickness 0.25)
		(keepout
			(tracks not_allowed)
			(vias allowed)
			(pads allowed)
			(copperpour not_allowed)
			(footprints allowed)
		)
		(placement
			(enabled no)
			(sheetname "")
		)
		(fill yes
			(thermal_gap 0.5)
			(thermal_bridge_width 0.5)
			(island_removal_mode 0)
		)
		(polygon
			(pts
				(arc
					(start 7.314184 -117.510814)
					(mid 6.725539 -116.926106)
					(end 6.140704 -117.514624)
				)
				(arc
					(start 6.144006 -118.429532)
					(mid 6.730492 -119.014243)
					(end 7.317486 -118.43004)
				)
				(arc
					(start 7.022846 -118.43004)
					(mid 6.730746 -118.719611)
					(end 6.438646 -118.43004)
				)
				(arc
					(start 6.438646 -118.4275)
					(mid 6.730746 -118.1354)
					(end 7.022846 -118.4275)
				)
				(xy 7.317486 -118.4275) (xy 7.317486 -118.425468) (xy 7.314184 -117.515132)
				(arc
					(start 7.019544 -117.515132)
					(mid 6.727444 -117.804703)
					(end 6.435344 -117.515132)
				)
				(arc
					(start 6.435344 -117.512592)
					(mid 6.727444 -117.220492)
					(end 7.019544 -117.512592)
				)
				(xy 7.314184 -117.512592)
			)
		)
	)
	(zone
		(layers "F.Cu" "In5.Cu")
		(hatch none 0.5)
		(connect_pads
			(clearance 0)
		)
		(min_thickness 0.25)
		(keepout
			(tracks not_allowed)
			(vias allowed)
			(pads allowed)
			(copperpour not_allowed)
			(footprints allowed)
		)
		(placement
			(enabled no)
			(sheetname "")
		)
		(fill yes
			(thermal_gap 0.5)
			(thermal_bridge_width 0.5)
			(island_removal_mode 0)
		)
		(polygon
			(pts
				(arc
					(start 7.342886 -133.514592)
					(mid 6.756146 -132.927852)
					(end 6.169406 -133.514592)
				)
				(arc
					(start 6.169406 -134.442708)
					(mid 6.754876 -135.029447)
					(end 7.342886 -134.445248)
				)
				(arc
					(start 7.048246 -134.445248)
					(mid 6.756146 -134.734819)
					(end 6.464046 -134.445248)
				)
				(arc
					(start 6.464046 -134.442708)
					(mid 6.756146 -134.150608)
					(end 7.048246 -134.442708)
				)
				(xy 7.342886 -134.442708) (xy 7.342886 -133.517132)
				(arc
					(start 7.048246 -133.517132)
					(mid 6.756146 -133.806703)
					(end 6.464046 -133.517132)
				)
				(arc
					(start 6.464046 -133.514592)
					(mid 6.756146 -133.222492)
					(end 7.048246 -133.514592)
				)
			)
		)
	)
	(zone
		(layers "F.Cu" "In5.Cu")
		(hatch none 0.5)
		(connect_pads
			(clearance 0)
		)
		(min_thickness 0.25)
		(keepout
			(tracks not_allowed)
			(vias allowed)
			(pads allowed)
			(copperpour not_allowed)
			(footprints allowed)
		)
		(placement
			(enabled no)
			(sheetname "")
		)
		(fill yes
			(thermal_gap 0.5)
			(thermal_bridge_width 0.5)
			(island_removal_mode 0)
		)
		(polygon
			(pts
				(arc
					(start 7.265416 -121.477532)
					(mid 6.642862 -120.929146)
					(end 6.094476 -121.5517)
				)
				(xy 6.091936 -121.551954) (xy 6.1468 -122.41403)
				(arc
					(start 6.14934 -122.413776)
					(mid 6.752092 -122.963081)
					(end 7.32155 -122.379232)
				)
				(arc
					(start 7.02691 -122.379232)
					(mid 6.73481 -122.668803)
					(end 6.44271 -122.379232)
				)
				(arc
					(start 6.44271 -122.376692)
					(mid 6.73481 -122.084592)
					(end 7.02691 -122.376692)
				)
				(xy 7.32155 -122.376692) (xy 7.32028 -122.339608) (xy 7.32282 -122.339354) (xy 7.270496 -121.517156)
				(arc
					(start 6.972046 -121.517156)
					(mid 6.679946 -121.806727)
					(end 6.387846 -121.517156)
				)
				(arc
					(start 6.387846 -121.514616)
					(mid 6.679946 -121.222516)
					(end 6.972046 -121.514616)
				)
				(xy 7.270242 -121.514616) (xy 7.267956 -121.477532) (xy 7.267702 -121.477278)
			)
		)
	)
	(zone
		(net "P12V")
		(layer "B.Cu")
		(hatch none 0.5)
		(connect_pads
			(clearance 0.5)
		)
		(min_thickness 0.25)
		(fill yes
			(thermal_gap 0.5)
			(thermal_bridge_width 0.5)
			(island_removal_mode 0)
		)
		(polygon
			(pts
				(xy 6.743446 -175.7807) (xy 5.841746 -175.7807) (xy 5.232146 -175.1711) (xy 1.396746 -175.1711)
				(xy 1.345946 -175.2219) (xy 1.345946 -180.5559) (xy 1.777746 -180.9877) (xy 1.777746 -188.3537)
				(xy 2.793746 -189.3697) (xy 2.794 -189.3697) (xy 3.0353 -189.611) (xy 14.350746 -189.611) (xy 14.985746 -188.976)
				(xy 14.985746 -187.4647) (xy 14.985746 -184.023)
			)
		)
	)
	(zone
		(layer "B.Cu")
		(hatch none 0.5)
		(connect_pads
			(clearance 0)
		)
		(min_thickness 0.25)
		(keepout
			(tracks not_allowed)
			(vias allowed)
			(pads allowed)
			(copperpour not_allowed)
			(footprints allowed)
		)
		(placement
			(enabled no)
			(sheetname "")
		)
		(fill
			(thermal_gap 0.5)
			(thermal_bridge_width 0.5)
			(island_removal_mode 0)
		)
		(polygon
			(pts
				(arc
					(start 7.266686 -97.49917)
					(mid 6.680073 -96.912176)
					(end 6.093206 -97.498916)
				)
				(arc
					(start 6.093206 -98.457766)
					(mid 6.679946 -99.044506)
					(end 7.266686 -98.457766)
				)
				(xy 7.266686 -98.206814)
				(arc
					(start 7.238746 -98.206814)
					(mid 7.076554 -98.232512)
					(end 6.930136 -98.30689)
				)
				(arc
					(start 6.930136 -98.30689)
					(mid 6.469479 -98.66027)
					(end 6.84149 -98.214434)
				)
				(arc
					(start 6.84149 -98.214434)
					(mid 7.01631 -98.118813)
					(end 7.211822 -98.080322)
				)
				(xy 7.21233 -98.079814) (xy 7.266686 -98.079814) (xy 7.266686 -97.876614) (xy 7.18693 -97.876614)
				(arc
					(start 7.186422 -97.876106)
					(mid 7.002189 -97.837827)
					(end 6.839204 -97.743772)
				)
				(arc
					(start 6.839204 -97.743772)
					(mid 6.471401 -97.294299)
					(end 6.928612 -97.652332)
				)
				(arc
					(start 6.928612 -97.652332)
					(mid 7.062907 -97.724585)
					(end 7.213346 -97.749614)
				)
				(xy 7.266686 -97.749614)
			)
		)
	)
	(zone
		(layer "B.Cu")
		(hatch none 0.5)
		(connect_pads
			(clearance 0)
		)
		(min_thickness 0.25)
		(keepout
			(tracks allowed)
			(vias allowed)
			(pads allowed)
			(copperpour allowed)
			(footprints not_allowed)
		)
		(placement
			(enabled no)
			(sheetname "")
		)
		(fill
			(thermal_gap 0.5)
			(thermal_bridge_width 0.5)
			(island_removal_mode 0)
		)
		(polygon
			(pts
				(arc
					(start 261.500112 -506.000004)
					(mid 262.207217 -505.707111)
					(end 262.50011 -505.000006)
				)
				(xy 262.50011 -428.079916) (xy 261.500112 -427.079918)
				(arc
					(start 260.150102 -427.079918)
					(mid 259.266101 -426.713911)
					(end 258.899914 -425.829984)
				)
				(xy 258.899914 -411.48508) (xy 257.899916 -410.485082)
				(arc
					(start 251.394976 -410.485082)
					(mid 250.860052 -409.950158)
					(end 251.394976 -409.41498)
				)
				(xy 257.899916 -409.41498) (xy 258.899914 -408.414982)
				(arc
					(start 258.899914 -364.16996)
					(mid 259.266101 -363.286033)
					(end 260.150102 -362.920026)
				)
				(xy 261.500112 -362.920026) (xy 262.50011 -361.920028)
				(arc
					(start 262.50011 -0.999998)
					(mid 262.207217 -0.292893)
					(end 261.500112 0)
				)
				(arc
					(start 0.999998 0)
					(mid 0.292893 -0.292893)
					(end 0 -0.999998)
				)
				(xy 0 -53.749956) (xy 0.500126 -54.250082)
				(arc
					(start 5.050028 -54.250082)
					(mid 5.999988 -55.200042)
					(end 5.050028 -56.150002)
				)
				(xy 0.500126 -56.150002) (xy 0 -56.649874) (xy 0 -104.549956) (xy 0.500126 -105.050082)
				(arc
					(start 5.050028 -105.050082)
					(mid 5.999988 -106.000042)
					(end 5.050028 -106.950002)
				)
				(xy 0.500126 -106.950002) (xy 0 -107.449874) (xy 0 -208.550002) (xy 0.500126 -209.049874)
				(arc
					(start 5.050028 -209.049874)
					(mid 6.000242 -210.000088)
					(end 5.050028 -210.950048)
				)
				(xy 0.500126 -210.950048) (xy 0 -211.44992) (xy 0 -303.749964) (xy 0.500126 -304.25009)
				(arc
					(start 5.050028 -304.25009)
					(mid 5.999988 -305.20005)
					(end 5.050028 -306.15001)
				)
				(xy 0.500126 -306.15001) (xy 0 -306.649882) (xy 0 -354.549964) (xy 0.500126 -355.05009)
				(arc
					(start 5.050028 -355.05009)
					(mid 5.999988 -356.00005)
					(end 5.050028 -356.95001)
				)
				(xy 0.500126 -356.95001) (xy 0 -357.449882) (xy 0 -458.55001) (xy 0.500126 -459.049882)
				(arc
					(start 5.050028 -459.049882)
					(mid 6.000242 -460.000096)
					(end 5.050028 -460.950056)
				)
				(xy 0.500126 -460.950056) (xy 0 -461.449928)
				(arc
					(start 0 -505.000006)
					(mid 0.292893 -505.707111)
					(end 0.999998 -506.000004)
				)
			)
		)
	)
	(zone
		(net "P3V3")
		(layer "B.Cu")
		(hatch none 0.5)
		(connect_pads
			(clearance 0.5)
		)
		(min_thickness 0.25)
		(fill yes
			(thermal_gap 0.5)
			(thermal_bridge_width 0.5)
			(island_removal_mode 0)
		)
		(polygon
			(pts
				(xy 47.878746 -123.3297) (xy 47.751746 -123.4567) (xy 47.751746 -124.5997) (xy 40.385746 -131.9657)
				(xy 37.210746 -131.9657) (xy 36.448746 -132.7277) (xy 36.448746 -135.5217) (xy 36.702746 -135.7757)
				(xy 40.258746 -135.7757) (xy 50.164746 -125.8697) (xy 50.164746 -124.3457) (xy 49.148746 -123.3297)
			)
		)
	)
	(zone
		(layer "B.Cu")
		(hatch none 0.5)
		(connect_pads
			(clearance 0)
		)
		(min_thickness 0.25)
		(keepout
			(tracks not_allowed)
			(vias allowed)
			(pads allowed)
			(copperpour not_allowed)
			(footprints allowed)
		)
		(placement
			(enabled no)
			(sheetname "")
		)
		(fill
			(thermal_gap 0.5)
			(thermal_bridge_width 0.5)
			(island_removal_mode 0)
		)
		(polygon
			(pts
				(arc
					(start 22.528022 -238.079788)
					(mid 22.014434 -237.428024)
					(end 21.36267 -237.941612)
				)
				(arc
					(start 21.26107 -238.799624)
					(mid 21.774529 -239.451657)
					(end 22.426422 -238.938054)
				)
				(xy 22.442424 -238.803942) (xy 22.154134 -238.803942)
				(arc
					(start 22.128734 -238.804704)
					(mid 21.581205 -238.997487)
					(end 22.069806 -238.684054)
				)
				(arc
					(start 22.069806 -238.684054)
					(mid 22.098417 -238.680055)
					(end 22.12721 -238.677704)
				)
				(xy 22.127718 -238.676942) (xy 22.45741 -238.676942) (xy 22.481286 -238.473742) (xy 22.086316 -238.473742)
				(arc
					(start 22.085046 -238.472472)
					(mid 21.985156 -238.445298)
					(end 21.900388 -238.385858)
				)
				(arc
					(start 21.900388 -238.385858)
					(mid 21.860678 -238.336547)
					(end 21.832316 -238.27994)
				)
				(arc
					(start 21.832316 -238.27994)
					(mid 21.979313 -237.720679)
					(end 21.993098 -238.298736)
				)
				(arc
					(start 21.993098 -238.298736)
					(mid 22.048287 -238.334261)
					(end 22.112732 -238.346742)
				)
				(xy 22.496526 -238.346742)
			)
		)
	)
	(zone
		(layer "B.Cu")
		(hatch none 0.5)
		(connect_pads
			(clearance 0)
		)
		(min_thickness 0.25)
		(keepout
			(tracks allowed)
			(vias allowed)
			(pads allowed)
			(copperpour allowed)
			(footprints not_allowed)
		)
		(placement
			(enabled no)
			(sheetname "")
		)
		(fill
			(thermal_gap 0.5)
			(thermal_bridge_width 0.5)
			(island_removal_mode 0)
		)
		(polygon
			(pts
				(arc
					(start 252.499876 -267.5001)
					(mid 248.499884 -271.500092)
					(end 252.499876 -275.500084)
				)
				(arc
					(start 252.499876 -275.500084)
					(mid 256.499868 -271.500092)
					(end 252.499876 -267.5001)
				)
			)
		)
	)
	(zone
		(layer "B.Cu")
		(hatch none 0.5)
		(connect_pads
			(clearance 0.5)
		)
		(min_thickness 0.25)
		(fill
			(thermal_gap 0.5)
			(thermal_bridge_width 0.5)
			(island_removal_mode 0)
		)
		(polygon
			(pts
				(xy 212.597746 -20.2057) (xy 212.089746 -20.7137) (xy 212.089746 -32.0167) (xy 212.851746 -32.7787)
				(xy 226.567746 -32.7787) (xy 226.948746 -32.3977) (xy 226.948746 -22.8727) (xy 224.281746 -20.2057)
			)
		)
	)
	(zone
		(layer "B.Cu")
		(hatch none 0.5)
		(connect_pads
			(clearance 0)
		)
		(min_thickness 0.25)
		(keepout
			(tracks not_allowed)
			(vias allowed)
			(pads allowed)
			(copperpour not_allowed)
			(footprints allowed)
		)
		(placement
			(enabled no)
			(sheetname "")
		)
		(fill
			(thermal_gap 0.5)
			(thermal_bridge_width 0.5)
			(island_removal_mode 0)
		)
		(polygon
			(pts
				(arc
					(start 36.908232 -369.934744)
					(mid 36.337748 -369.332256)
					(end 35.73526 -369.90274)
				)
				(xy 35.73272 -369.90274) (xy 35.728402 -370.05641) (xy 35.727894 -370.078)
				(arc
					(start 35.9283 -370.078)
					(mid 35.996277 -370.071361)
					(end 36.06165 -370.051584)
				)
				(arc
					(start 36.06165 -370.051584)
					(mid 36.545285 -369.730786)
					(end 36.146232 -370.152168)
				)
				(arc
					(start 36.146232 -370.152168)
					(mid 36.053594 -370.188243)
					(end 35.955478 -370.204238)
				)
				(xy 35.954716 -370.205) (xy 35.724592 -370.205) (xy 35.719004 -370.4082) (xy 35.954716 -370.4082)
				(arc
					(start 35.955478 -370.408962)
					(mid 36.116718 -370.451373)
					(end 36.249864 -370.55171)
				)
				(arc
					(start 36.249864 -370.55171)
					(mid 36.410056 -371.109115)
					(end 36.122864 -370.605304)
				)
				(arc
					(start 36.122864 -370.605304)
					(mid 36.031704 -370.553262)
					(end 35.9283 -370.5352)
				)
				(xy 35.715448 -370.5352) (xy 35.707574 -370.823998)
				(arc
					(start 35.710114 -370.823998)
					(mid 36.280598 -371.426486)
					(end 36.883086 -370.856002)
				)
				(xy 36.885626 -370.856002) (xy 36.910772 -369.934998) (xy 36.910518 -369.934744)
			)
		)
	)
	(zone
		(layer "B.Cu")
		(hatch none 0.5)
		(connect_pads
			(clearance 0)
		)
		(min_thickness 0.25)
		(keepout
			(tracks not_allowed)
			(vias allowed)
			(pads allowed)
			(copperpour not_allowed)
			(footprints allowed)
		)
		(placement
			(enabled no)
			(sheetname "")
		)
		(fill
			(thermal_gap 0.5)
			(thermal_bridge_width 0.5)
			(island_removal_mode 0)
		)
		(polygon
			(pts
				(arc
					(start 222.743522 -267.70457)
					(mid 222.594564 -267.629549)
					(end 222.434658 -267.582142)
				)
				(arc
					(start 222.417894 -267.792708)
					(mid 222.956374 -268.424152)
					(end 223.587818 -267.885672)
				)
				(arc
					(start 223.656144 -267.024866)
					(mid 223.11779 -266.393432)
					(end 222.48622 -266.931648)
				)
				(arc
					(start 222.47098 -267.123926)
					(mid 222.606735 -267.152815)
					(end 222.73895 -267.195046)
				)
				(arc
					(start 222.73895 -267.195046)
					(mid 222.807596 -267.207714)
					(end 222.876364 -267.195808)
				)
				(arc
					(start 222.876364 -267.195808)
					(mid 223.202528 -266.717049)
					(end 223.011238 -267.26388)
				)
				(arc
					(start 223.011238 -267.26388)
					(mid 222.859332 -267.330637)
					(end 222.694246 -267.313918)
				)
				(arc
					(start 222.694246 -267.313918)
					(mid 222.579032 -267.276973)
					(end 222.46082 -267.25118)
				)
				(arc
					(start 222.444818 -267.454634)
					(mid 222.642846 -267.512003)
					(end 222.826072 -267.606526)
				)
				(arc
					(start 222.826072 -267.606526)
					(mid 223.226363 -268.027418)
					(end 222.743522 -267.70457)
				)
			)
		)
	)
	(zone
		(layer "B.Cu")
		(hatch none 0.5)
		(connect_pads
			(clearance 0)
		)
		(min_thickness 0.25)
		(keepout
			(tracks not_allowed)
			(vias allowed)
			(pads allowed)
			(copperpour not_allowed)
			(footprints allowed)
		)
		(placement
			(enabled no)
			(sheetname "")
		)
		(fill
			(thermal_gap 0.5)
			(thermal_bridge_width 0.5)
			(island_removal_mode 0)
		)
		(polygon
			(pts
				(arc
					(start 31.927546 -475.163896)
					(mid 31.307532 -474.612462)
					(end 30.756098 -475.232476)
				)
				(xy 30.753558 -475.23273) (xy 30.804104 -476.09506)
				(arc
					(start 30.806644 -476.094806)
					(mid 31.426658 -476.64624)
					(end 31.978092 -476.026226)
				)
				(xy 31.980632 -476.025972) (xy 31.975044 -475.9325)
				(arc
					(start 31.854648 -475.9325)
					(mid 31.759944 -475.940188)
					(end 31.667704 -475.96298)
				)
				(arc
					(start 31.667704 -475.96298)
					(mid 31.145723 -476.217006)
					(end 31.597854 -475.852998)
				)
				(arc
					(start 31.597854 -475.852998)
					(mid 31.710857 -475.820059)
					(end 31.827724 -475.806008)
				)
				(xy 31.828232 -475.8055) (xy 31.967678 -475.8055) (xy 31.95574 -475.6023) (xy 31.65602 -475.6023)
				(arc
					(start 31.655258 -475.601284)
					(mid 31.516007 -475.566327)
					(end 31.397702 -475.484952)
				)
				(arc
					(start 31.397702 -475.484952)
					(mid 31.218859 -474.933163)
					(end 31.524702 -475.426024)
				)
				(arc
					(start 31.524702 -475.426024)
					(mid 31.599811 -475.462692)
					(end 31.682436 -475.4753)
				)
				(xy 31.948374 -475.4753) (xy 31.930086 -475.163896) (xy 31.929832 -475.163642)
			)
		)
	)
	(zone
		(layer "B.Cu")
		(hatch none 0.5)
		(connect_pads
			(clearance 0)
		)
		(min_thickness 0.25)
		(keepout
			(tracks not_allowed)
			(vias allowed)
			(pads allowed)
			(copperpour not_allowed)
			(footprints allowed)
		)
		(placement
			(enabled no)
			(sheetname "")
		)
		(fill
			(thermal_gap 0.5)
			(thermal_bridge_width 0.5)
			(island_removal_mode 0)
		)
		(polygon
			(pts
				(arc
					(start 22.65426 -341.08644)
					(mid 22.07006 -340.50224)
					(end 21.48586 -341.08644)
				)
				(arc
					(start 21.48586 -342.045036)
					(mid 22.069933 -342.62949)
					(end 22.65426 -342.04529)
				)
				(arc
					(start 22.65426 -341.83701)
					(mid 22.491694 -341.867758)
					(end 22.337776 -341.92845)
				)
				(arc
					(start 22.337776 -341.92845)
					(mid 21.834551 -342.217662)
					(end 22.26183 -341.824818)
				)
				(arc
					(start 22.26183 -341.824818)
					(mid 22.452111 -341.746963)
					(end 22.65426 -341.709502)
				)
				(arc
					(start 22.65426 -341.474298)
					(mid 22.447465 -341.410751)
					(end 22.254464 -341.313008)
				)
				(arc
					(start 22.254464 -341.313008)
					(mid 21.840081 -340.906297)
					(end 22.333458 -341.212424)
				)
				(arc
					(start 22.333458 -341.212424)
					(mid 22.488831 -341.290472)
					(end 22.65426 -341.343996)
				)
			)
		)
	)
	(zone
		(layer "B.Cu")
		(hatch none 0.5)
		(connect_pads
			(clearance 0)
		)
		(min_thickness 0.25)
		(keepout
			(tracks not_allowed)
			(vias allowed)
			(pads allowed)
			(copperpour not_allowed)
			(footprints allowed)
		)
		(placement
			(enabled no)
			(sheetname "")
		)
		(fill
			(thermal_gap 0.5)
			(thermal_bridge_width 0.5)
			(island_removal_mode 0)
		)
		(polygon
			(pts
				(arc
					(start 7.291578 -107.502198)
					(mid 6.683756 -106.937556)
					(end 6.119114 -107.545378)
				)
				(xy 6.116574 -107.545378) (xy 6.148324 -108.408216) (xy 6.148578 -108.40847)
				(arc
					(start 6.150864 -108.40847)
					(mid 6.758686 -108.973112)
					(end 7.323328 -108.36529)
				)
				(xy 7.325868 -108.36529) (xy 7.321042 -108.231686)
				(arc
					(start 7.238746 -108.231686)
					(mid 7.121018 -108.243073)
					(end 7.007606 -108.276644)
				)
				(arc
					(start 7.007606 -108.276644)
					(mid 6.497905 -108.554556)
					(end 6.93293 -108.170218)
				)
				(arc
					(start 6.93293 -108.170218)
					(mid 7.069352 -108.124174)
					(end 7.212076 -108.105194)
				)
				(xy 7.21233 -108.104686) (xy 7.316216 -108.104686) (xy 7.30885 -107.901486) (xy 6.85673 -107.901486)
				(arc
					(start 6.855206 -107.899962)
					(mid 6.768943 -107.872861)
					(end 6.698742 -107.815888)
				)
				(arc
					(start 6.698742 -107.815888)
					(mid 6.62798 -107.241979)
					(end 6.85927 -107.771946)
				)
				(arc
					(start 6.85927 -107.771946)
					(mid 6.871142 -107.773836)
					(end 6.883146 -107.774486)
				)
				(xy 7.304024 -107.774486) (xy 7.294118 -107.502198)
			)
		)
	)
	(zone
		(layer "B.Cu")
		(hatch none 0.5)
		(connect_pads
			(clearance 0)
		)
		(min_thickness 0.25)
		(keepout
			(tracks not_allowed)
			(vias allowed)
			(pads allowed)
			(copperpour not_allowed)
			(footprints allowed)
		)
		(placement
			(enabled no)
			(sheetname "")
		)
		(fill
			(thermal_gap 0.5)
			(thermal_bridge_width 0.5)
			(island_removal_mode 0)
		)
		(polygon
			(pts
				(arc
					(start 223.618552 -60.986416)
					(mid 223.031939 -60.399422)
					(end 222.445072 -60.986162)
				)
				(xy 222.445072 -61.1632)
				(arc
					(start 222.554546 -61.1632)
					(mid 222.599169 -61.161214)
					(end 222.643446 -61.155326)
				)
				(arc
					(start 222.654622 -61.15431)
					(mid 222.716791 -61.147458)
					(end 222.776034 -61.127386)
				)
				(arc
					(start 222.776034 -61.127386)
					(mid 223.249437 -60.791211)
					(end 222.86341 -61.224922)
				)
				(arc
					(start 222.86341 -61.224922)
					(mid 222.76545 -61.266223)
					(end 222.66021 -61.28131)
				)
				(arc
					(start 222.66021 -61.28131)
					(mid 222.620971 -61.286727)
					(end 222.58147 -61.289692)
				)
				(xy 222.580962 -61.2902) (xy 222.445072 -61.2902) (xy 222.445072 -61.4934) (xy 222.530162 -61.4934)
				(arc
					(start 222.530924 -61.494416)
					(mid 222.657186 -61.52408)
					(end 222.767398 -61.59246)
				)
				(xy 222.768668 -61.59246) (xy 222.786956 -61.610494) (xy 222.787464 -61.611002)
				(arc
					(start 222.875094 -61.698632)
					(mid 223.237888 -62.151996)
					(end 222.785178 -61.788294)
				)
				(arc
					(start 222.69704 -61.70041)
					(mid 222.608314 -61.641285)
					(end 222.503746 -61.6204)
				)
				(xy 222.445072 -61.6204)
				(arc
					(start 222.445072 -61.945012)
					(mid 223.031812 -62.531752)
					(end 223.618552 -61.945012)
				)
			)
		)
	)
	(zone
		(layer "B.Cu")
		(hatch none 0.5)
		(connect_pads
			(clearance 0)
		)
		(min_thickness 0.25)
		(keepout
			(tracks not_allowed)
			(vias allowed)
			(pads allowed)
			(copperpour not_allowed)
			(footprints allowed)
		)
		(placement
			(enabled no)
			(sheetname "")
		)
		(fill
			(thermal_gap 0.5)
			(thermal_bridge_width 0.5)
			(island_removal_mode 0)
		)
		(polygon
			(pts
				(arc
					(start 216.490804 -373.038624)
					(mid 217.067892 -372.442232)
					(end 216.4715 -371.865144)
				)
				(arc
					(start 215.608154 -371.879368)
					(mid 215.177105 -372.078347)
					(end 215.034368 -372.531132)
				)
				(arc
					(start 215.034368 -372.531132)
					(mid 215.065279 -372.548195)
					(end 215.097614 -372.562374)
				)
				(arc
					(start 215.097614 -372.562374)
					(mid 215.220965 -372.588442)
					(end 215.34628 -372.574566)
				)
				(arc
					(start 215.34628 -372.574566)
					(mid 215.857022 -372.298759)
					(end 215.42248 -372.683532)
				)
				(arc
					(start 215.42248 -372.683532)
					(mid 215.249091 -372.716032)
					(end 215.074754 -372.68912)
				)
				(arc
					(start 215.074754 -372.68912)
					(mid 215.156464 -372.829099)
					(end 215.273382 -372.941342)
				)
				(arc
					(start 215.273382 -372.941342)
					(mid 215.791508 -372.883449)
					(end 216.234518 -372.608602)
				)
				(arc
					(start 216.234518 -372.608602)
					(mid 216.687778 -372.245258)
					(end 216.324434 -372.698518)
				)
				(xy 216.31275 -372.710202)
				(arc
					(start 216.312242 -372.710202)
					(mid 216.005642 -372.929552)
					(end 215.649302 -373.052594)
				)
			)
		)
	)
	(zone
		(layer "B.Cu")
		(hatch none 0.5)
		(connect_pads
			(clearance 0)
		)
		(min_thickness 0.25)
		(keepout
			(tracks allowed)
			(vias allowed)
			(pads allowed)
			(copperpour allowed)
			(footprints not_allowed)
		)
		(placement
			(enabled no)
			(sheetname "")
		)
		(fill
			(thermal_gap 0.5)
			(thermal_bridge_width 0.5)
			(island_removal_mode 0)
		)
		(polygon
			(pts
				(arc
					(start 252.499876 -166.99992)
					(mid 248.499884 -170.999912)
					(end 252.499876 -174.999904)
				)
				(arc
					(start 252.499876 -174.999904)
					(mid 256.499868 -170.999912)
					(end 252.499876 -166.99992)
				)
			)
		)
	)
	(zone
		(layer "B.Cu")
		(hatch none 0.5)
		(connect_pads
			(clearance 0)
		)
		(min_thickness 0.25)
		(keepout
			(tracks not_allowed)
			(vias allowed)
			(pads allowed)
			(copperpour not_allowed)
			(footprints allowed)
		)
		(placement
			(enabled no)
			(sheetname "")
		)
		(fill
			(thermal_gap 0.5)
			(thermal_bridge_width 0.5)
			(island_removal_mode 0)
		)
		(polygon
			(pts
				(arc
					(start 7.993126 -413.28213)
					(mid 7.963095 -413.199693)
					(end 7.944358 -413.113982)
				)
				(xy 7.734046 -413.238188) (xy 7.734046 -413.629856)
				(arc
					(start 7.733538 -413.630364)
					(mid 7.722263 -413.728372)
					(end 7.696708 -413.823658)
				)
				(arc
					(start 7.696708 -413.823658)
					(mid 7.340171 -414.282101)
					(end 7.585202 -413.755586)
				)
				(arc
					(start 7.585202 -413.755586)
					(mid 7.601544 -413.68029)
					(end 7.607046 -413.60344)
				)
				(xy 7.607046 -413.313372)
				(arc
					(start 7.215886 -413.544512)
					(mid 7.007016 -414.313851)
					(end 7.778242 -414.516062)
				)
				(arc
					(start 8.581898 -414.041336)
					(mid 8.794562 -413.299162)
					(end 8.065008 -413.046418)
				)
				(arc
					(start 8.065008 -413.046418)
					(mid 8.078927 -413.14062)
					(end 8.109458 -413.230822)
				)
				(arc
					(start 8.109458 -413.230822)
					(mid 8.128166 -413.268838)
					(end 8.149844 -413.305244)
				)
				(arc
					(start 8.149844 -413.305244)
					(mid 8.49496 -413.772278)
					(end 8.05561 -413.39262)
				)
				(arc
					(start 8.05561 -413.39262)
					(mid 8.021685 -413.338892)
					(end 7.993126 -413.28213)
				)
			)
		)
	)
	(zone
		(layer "B.Cu")
		(hatch none 0.5)
		(connect_pads
			(clearance 0)
		)
		(min_thickness 0.25)
		(keepout
			(tracks allowed)
			(vias allowed)
			(pads allowed)
			(copperpour allowed)
			(footprints not_allowed)
		)
		(placement
			(enabled no)
			(sheetname "")
		)
		(fill
			(thermal_gap 0.5)
			(thermal_bridge_width 0.5)
			(island_removal_mode 0)
		)
		(polygon
			(pts
				(arc
					(start 7.500112 -265.500104)
					(mid 11.500104 -261.500112)
					(end 7.500112 -257.50012)
				)
				(arc
					(start 7.500112 -257.50012)
					(mid 3.50012 -261.500112)
					(end 7.500112 -265.500104)
				)
			)
		)
	)
	(zone
		(net "P12V")
		(layer "B.Cu")
		(hatch none 0.5)
		(connect_pads
			(clearance 0.5)
		)
		(min_thickness 0.25)
		(fill yes
			(thermal_gap 0.5)
			(thermal_bridge_width 0.5)
			(island_removal_mode 0)
		)
		(polygon
			(pts
				(xy 1.3462 -51.181) (xy 7.7724 -51.181) (xy 8.89 -51.181) (xy 9.271 -51.181) (xy 12.8905 -47.5615)
				(xy 12.8905 -28.8925) (xy 12.065 -28.067) (xy 10.541 -28.067) (xy 8.001 -28.067) (xy 6.985 -29.083)
				(xy 6.985 -43.053) (xy 5.715 -44.323) (xy 1.397 -44.323) (xy 1.2954 -44.4246) (xy 1.2954 -51.1302)
			)
		)
	)
	(zone
		(layer "B.Cu")
		(hatch none 0.5)
		(connect_pads
			(clearance 0)
		)
		(min_thickness 0.25)
		(keepout
			(tracks not_allowed)
			(vias allowed)
			(pads allowed)
			(copperpour not_allowed)
			(footprints allowed)
		)
		(placement
			(enabled no)
			(sheetname "")
		)
		(fill
			(thermal_gap 0.5)
			(thermal_bridge_width 0.5)
			(island_removal_mode 0)
		)
		(polygon
			(pts
				(arc
					(start 7.909814 -421.731694)
					(mid 7.840504 -421.548072)
					(end 7.811262 -421.353996)
				)
				(arc
					(start 7.600188 -421.348662)
					(mid 7.559915 -421.536111)
					(end 7.485126 -421.712644)
				)
				(arc
					(start 7.485126 -421.712644)
					(mid 7.091125 -422.139016)
					(end 7.381748 -421.636444)
				)
				(arc
					(start 7.381748 -421.636444)
					(mid 7.439654 -421.494817)
					(end 7.472426 -421.34536)
				)
				(xy 7.374382 -421.34282) (xy 7.278878 -421.34028)
				(arc
					(start 7.278878 -421.34282)
					(mid 6.703314 -421.889428)
					(end 7.249922 -422.464992)
				)
				(xy 7.249922 -422.467532) (xy 8.113014 -422.489884) (xy 8.113268 -422.48963)
				(arc
					(start 8.113268 -422.487344)
					(mid 8.688832 -421.940736)
					(end 8.142224 -421.365172)
				)
				(xy 8.142224 -421.362632)
				(arc
					(start 7.938516 -421.357298)
					(mid 7.961957 -421.510838)
					(end 8.014462 -421.657018)
				)
				(arc
					(start 8.014462 -421.657018)
					(mid 8.297498 -422.163971)
					(end 7.909814 -421.731694)
				)
			)
		)
	)
	(zone
		(layer "B.Cu")
		(hatch none 0.5)
		(connect_pads
			(clearance 0)
		)
		(min_thickness 0.25)
		(keepout
			(tracks not_allowed)
			(vias allowed)
			(pads allowed)
			(copperpour not_allowed)
			(footprints allowed)
		)
		(placement
			(enabled no)
			(sheetname "")
		)
		(fill
			(thermal_gap 0.5)
			(thermal_bridge_width 0.5)
			(island_removal_mode 0)
		)
		(polygon
			(pts
				(arc
					(start 25.282144 -348.859348)
					(mid 24.727789 -348.241881)
					(end 24.110188 -348.796102)
				)
				(arc
					(start 24.052022 -349.878904)
					(mid 24.606504 -350.496378)
					(end 25.223978 -349.941896)
				)
				(xy 25.25141 -349.432372)
				(arc
					(start 24.896826 -349.432372)
					(mid 24.877288 -349.436258)
					(end 24.860758 -349.447358)
				)
				(arc
					(start 24.860758 -349.447358)
					(mid 24.789566 -349.535179)
					(end 24.738076 -349.635826)
				)
				(arc
					(start 24.738076 -349.635826)
					(mid 24.60268 -350.200264)
					(end 24.60879 -349.619824)
				)
				(arc
					(start 24.60879 -349.619824)
					(mid 24.674544 -349.479203)
					(end 24.770842 -349.357442)
				)
				(arc
					(start 24.770842 -349.357442)
					(mid 24.81556 -349.324871)
					(end 24.868124 -349.307658)
				)
				(xy 24.87041 -349.305372) (xy 25.258268 -349.305372) (xy 25.26919 -349.102172) (xy 25.179274 -349.102172)
				(arc
					(start 25.17902 -349.101664)
					(mid 25.035413 -349.083452)
					(end 24.897588 -349.03918)
				)
				(arc
					(start 24.897588 -349.03918)
					(mid 24.452877 -348.666481)
					(end 24.969216 -348.93123)
				)
				(arc
					(start 24.969216 -348.93123)
					(mid 25.085426 -348.964106)
					(end 25.20569 -348.975172)
				)
				(xy 25.275794 -348.975172)
			)
		)
	)
	(zone
		(layer "B.Cu")
		(hatch none 0.5)
		(connect_pads
			(clearance 0)
		)
		(min_thickness 0.25)
		(keepout
			(tracks not_allowed)
			(vias allowed)
			(pads allowed)
			(copperpour not_allowed)
			(footprints allowed)
		)
		(placement
			(enabled no)
			(sheetname "")
		)
		(fill
			(thermal_gap 0.5)
			(thermal_bridge_width 0.5)
			(island_removal_mode 0)
		)
		(polygon
			(pts
				(xy 8.140446 -370.911628) (xy 7.937246 -370.90223) (xy 7.937246 -371.125242)
				(arc
					(start 7.936484 -371.12575)
					(mid 7.934407 -371.155029)
					(end 7.930896 -371.18417)
				)
				(arc
					(start 7.930896 -371.18417)
					(mid 7.923772 -371.224722)
					(end 7.913878 -371.264688)
				)
				(arc
					(start 7.913878 -371.264688)
					(mid 7.571697 -371.733539)
					(end 7.799324 -371.199664)
				)
				(xy 7.80542 -371.166136)
				(arc
					(start 7.80542 -371.165882)
					(mid 7.809023 -371.13244)
					(end 7.810246 -371.098826)
				)
				(xy 7.810246 -370.896388)
				(arc
					(start 7.74319 -370.89334)
					(mid 7.13004 -371.452521)
					(end 7.689088 -372.065804)
				)
				(arc
					(start 8.587486 -372.107206)
					(mid 9.200642 -371.547898)
					(end 8.641334 -370.934742)
				)
				(xy 8.267446 -370.91747)
				(arc
					(start 8.267446 -371.238018)
					(mid 8.275818 -371.280106)
					(end 8.299704 -371.315742)
				)
				(arc
					(start 8.319008 -371.335046)
					(mid 8.340065 -371.354848)
					(end 8.362442 -371.373146)
				)
				(arc
					(start 8.362442 -371.373146)
					(mid 8.89341 -371.607577)
					(end 8.323072 -371.500146)
				)
				(arc
					(start 8.323072 -371.500146)
					(mid 8.284646 -371.473421)
					(end 8.24865 -371.443504)
				)
				(xy 8.247634 -371.443504) (xy 8.191246 -371.387116)
				(arc
					(start 8.191246 -371.384576)
					(mid 8.158565 -371.328646)
					(end 8.142224 -371.265958)
				)
				(xy 8.140446 -371.264434)
			)
		)
	)
	(zone
		(layer "B.Cu")
		(hatch none 0.5)
		(connect_pads
			(clearance 0)
		)
		(min_thickness 0.25)
		(keepout
			(tracks not_allowed)
			(vias allowed)
			(pads allowed)
			(copperpour not_allowed)
			(footprints allowed)
		)
		(placement
			(enabled no)
			(sheetname "")
		)
		(fill
			(thermal_gap 0.5)
			(thermal_bridge_width 0.5)
			(island_removal_mode 0)
		)
		(polygon
			(pts
				(arc
					(start 7.265416 -121.477532)
					(mid 6.642862 -120.929146)
					(end 6.094476 -121.5517)
				)
				(xy 6.091936 -121.551954)
				(arc
					(start 6.105398 -121.762266)
					(mid 6.270075 -121.725072)
					(end 6.422644 -121.652792)
				)
				(arc
					(start 6.422644 -121.652792)
					(mid 6.900589 -121.32327)
					(end 6.506718 -121.74982)
				)
				(arc
					(start 6.506718 -121.74982)
					(mid 6.318237 -121.842797)
					(end 6.113272 -121.889266)
				)
				(arc
					(start 6.126226 -122.092212)
					(mid 6.323454 -122.05462)
					(end 6.510528 -121.981722)
				)
				(arc
					(start 6.510528 -121.981722)
					(mid 6.671726 -121.974359)
					(end 6.785356 -122.08891)
				)
				(arc
					(start 6.785356 -122.08891)
					(mid 6.757637 -122.667986)
					(end 6.640068 -122.10034)
				)
				(arc
					(start 6.640068 -122.10034)
					(mid 6.604407 -122.088073)
					(end 6.567424 -122.095514)
				)
				(arc
					(start 6.567424 -122.095514)
					(mid 6.356611 -122.177317)
					(end 6.134354 -122.218958)
				)
				(xy 6.134608 -122.224292) (xy 6.1468 -122.41403)
				(arc
					(start 6.14934 -122.413776)
					(mid 6.771894 -122.962162)
					(end 7.32028 -122.339608)
				)
				(xy 7.32282 -122.339354) (xy 7.267956 -121.477532) (xy 7.267702 -121.477278)
			)
		)
	)
	(zone
		(layer "B.Cu")
		(hatch none 0.5)
		(connect_pads
			(clearance 0)
		)
		(min_thickness 0.25)
		(keepout
			(tracks not_allowed)
			(vias allowed)
			(pads allowed)
			(copperpour not_allowed)
			(footprints allowed)
		)
		(placement
			(enabled no)
			(sheetname "")
		)
		(fill
			(thermal_gap 0.5)
			(thermal_bridge_width 0.5)
			(island_removal_mode 0)
		)
		(polygon
			(pts
				(arc
					(start 223.61144 -369.971574)
					(mid 223.058863 -369.352569)
					(end 222.439992 -369.90528)
				)
				(xy 222.437452 -369.905026) (xy 222.424752 -370.1288)
				(arc
					(start 222.771716 -370.1288)
					(mid 222.787007 -370.128144)
					(end 222.802196 -370.12626)
				)
				(arc
					(start 222.802196 -370.12626)
					(mid 223.191638 -369.697967)
					(end 222.929196 -370.21389)
				)
				(arc
					(start 222.929196 -370.21389)
					(mid 222.866378 -370.241267)
					(end 222.799148 -370.25453)
				)
				(xy 222.798132 -370.2558) (xy 222.41764 -370.2558) (xy 222.405956 -370.459) (xy 222.685864 -370.459)
				(arc
					(start 222.686626 -370.460016)
					(mid 222.805468 -370.488325)
					(end 222.90913 -370.55298)
				)
				(arc
					(start 222.90913 -370.55298)
					(mid 223.107737 -371.097827)
					(end 222.78213 -370.618004)
				)
				(arc
					(start 222.78213 -370.618004)
					(mid 222.72284 -370.594126)
					(end 222.659448 -370.586)
				)
				(xy 222.398844 -370.586) (xy 222.386398 -370.80444)
				(arc
					(start 222.388938 -370.804694)
					(mid 222.941642 -371.423438)
					(end 223.560386 -370.870734)
				)
				(xy 223.562926 -370.870988) (xy 223.61398 -369.971828) (xy 223.613726 -369.971574)
			)
		)
	)
	(zone
		(layer "B.Cu")
		(hatch none 0.5)
		(connect_pads
			(clearance 0)
		)
		(min_thickness 0.25)
		(keepout
			(tracks not_allowed)
			(vias allowed)
			(pads allowed)
			(copperpour not_allowed)
			(footprints allowed)
		)
		(placement
			(enabled no)
			(sheetname "")
		)
		(fill
			(thermal_gap 0.5)
			(thermal_bridge_width 0.5)
			(island_removal_mode 0)
		)
		(polygon
			(pts
				(arc
					(start 7.266686 -101.498908)
					(mid 6.680073 -100.911914)
					(end 6.093206 -101.498654)
				)
				(arc
					(start 6.093206 -102.457504)
					(mid 6.679946 -103.044244)
					(end 7.266686 -102.457504)
				)
				(xy 7.266686 -102.206552)
				(arc
					(start 7.129018 -102.206552)
					(mid 7.028969 -102.226417)
					(end 6.944106 -102.283006)
				)
				(arc
					(start 6.92658 -102.300786)
					(mid 6.47332 -102.66413)
					(end 6.836664 -102.21087)
				)
				(xy 6.85419 -102.193344) (xy 6.854444 -102.193344) (xy 6.872732 -102.174802)
				(arc
					(start 6.874256 -102.174802)
					(mid 6.980384 -102.109177)
					(end 7.10184 -102.080568)
				)
				(xy 7.102602 -102.079552) (xy 7.266686 -102.079552) (xy 7.266686 -101.876352) (xy 6.967728 -101.876352)
				(arc
					(start 6.966966 -101.875336)
					(mid 6.848844 -101.847245)
					(end 6.745732 -101.783134)
				)
				(arc
					(start 6.745732 -101.783134)
					(mid 6.547125 -101.238287)
					(end 6.872732 -101.71811)
				)
				(arc
					(start 6.872732 -101.71811)
					(mid 6.931455 -101.741434)
					(end 6.994144 -101.749352)
				)
				(xy 7.266686 -101.749352)
			)
		)
	)
	(zone
		(layer "B.Cu")
		(hatch none 0.5)
		(connect_pads
			(clearance 0.5)
		)
		(min_thickness 0.25)
		(fill
			(thermal_gap 0.5)
			(thermal_bridge_width 0.5)
			(island_removal_mode 0)
		)
		(polygon
			(pts
				(xy 228.091746 -4.4577) (xy 228.091746 -9.4107) (xy 231.393746 -12.7127) (xy 233.933746 -12.7127)
				(xy 234.314746 -12.3317) (xy 234.314746 -4.4577) (xy 233.679746 -3.8227) (xy 228.726746 -3.8227)
			)
		)
	)
	(zone
		(layer "B.Cu")
		(hatch none 0.5)
		(connect_pads
			(clearance 0)
		)
		(min_thickness 0.25)
		(keepout
			(tracks not_allowed)
			(vias allowed)
			(pads allowed)
			(copperpour not_allowed)
			(footprints allowed)
		)
		(placement
			(enabled no)
			(sheetname "")
		)
		(fill
			(thermal_gap 0.5)
			(thermal_bridge_width 0.5)
			(island_removal_mode 0)
		)
		(polygon
			(pts
				(arc
					(start 216.11971 -270.192754)
					(mid 216.69832 -269.597759)
					(end 216.1032 -269.019274)
				)
				(arc
					(start 215.1888 -269.032228)
					(mid 214.757584 -269.230268)
					(end 214.613998 -269.682468)
				)
				(xy 214.890604 -269.682468)
				(arc
					(start 214.91194 -269.681706)
					(mid 215.460309 -269.492226)
					(end 214.97036 -269.802864)
				)
				(arc
					(start 214.96782 -269.803372)
					(mid 214.942869 -269.806677)
					(end 214.917782 -269.808706)
				)
				(xy 214.91702 -269.809468)
				(arc
					(start 214.642192 -269.809468)
					(mid 214.691821 -269.917153)
					(end 214.76208 -270.012668)
				)
				(arc
					(start 215.391746 -270.012668)
					(mid 215.598091 -269.971606)
					(end 215.773 -269.85468)
				)
				(arc
					(start 215.864948 -269.762732)
					(mid 216.318208 -269.399388)
					(end 215.954864 -269.852648)
				)
				(xy 215.844374 -269.963138)
				(arc
					(start 215.843612 -269.963138)
					(mid 215.646817 -270.089007)
					(end 215.41867 -270.13916)
				)
				(xy 215.418162 -270.139668)
				(arc
					(start 214.926672 -270.139668)
					(mid 215.062025 -270.189964)
					(end 215.205564 -270.205708)
				)
			)
		)
	)
	(zone
		(layer "B.Cu")
		(hatch none 0.5)
		(connect_pads
			(clearance 0)
		)
		(min_thickness 0.25)
		(keepout
			(tracks not_allowed)
			(vias allowed)
			(pads allowed)
			(copperpour not_allowed)
			(footprints allowed)
		)
		(placement
			(enabled no)
			(sheetname "")
		)
		(fill
			(thermal_gap 0.5)
			(thermal_bridge_width 0.5)
			(island_removal_mode 0)
		)
		(polygon
			(pts
				(arc
					(start 6.879082 -128.223518)
					(mid 7.076952 -128.127995)
					(end 7.292086 -128.08331)
				)
				(xy 7.292086 -127.877062) (xy 6.993128 -127.877062)
				(arc
					(start 6.992366 -127.876046)
					(mid 6.874244 -127.847955)
					(end 6.771132 -127.783844)
				)
				(arc
					(start 6.771132 -127.783844)
					(mid 6.572525 -127.238997)
					(end 6.898132 -127.71882)
				)
				(arc
					(start 6.898132 -127.71882)
					(mid 6.956855 -127.742144)
					(end 7.019544 -127.750062)
				)
				(xy 7.292086 -127.750062)
				(arc
					(start 7.292086 -127.499618)
					(mid 6.705473 -126.912624)
					(end 6.118606 -127.499364)
				)
				(arc
					(start 6.118606 -128.458214)
					(mid 6.705346 -129.044954)
					(end 7.292086 -128.458214)
				)
				(arc
					(start 7.292086 -128.210818)
					(mid 7.121372 -128.246954)
					(end 6.963156 -128.320546)
				)
				(arc
					(start 6.963156 -128.320546)
					(mid 6.485211 -128.650068)
					(end 6.879082 -128.223518)
				)
			)
		)
	)
	(zone
		(layer "B.Cu")
		(hatch none 0.5)
		(connect_pads
			(clearance 0)
		)
		(min_thickness 0.25)
		(keepout
			(tracks not_allowed)
			(vias allowed)
			(pads allowed)
			(copperpour not_allowed)
			(footprints allowed)
		)
		(placement
			(enabled no)
			(sheetname "")
		)
		(fill
			(thermal_gap 0.5)
			(thermal_bridge_width 0.5)
			(island_removal_mode 0)
		)
		(polygon
			(pts
				(arc
					(start 216.792048 -475.829884)
					(mid 217.375485 -475.239715)
					(end 216.78519 -474.656404)
				)
				(arc
					(start 215.92159 -474.661484)
					(mid 215.471002 -474.8767)
					(end 215.349328 -475.361)
				)
				(arc
					(start 215.655652 -475.361)
					(mid 216.152388 -475.06463)
					(end 215.758268 -475.488)
				)
				(arc
					(start 215.389714 -475.488)
					(mid 215.453929 -475.597828)
					(end 215.540336 -475.6912)
				)
				(arc
					(start 215.899746 -475.6912)
					(mid 216.224136 -475.62671)
					(end 216.499186 -475.443042)
				)
				(arc
					(start 216.542112 -475.399862)
					(mid 216.995372 -475.036518)
					(end 216.632028 -475.489778)
				)
				(xy 216.589102 -475.532704) (xy 216.588848 -475.532704) (xy 216.57056 -475.551246)
				(arc
					(start 216.570052 -475.551246)
					(mid 216.272877 -475.74407)
					(end 215.926416 -475.817946)
				)
				(xy 215.926162 -475.8182)
				(arc
					(start 215.785954 -475.8182)
					(mid 215.856813 -475.830957)
					(end 215.928702 -475.834964)
				)
			)
		)
	)
	(zone
		(layer "B.Cu")
		(hatch none 0.5)
		(connect_pads
			(clearance 0)
		)
		(min_thickness 0.25)
		(keepout
			(tracks not_allowed)
			(vias allowed)
			(pads allowed)
			(copperpour not_allowed)
			(footprints allowed)
		)
		(placement
			(enabled no)
			(sheetname "")
		)
		(fill
			(thermal_gap 0.5)
			(thermal_bridge_width 0.5)
			(island_removal_mode 0)
		)
		(polygon
			(pts
				(arc
					(start 35.638486 -472.820492)
					(mid 35.051873 -472.233498)
					(end 34.465006 -472.820238)
				)
				(xy 34.465006 -473.0115)
				(arc
					(start 34.6202 -473.0115)
					(mid 34.712087 -472.999685)
					(end 34.798 -472.965018)
				)
				(arc
					(start 34.798 -472.965018)
					(mid 35.26705 -472.622773)
					(end 34.88563 -473.060522)
				)
				(arc
					(start 34.88563 -473.060522)
					(mid 34.771395 -473.114626)
					(end 34.647124 -473.137738)
				)
				(xy 34.646616 -473.1385) (xy 34.465006 -473.1385) (xy 34.465006 -473.3417) (xy 34.519616 -473.3417)
				(arc
					(start 34.520124 -473.342208)
					(mid 34.716398 -473.386164)
					(end 34.886138 -473.4941)
				)
				(xy 34.8869 -473.4941)
				(arc
					(start 34.894774 -473.501974)
					(mid 35.258517 -473.954725)
					(end 34.805112 -473.59189)
				)
				(arc
					(start 34.805112 -473.59189)
					(mid 34.66088 -473.500607)
					(end 34.4932 -473.4687)
				)
				(xy 34.465006 -473.4687)
				(arc
					(start 34.465006 -473.748354)
					(mid 35.051746 -474.335094)
					(end 35.638486 -473.748354)
				)
			)
		)
	)
	(zone
		(layer "B.Cu")
		(hatch none 0.5)
		(connect_pads
			(clearance 0)
		)
		(min_thickness 0.25)
		(keepout
			(tracks not_allowed)
			(vias allowed)
			(pads allowed)
			(copperpour not_allowed)
			(footprints allowed)
		)
		(placement
			(enabled no)
			(sheetname "")
		)
		(fill
			(thermal_gap 0.5)
			(thermal_bridge_width 0.5)
			(island_removal_mode 0)
		)
		(polygon
			(pts
				(arc
					(start 7.746746 -379.79096)
					(mid 7.160006 -380.3777)
					(end 7.746746 -380.96444)
				)
				(xy 8.660892 -380.96444)
				(arc
					(start 8.661146 -380.96444)
					(mid 9.247886 -380.3777)
					(end 8.661146 -379.79096)
				)
				(arc
					(start 8.410194 -379.79096)
					(mid 8.456525 -379.958824)
					(end 8.53186 -380.115826)
				)
				(arc
					(start 8.53186 -380.115826)
					(mid 8.84431 -380.60537)
					(end 8.432038 -380.196344)
				)
				(arc
					(start 8.432038 -380.196344)
					(mid 8.336724 -380.001085)
					(end 8.281416 -379.79096)
				)
				(xy 8.064246 -379.79096)
				(arc
					(start 8.063738 -379.791214)
					(mid 8.035737 -379.992615)
					(end 7.964678 -380.183136)
				)
				(arc
					(start 7.964678 -380.183136)
					(mid 7.576968 -380.61545)
					(end 7.86003 -380.10846)
				)
				(arc
					(start 7.86003 -380.10846)
					(mid 7.914713 -379.953652)
					(end 7.936738 -379.79096)
				)
			)
		)
	)
	(zone
		(layer "B.Cu")
		(hatch none 0.5)
		(connect_pads
			(clearance 0)
		)
		(min_thickness 0.25)
		(keepout
			(tracks not_allowed)
			(vias allowed)
			(pads allowed)
			(copperpour not_allowed)
			(footprints allowed)
		)
		(placement
			(enabled no)
			(sheetname "")
		)
		(fill
			(thermal_gap 0.5)
			(thermal_bridge_width 0.5)
			(island_removal_mode 0)
		)
		(polygon
			(pts
				(arc
					(start 22.581108 -32.148526)
					(mid 21.950172 -31.609538)
					(end 21.411184 -32.240474)
				)
				(arc
					(start 21.487384 -33.209738)
					(mid 22.118192 -33.74897)
					(end 22.657308 -33.118044)
				)
				(xy 22.631654 -32.7914)
				(arc
					(start 22.102064 -32.7914)
					(mid 22.005198 -32.821823)
					(end 21.94306 -32.902144)
				)
				(arc
					(start 21.94306 -32.902144)
					(mid 22.276026 -33.37332)
					(end 21.814028 -33.02762)
				)
				(arc
					(start 21.814028 -33.02762)
					(mid 21.807726 -32.994484)
					(end 21.805646 -32.960818)
				)
				(arc
					(start 21.805646 -32.960818)
					(mid 21.882896 -32.761246)
					(end 22.074378 -32.66567)
				)
				(xy 22.075648 -32.6644) (xy 22.621748 -32.6644) (xy 22.605746 -32.4612) (xy 22.433026 -32.4612)
				(xy 22.432518 -32.460692) (xy 22.381972 -32.456628)
				(arc
					(start 22.381718 -32.456628)
					(mid 22.338037 -32.450265)
					(end 22.29485 -32.441134)
				)
				(arc
					(start 22.29485 -32.441134)
					(mid 22.244318 -32.426643)
					(end 22.195028 -32.408368)
				)
				(arc
					(start 22.195028 -32.408368)
					(mid 21.755006 -32.029837)
					(end 22.268434 -32.300672)
				)
				(arc
					(start 22.268434 -32.300672)
					(mid 22.296658 -32.30993)
					(end 22.32533 -32.31769)
				)
				(arc
					(start 22.32533 -32.31769)
					(mid 22.360557 -32.325298)
					(end 22.396196 -32.330644)
				)
				(arc
					(start 22.396196 -32.330644)
					(mid 22.427769 -32.333309)
					(end 22.459442 -32.3342)
				)
				(xy 22.595586 -32.3342)
			)
		)
	)
	(zone
		(layer "B.Cu")
		(hatch none 0.5)
		(connect_pads
			(clearance 0)
		)
		(min_thickness 0.25)
		(keepout
			(tracks not_allowed)
			(vias allowed)
			(pads allowed)
			(copperpour not_allowed)
			(footprints allowed)
		)
		(placement
			(enabled no)
			(sheetname "")
		)
		(fill
			(thermal_gap 0.5)
			(thermal_bridge_width 0.5)
			(island_removal_mode 0)
		)
		(polygon
			(pts
				(arc
					(start 27.146758 -236.448092)
					(mid 27.109791 -236.445105)
					(end 27.073098 -236.43971)
				)
				(arc
					(start 27.061414 -236.59719)
					(mid 27.602942 -237.226094)
					(end 28.231846 -236.684566)
				)
				(arc
					(start 28.296362 -235.819442)
					(mid 27.75496 -235.190547)
					(end 27.12593 -235.731812)
				)
				(xy 27.121612 -235.78947)
				(arc
					(start 27.10815 -235.970064)
					(mid 27.139084 -235.985936)
					(end 27.173428 -235.9914)
				)
				(arc
					(start 27.2796 -235.9914)
					(mid 27.376449 -235.975675)
					(end 27.463242 -235.929932)
				)
				(arc
					(start 27.463242 -235.929932)
					(mid 27.919359 -235.570676)
					(end 27.55265 -236.020864)
				)
				(arc
					(start 27.55265 -236.020864)
					(mid 27.437175 -236.088535)
					(end 27.306524 -236.117638)
				)
				(xy 27.305762 -236.1184) (xy 27.147012 -236.1184)
				(arc
					(start 27.145488 -236.116622)
					(mid 27.121469 -236.112643)
					(end 27.09799 -236.106208)
				)
				(arc
					(start 27.08275 -236.312202)
					(mid 27.12734 -236.319197)
					(end 27.172412 -236.3216)
				)
				(xy 27.305762 -236.3216)
				(arc
					(start 27.306778 -236.322616)
					(mid 27.403029 -236.345316)
					(end 27.488388 -236.39526)
				)
				(arc
					(start 27.488388 -236.39526)
					(mid 27.855243 -236.845346)
					(end 27.398726 -236.486446)
				)
				(arc
					(start 27.398726 -236.486446)
					(mid 27.342098 -236.458303)
					(end 27.2796 -236.4486)
				)
				(xy 27.173682 -236.4486) (xy 27.172412 -236.4486) (xy 27.147266 -236.4486)
			)
		)
	)
	(zone
		(layer "B.Cu")
		(hatch none 0.5)
		(connect_pads
			(clearance 0)
		)
		(min_thickness 0.25)
		(keepout
			(tracks not_allowed)
			(vias allowed)
			(pads allowed)
			(copperpour not_allowed)
			(footprints allowed)
		)
		(placement
			(enabled no)
			(sheetname "")
		)
		(fill
			(thermal_gap 0.5)
			(thermal_bridge_width 0.5)
			(island_removal_mode 0)
		)
		(polygon
			(pts
				(arc
					(start 7.418832 -115.548156)
					(mid 6.848602 -114.945414)
					(end 6.24586 -115.515644)
				)
				(xy 6.24332 -115.515644) (xy 6.21792 -116.441982)
				(arc
					(start 6.22046 -116.441982)
					(mid 6.79069 -117.044724)
					(end 7.393432 -116.474494)
				)
				(xy 7.395972 -116.474494) (xy 7.403338 -116.207286)
				(arc
					(start 7.121398 -116.207286)
					(mid 7.05856 -116.215289)
					(end 6.999732 -116.238782)
				)
				(arc
					(start 6.999732 -116.238782)
					(mid 6.674145 -116.718564)
					(end 6.872732 -116.173758)
				)
				(arc
					(start 6.872732 -116.173758)
					(mid 6.975949 -116.109514)
					(end 7.09422 -116.081302)
				)
				(xy 7.094982 -116.080286) (xy 7.406894 -116.080286) (xy 7.412482 -115.877086) (xy 7.087616 -115.877086)
				(arc
					(start 7.0866 -115.87607)
					(mid 6.995542 -115.856121)
					(end 6.913118 -115.81257)
				)
				(arc
					(start 6.913118 -115.81257)
					(mid 6.68322 -115.28078)
					(end 7.040118 -115.737132)
				)
				(arc
					(start 7.040118 -115.737132)
					(mid 7.076512 -115.746828)
					(end 7.114032 -115.750086)
				)
				(xy 7.415784 -115.750086) (xy 7.421372 -115.54841) (xy 7.421118 -115.548156)
			)
		)
	)
	(zone
		(layer "B.Cu")
		(hatch none 0.5)
		(connect_pads
			(clearance 0)
		)
		(min_thickness 0.25)
		(keepout
			(tracks not_allowed)
			(vias allowed)
			(pads allowed)
			(copperpour not_allowed)
			(footprints allowed)
		)
		(placement
			(enabled no)
			(sheetname "")
		)
		(fill
			(thermal_gap 0.5)
			(thermal_bridge_width 0.5)
			(island_removal_mode 0)
		)
		(polygon
			(pts
				(arc
					(start 22.225508 -444.181992)
					(mid 21.613876 -443.62116)
					(end 21.053044 -444.232792)
				)
				(arc
					(start 21.090382 -445.095376)
					(mid 21.701887 -445.656457)
					(end 22.262846 -445.04483)
				)
				(arc
					(start 22.251416 -444.779908)
					(mid 22.213281 -444.782972)
					(end 22.17547 -444.788798)
				)
				(arc
					(start 22.17547 -444.788798)
					(mid 22.040958 -444.8344)
					(end 21.923502 -444.914274)
				)
				(arc
					(start 21.923502 -444.914274)
					(mid 21.469602 -445.276196)
					(end 21.83384 -444.824104)
				)
				(arc
					(start 21.83384 -444.824104)
					(mid 21.981617 -444.722134)
					(end 22.151594 -444.664338)
				)
				(arc
					(start 22.151594 -444.664338)
					(mid 22.198508 -444.657037)
					(end 22.245828 -444.653162)
				)
				(xy 22.237192 -444.4492) (xy 22.04339 -444.4492)
				(arc
					(start 22.042882 -444.448692)
					(mid 21.944097 -444.437375)
					(end 21.848064 -444.411608)
				)
				(arc
					(start 21.848064 -444.411608)
					(mid 21.390139 -444.055582)
					(end 21.916136 -444.300102)
				)
				(arc
					(start 21.916136 -444.300102)
					(mid 21.992181 -444.316648)
					(end 22.069806 -444.3222)
				)
				(xy 22.231604 -444.3222)
			)
		)
	)
	(zone
		(layer "B.Cu")
		(hatch none 0.5)
		(connect_pads
			(clearance 0)
		)
		(min_thickness 0.25)
		(keepout
			(tracks not_allowed)
			(vias allowed)
			(pads allowed)
			(copperpour not_allowed)
			(footprints allowed)
		)
		(placement
			(enabled no)
			(sheetname "")
		)
		(fill
			(thermal_gap 0.5)
			(thermal_bridge_width 0.5)
			(island_removal_mode 0)
		)
		(polygon
			(pts
				(arc
					(start 223.750124 -163.975796)
					(mid 223.163511 -163.388802)
					(end 222.576644 -163.975542)
				)
				(xy 222.576644 -164.181282)
				(arc
					(start 222.778066 -164.181282)
					(mid 222.851502 -164.168457)
					(end 222.916242 -164.131498)
				)
				(arc
					(start 222.916242 -164.131498)
					(mid 223.370349 -163.769224)
					(end 223.006666 -164.222176)
				)
				(xy 223.002602 -164.22624)
				(arc
					(start 223.000824 -164.22624)
					(mid 222.909547 -164.28215)
					(end 222.805498 -164.307266)
				)
				(xy 222.804482 -164.308282) (xy 222.576644 -164.308282) (xy 222.576644 -164.511482) (xy 222.66275 -164.511482)
				(arc
					(start 222.663512 -164.512244)
					(mid 222.815564 -164.547191)
					(end 222.947738 -164.6301)
				)
				(xy 222.949008 -164.6301) (xy 222.967296 -164.648642) (xy 222.96755 -164.648642)
				(arc
					(start 223.006666 -164.687758)
					(mid 223.37001 -165.141018)
					(end 222.91675 -164.777674)
				)
				(arc
					(start 222.877634 -164.738558)
					(mid 222.76694 -164.664501)
					(end 222.636334 -164.638482)
				)
				(xy 222.576644 -164.638482)
				(arc
					(start 222.576644 -164.934392)
					(mid 223.163384 -165.521132)
					(end 223.750124 -164.934392)
				)
			)
		)
	)
	(zone
		(layer "B.Cu")
		(hatch none 0.5)
		(connect_pads
			(clearance 0)
		)
		(min_thickness 0.25)
		(keepout
			(tracks allowed)
			(vias allowed)
			(pads allowed)
			(copperpour allowed)
			(footprints not_allowed)
		)
		(placement
			(enabled no)
			(sheetname "")
		)
		(fill
			(thermal_gap 0.5)
			(thermal_bridge_width 0.5)
			(island_removal_mode 0)
		)
		(polygon
			(pts
				(arc
					(start 252.499876 -33.999932)
					(mid 248.499884 -37.999924)
					(end 252.499876 -41.999916)
				)
				(arc
					(start 252.499876 -41.999916)
					(mid 256.499868 -37.999924)
					(end 252.499876 -33.999932)
				)
			)
		)
	)
	(zone
		(layer "B.Cu")
		(hatch none 0.5)
		(connect_pads
			(clearance 0)
		)
		(min_thickness 0.25)
		(keepout
			(tracks not_allowed)
			(vias allowed)
			(pads allowed)
			(copperpour not_allowed)
			(footprints allowed)
		)
		(placement
			(enabled no)
			(sheetname "")
		)
		(fill
			(thermal_gap 0.5)
			(thermal_bridge_width 0.5)
			(island_removal_mode 0)
		)
		(polygon
			(pts
				(arc
					(start 28.330652 -338.66201)
					(mid 27.743912 -338.07527)
					(end 27.157172 -338.66201)
				)
				(arc
					(start 27.157172 -338.911438)
					(mid 27.330314 -338.880516)
					(end 27.489404 -338.80552)
				)
				(arc
					(start 27.489404 -338.80552)
					(mid 27.960036 -338.465558)
					(end 27.575764 -338.90077)
				)
				(arc
					(start 27.575764 -338.90077)
					(mid 27.376204 -338.999274)
					(end 27.157172 -339.038692)
				)
				(arc
					(start 27.157172 -339.242908)
					(mid 27.376332 -339.282664)
					(end 27.575764 -339.381846)
				)
				(arc
					(start 27.575764 -339.381846)
					(mid 27.960915 -339.816528)
					(end 27.489658 -339.477096)
				)
				(arc
					(start 27.489658 -339.477096)
					(mid 27.330551 -339.401454)
					(end 27.157172 -339.370162)
				)
				(arc
					(start 27.157172 -339.620606)
					(mid 27.743785 -340.2076)
					(end 28.330652 -339.62086)
				)
			)
		)
	)
	(zone
		(layer "B.Cu")
		(hatch none 0.5)
		(connect_pads
			(clearance 0)
		)
		(min_thickness 0.25)
		(keepout
			(tracks not_allowed)
			(vias allowed)
			(pads allowed)
			(copperpour not_allowed)
			(footprints allowed)
		)
		(placement
			(enabled no)
			(sheetname "")
		)
		(fill
			(thermal_gap 0.5)
			(thermal_bridge_width 0.5)
			(island_removal_mode 0)
		)
		(polygon
			(pts
				(arc
					(start 26.58364 -341.503254)
					(mid 25.997027 -340.91626)
					(end 25.41016 -341.503)
				)
				(arc
					(start 25.41016 -341.732616)
					(mid 25.514226 -341.729505)
					(end 25.617932 -341.738712)
				)
				(arc
					(start 25.617932 -341.738712)
					(mid 25.660917 -341.734911)
					(end 25.697688 -341.712296)
				)
				(xy 25.697942 -341.712042)
				(arc
					(start 25.750266 -341.659718)
					(mid 26.203526 -341.296374)
					(end 25.840182 -341.749634)
				)
				(xy 25.787858 -341.801958) (xy 25.787604 -341.802212) (xy 25.769316 -341.8205)
				(arc
					(start 25.766776 -341.8205)
					(mid 25.687426 -341.859539)
					(end 25.599136 -341.864188)
				)
				(arc
					(start 25.599136 -341.864188)
					(mid 25.504776 -341.856193)
					(end 25.41016 -341.860124)
				)
				(arc
					(start 25.41016 -342.065356)
					(mid 25.636957 -342.080276)
					(end 25.83815 -342.186006)
				)
				(arc
					(start 25.83815 -342.186006)
					(mid 26.204882 -342.636217)
					(end 25.748742 -342.276938)
				)
				(arc
					(start 25.748742 -342.276938)
					(mid 25.588433 -342.198768)
					(end 25.41016 -342.194134)
				)
				(arc
					(start 25.41016 -342.431116)
					(mid 25.9969 -343.017856)
					(end 26.58364 -342.431116)
				)
			)
		)
	)
	(zone
		(layer "B.Cu")
		(hatch none 0.5)
		(connect_pads
			(clearance 0)
		)
		(min_thickness 0.25)
		(keepout
			(tracks not_allowed)
			(vias allowed)
			(pads allowed)
			(copperpour not_allowed)
			(footprints allowed)
		)
		(placement
			(enabled no)
			(sheetname "")
		)
		(fill
			(thermal_gap 0.5)
			(thermal_bridge_width 0.5)
			(island_removal_mode 0)
		)
		(polygon
			(pts
				(arc
					(start 7.075932 -347.594174)
					(mid 6.500241 -347.001594)
					(end 5.907532 -347.577156)
				)
				(arc
					(start 5.894578 -348.491048)
					(mid 6.470396 -349.08363)
					(end 7.062978 -348.507812)
				)
				(arc
					(start 7.066788 -348.240858)
					(mid 6.897018 -348.288407)
					(end 6.738874 -348.366334)
				)
				(arc
					(start 6.738874 -348.366334)
					(mid 6.254229 -348.686359)
					(end 6.656832 -348.267782)
				)
				(arc
					(start 6.656832 -348.267782)
					(mid 6.854688 -348.168648)
					(end 7.068566 -348.111826)
				)
				(arc
					(start 7.071614 -347.895164)
					(mid 6.874336 -347.870067)
					(end 6.687312 -347.802454)
				)
				(arc
					(start 6.687312 -347.802454)
					(mid 6.253576 -347.416536)
					(end 6.761734 -347.697298)
				)
				(arc
					(start 6.761734 -347.697298)
					(mid 6.91388 -347.748926)
					(end 7.073392 -347.768164)
				)
			)
		)
	)
	(zone
		(layer "B.Cu")
		(hatch none 0.5)
		(connect_pads
			(clearance 0)
		)
		(min_thickness 0.25)
		(keepout
			(tracks allowed)
			(vias allowed)
			(pads allowed)
			(copperpour allowed)
			(footprints not_allowed)
		)
		(placement
			(enabled no)
			(sheetname "")
		)
		(fill
			(thermal_gap 0.5)
			(thermal_bridge_width 0.5)
			(island_removal_mode 0)
		)
		(polygon
			(pts
				(arc
					(start 69.000116 -277.999952)
					(mid 73.000108 -273.99996)
					(end 69.000116 -269.999968)
				)
				(arc
					(start 69.000116 -269.999968)
					(mid 65.000124 -273.99996)
					(end 69.000116 -277.999952)
				)
			)
		)
	)
	(zone
		(layer "B.Cu")
		(hatch none 0.5)
		(connect_pads
			(clearance 0)
		)
		(min_thickness 0.25)
		(keepout
			(tracks not_allowed)
			(vias allowed)
			(pads allowed)
			(copperpour not_allowed)
			(footprints allowed)
		)
		(placement
			(enabled no)
			(sheetname "")
		)
		(fill
			(thermal_gap 0.5)
			(thermal_bridge_width 0.5)
			(island_removal_mode 0)
		)
		(polygon
			(pts
				(arc
					(start 6.937502 -162.236912)
					(mid 7.128638 -162.152246)
					(end 7.332472 -162.105848)
				)
				(arc
					(start 7.332472 -161.884868)
					(mid 7.128642 -161.838458)
					(end 6.937502 -161.753804)
				)
				(arc
					(start 6.937502 -161.753804)
					(mid 6.514864 -161.355696)
					(end 7.014464 -161.651442)
				)
				(arc
					(start 7.014464 -161.651442)
					(mid 7.168817 -161.718182)
					(end 7.332472 -161.756852)
				)
				(arc
					(start 7.332472 -161.531554)
					(mid 6.748399 -160.9471)
					(end 6.164072 -161.5313)
				)
				(arc
					(start 6.164072 -162.459416)
					(mid 6.748272 -163.043616)
					(end 7.332472 -162.459416)
				)
				(arc
					(start 7.332472 -162.233864)
					(mid 7.168828 -162.272566)
					(end 7.014464 -162.339274)
				)
				(arc
					(start 7.014464 -162.339274)
					(mid 6.514896 -162.634995)
					(end 6.937502 -162.236912)
				)
			)
		)
	)
	(zone
		(layer "B.Cu")
		(hatch none 0.5)
		(connect_pads
			(clearance 0.5)
		)
		(min_thickness 0.25)
		(fill
			(thermal_gap 0.5)
			(thermal_bridge_width 0.5)
			(island_removal_mode 0)
		)
		(polygon
			(pts
				(xy 23.622 -486.41) (xy 23.622 -494.423954) (xy 25.907746 -496.7097) (xy 33.527746 -496.7097) (xy 34.924746 -495.3127)
				(xy 34.924746 -485.1527) (xy 33.146746 -483.3747) (xy 29.971746 -483.3747) (xy 27.177746 -480.5807)
				(xy 27.177746 -474.2307) (xy 26.415746 -473.4687) (xy 21.208746 -473.4687) (xy 20.319746 -474.3577)
				(xy 20.319746 -476.6437) (xy 20.065746 -476.8977) (xy 14.477746 -476.8977) (xy 13.842746 -477.5327)
				(xy 13.842746 -482.2317) (xy 15.620746 -484.0097) (xy 18.541746 -484.0097) (xy 19.424396 -484.892604)
				(xy 22.104604 -484.892604)
			)
		)
	)
	(zone
		(layer "B.Cu")
		(hatch none 0.5)
		(connect_pads
			(clearance 0.5)
		)
		(min_thickness 0.25)
		(fill
			(thermal_gap 0.5)
			(thermal_bridge_width 0.5)
			(island_removal_mode 0)
		)
		(polygon
			(pts
				(xy 27.177746 -19.3167) (xy 27.177746 -28.9687) (xy 28.320746 -30.1117) (xy 45.592746 -30.1117)
				(xy 45.973746 -29.7307) (xy 45.973746 -27.6987) (xy 43.306746 -25.0317) (xy 43.306746 -19.5707)
				(xy 42.671746 -18.9357) (xy 27.558746 -18.9357)
			)
		)
	)
	(zone
		(layer "B.Cu")
		(hatch none 0.5)
		(connect_pads
			(clearance 0)
		)
		(min_thickness 0.25)
		(keepout
			(tracks not_allowed)
			(vias allowed)
			(pads allowed)
			(copperpour not_allowed)
			(footprints allowed)
		)
		(placement
			(enabled no)
			(sheetname "")
		)
		(fill
			(thermal_gap 0.5)
			(thermal_bridge_width 0.5)
			(island_removal_mode 0)
		)
		(polygon
			(pts
				(arc
					(start 38.686486 -60.89142)
					(mid 38.099873 -60.304426)
					(end 37.513006 -60.891166)
				)
				(xy 37.513006 -61.2902)
				(arc
					(start 37.71265 -61.2902)
					(mid 37.78783 -61.275152)
					(end 37.851588 -61.232542)
				)
				(xy 37.925248 -61.158882)
				(arc
					(start 37.944298 -61.138562)
					(mid 38.194218 -60.614681)
					(end 38.071298 -61.181996)
				)
				(arc
					(start 38.071298 -61.181996)
					(mid 38.053201 -61.206174)
					(end 38.033706 -61.22924)
				)
				(xy 38.033706 -61.230256) (xy 38.015164 -61.248798) (xy 37.941504 -61.322458) (xy 37.922962 -61.341)
				(arc
					(start 37.921184 -61.341)
					(mid 37.836452 -61.392543)
					(end 37.740082 -61.41593)
				)
				(xy 37.739066 -61.4172) (xy 37.513006 -61.4172) (xy 37.513006 -61.6204) (xy 37.725096 -61.6204)
				(arc
					(start 37.725604 -61.620908)
					(mid 37.807432 -61.629846)
					(end 37.887402 -61.649356)
				)
				(arc
					(start 37.887402 -61.649356)
					(mid 38.351685 -61.997939)
					(end 37.821108 -61.762386)
				)
				(arc
					(start 37.821108 -61.762386)
					(mid 37.760354 -61.751135)
					(end 37.69868 -61.7474)
				)
				(xy 37.513006 -61.7474)
				(arc
					(start 37.513006 -61.850016)
					(mid 38.099746 -62.436756)
					(end 38.686486 -61.850016)
				)
			)
		)
	)
	(zone
		(net "P5VC")
		(layer "B.Cu")
		(hatch none 0.5)
		(connect_pads
			(clearance 0.5)
		)
		(min_thickness 0.25)
		(fill yes
			(thermal_gap 0.5)
			(thermal_bridge_width 0.5)
			(island_removal_mode 0)
		)
		(polygon
			(pts
				(xy 87.248746 -25.0317) (xy 68.706746 -43.5737) (xy 56.260746 -43.5737) (xy 56.133746 -43.7007)
				(xy 56.133746 -49.6697) (xy 56.133746 -52.069746) (xy 56.388 -52.324) (xy 72.771 -52.324) (xy 95.123 -29.972)
				(xy 95.123 -25.527) (xy 94.6277 -25.0317) (xy 92.201746 -25.0317)
			)
		)
	)
	(zone
		(layer "B.Cu")
		(hatch none 0.5)
		(connect_pads
			(clearance 0.5)
		)
		(min_thickness 0.25)
		(fill
			(thermal_gap 0.5)
			(thermal_bridge_width 0.5)
			(island_removal_mode 0)
		)
		(polygon
			(pts
				(xy 11.683746 -496.7097) (xy 11.683746 -499.1227) (xy 12.826746 -500.2657) (xy 24.637746 -500.2657)
				(xy 25.272746 -500.9007) (xy 27.685746 -500.9007) (xy 28.574746 -500.0117) (xy 28.574746 -497.5987)
				(xy 28.193746 -497.2177) (xy 24.002746 -497.2177) (xy 23.240746 -496.4557) (xy 11.937746 -496.4557)
			)
		)
	)
	(zone
		(layer "B.Cu")
		(hatch none 0.5)
		(connect_pads
			(clearance 0)
		)
		(min_thickness 0.25)
		(keepout
			(tracks not_allowed)
			(vias allowed)
			(pads allowed)
			(copperpour not_allowed)
			(footprints allowed)
		)
		(placement
			(enabled no)
			(sheetname "")
		)
		(fill
			(thermal_gap 0.5)
			(thermal_bridge_width 0.5)
			(island_removal_mode 0)
		)
		(polygon
			(pts
				(arc
					(start 29.138626 -344.885518)
					(mid 28.463364 -344.403151)
					(end 27.980894 -345.078304)
				)
				(arc
					(start 28.010866 -345.257628)
					(mid 28.167786 -345.212876)
					(end 28.30449 -345.12377)
				)
				(arc
					(start 28.30449 -345.12377)
					(mid 28.778618 -344.788149)
					(end 28.388818 -345.218766)
				)
				(arc
					(start 28.388818 -345.218766)
					(mid 28.222511 -345.327554)
					(end 28.031694 -345.383104)
				)
				(xy 28.066492 -345.5924) (xy 28.298902 -345.5924)
				(arc
					(start 28.29941 -345.592908)
					(mid 28.397418 -345.604183)
					(end 28.492704 -345.629738)
				)
				(arc
					(start 28.492704 -345.629738)
					(mid 28.951147 -345.986275)
					(end 28.424632 -345.741244)
				)
				(arc
					(start 28.424632 -345.741244)
					(mid 28.349336 -345.724902)
					(end 28.272486 -345.7194)
				)
				(xy 28.087828 -345.7194)
				(arc
					(start 28.12288 -345.93022)
					(mid 28.798266 -346.412566)
					(end 29.280612 -345.73718)
				)
			)
		)
	)
	(zone
		(layer "B.Cu")
		(hatch none 0.5)
		(connect_pads
			(clearance 0.5)
		)
		(min_thickness 0.25)
		(fill
			(thermal_gap 0.5)
			(thermal_bridge_width 0.5)
			(island_removal_mode 0)
		)
		(polygon
			(pts
				(xy 225.170746 -19.5707) (xy 227.456746 -21.8567) (xy 233.552746 -21.8567) (xy 233.806746 -21.6027)
				(xy 233.806746 -15.6337) (xy 227.456746 -9.2837) (xy 213.232746 -9.2837) (xy 212.343746 -10.1727)
				(xy 212.343746 -19.3167) (xy 212.597746 -19.5707)
			)
		)
	)
	(zone
		(layer "B.Cu")
		(hatch none 0.5)
		(connect_pads
			(clearance 0)
		)
		(min_thickness 0.25)
		(keepout
			(tracks not_allowed)
			(vias allowed)
			(pads allowed)
			(copperpour not_allowed)
			(footprints allowed)
		)
		(placement
			(enabled no)
			(sheetname "")
		)
		(fill
			(thermal_gap 0.5)
			(thermal_bridge_width 0.5)
			(island_removal_mode 0)
		)
		(polygon
			(pts
				(arc
					(start 7.340346 -409.273756)
					(mid 6.779006 -409.835096)
					(end 7.340346 -410.396436)
				)
				(arc
					(start 8.203946 -410.396436)
					(mid 8.765286 -409.835096)
					(end 8.203946 -409.273756)
				)
				(xy 8.033766 -409.273756)
				(arc
					(start 8.033766 -409.338272)
					(mid 8.046088 -409.456387)
					(end 8.082534 -409.569412)
				)
				(arc
					(start 8.082534 -409.569412)
					(mid 8.381856 -410.066561)
					(end 7.97941 -409.648406)
				)
				(arc
					(start 7.97941 -409.648406)
					(mid 7.928347 -409.510618)
					(end 7.907274 -409.365196)
				)
				(xy 7.906766 -409.364688) (xy 7.906766 -409.273756) (xy 7.703566 -409.273756) (xy 7.703566 -409.360116)
				(arc
					(start 7.702804 -409.360624)
					(mid 7.668502 -409.527204)
					(end 7.584948 -409.67533)
				)
				(arc
					(start 7.584948 -409.67533)
					(mid 7.136646 -410.044527)
					(end 7.493254 -409.586176)
				)
				(arc
					(start 7.493254 -409.586176)
					(mid 7.555164 -409.466888)
					(end 7.576566 -409.334208)
				)
				(xy 7.576566 -409.273756) (xy 7.3406 -409.273756)
			)
		)
	)
	(zone
		(layer "B.Cu")
		(hatch none 0.5)
		(connect_pads
			(clearance 0)
		)
		(min_thickness 0.25)
		(keepout
			(tracks not_allowed)
			(vias allowed)
			(pads allowed)
			(copperpour not_allowed)
			(footprints allowed)
		)
		(placement
			(enabled no)
			(sheetname "")
		)
		(fill
			(thermal_gap 0.5)
			(thermal_bridge_width 0.5)
			(island_removal_mode 0)
		)
		(polygon
			(pts
				(arc
					(start 29.550106 -363.09554)
					(mid 29.394757 -363.031605)
					(end 29.23032 -362.997242)
				)
				(arc
					(start 29.23032 -363.213904)
					(mid 29.81706 -363.800644)
					(end 30.4038 -363.213904)
				)
				(arc
					(start 30.4038 -362.255308)
					(mid 29.817187 -361.668314)
					(end 29.23032 -362.255054)
				)
				(arc
					(start 29.23032 -362.533946)
					(mid 29.40954 -362.498515)
					(end 29.568648 -362.408724)
				)
				(arc
					(start 29.568648 -362.408724)
					(mid 30.025935 -362.050862)
					(end 29.657802 -362.49991)
				)
				(arc
					(start 29.657802 -362.49991)
					(mid 29.460475 -362.614964)
					(end 29.23667 -362.660692)
				)
				(xy 29.236162 -362.6612) (xy 29.23032 -362.6612)
				(arc
					(start 29.23032 -362.86948)
					(mid 29.43463 -362.910994)
					(end 29.62656 -362.992416)
				)
				(arc
					(start 29.62656 -362.992416)
					(mid 30.052016 -363.387566)
					(end 29.550106 -363.09554)
				)
			)
		)
	)
	(zone
		(layer "B.Cu")
		(hatch none 0.5)
		(connect_pads
			(clearance 0.5)
		)
		(min_thickness 0.25)
		(fill
			(thermal_gap 0.5)
			(thermal_bridge_width 0.5)
			(island_removal_mode 0)
		)
		(polygon
			(pts
				(xy 46.735746 -5.6007) (xy 46.735746 -9.4107) (xy 49.656746 -12.3317) (xy 53.085746 -12.3317) (xy 53.847746 -11.5697)
				(xy 53.847746 -5.2197) (xy 53.339746 -4.7117) (xy 47.624746 -4.7117)
			)
		)
	)
	(zone
		(layer "B.Cu")
		(hatch none 0.5)
		(connect_pads
			(clearance 0)
		)
		(min_thickness 0.25)
		(keepout
			(tracks not_allowed)
			(vias allowed)
			(pads allowed)
			(copperpour not_allowed)
			(footprints allowed)
		)
		(placement
			(enabled no)
			(sheetname "")
		)
		(fill
			(thermal_gap 0.5)
			(thermal_bridge_width 0.5)
			(island_removal_mode 0)
		)
		(polygon
			(pts
				(arc
					(start 27.24023 -365.912654)
					(mid 26.644981 -365.334548)
					(end 26.06675 -365.929672)
				)
				(arc
					(start 26.083006 -367.02365)
					(mid 26.642253 -367.600923)
					(end 27.25293 -367.078514)
				)
				(arc
					(start 26.954734 -367.078514)
					(mid 26.377769 -367.015014)
					(end 26.954734 -366.951514)
				)
				(xy 27.255724 -366.951514)
				(arc
					(start 27.252422 -366.724946)
					(mid 27.214342 -366.712289)
					(end 27.177238 -366.697006)
				)
				(xy 27.165046 -366.697006) (xy 27.146504 -366.67821) (xy 27.069542 -366.601248) (xy 27.06878 -366.600232)
				(xy 27.051 -366.582452)
				(arc
					(start 27.051 -366.580674)
					(mid 27.010245 -366.512446)
					(end 26.990802 -366.435386)
				)
				(xy 26.989278 -366.434116)
				(arc
					(start 26.989278 -366.2807)
					(mid 26.967131 -366.167678)
					(end 26.903934 -366.071404)
				)
				(arc
					(start 26.903934 -366.071404)
					(mid 26.374564 -365.834242)
					(end 26.945082 -365.939324)
				)
				(arc
					(start 26.945082 -365.939324)
					(mid 26.968927 -365.958415)
					(end 26.99131 -365.979202)
				)
				(arc
					(start 26.99131 -365.979202)
					(mid 27.078462 -366.105025)
					(end 27.115516 -366.253522)
				)
				(xy 27.116278 -366.254284)
				(arc
					(start 27.116278 -366.4077)
					(mid 27.127282 -366.463467)
					(end 27.158696 -366.510824)
				)
				(xy 27.159458 -366.511586) (xy 27.228546 -366.580674) (xy 27.25039 -366.590072) (xy 27.24912 -366.511586)
			)
		)
	)
	(zone
		(layer "B.Cu")
		(hatch none 0.5)
		(connect_pads
			(clearance 0)
		)
		(min_thickness 0.25)
		(keepout
			(tracks not_allowed)
			(vias allowed)
			(pads allowed)
			(copperpour not_allowed)
			(footprints allowed)
		)
		(placement
			(enabled no)
			(sheetname "")
		)
		(fill
			(thermal_gap 0.5)
			(thermal_bridge_width 0.5)
			(island_removal_mode 0)
		)
		(polygon
			(pts
				(arc
					(start 216.236042 -64.080136)
					(mid 216.811352 -63.481966)
					(end 216.213182 -62.906656)
				)
				(arc
					(start 215.349836 -62.92342)
					(mid 214.920455 -63.122476)
					(end 214.777828 -63.57366)
				)
				(xy 215.054434 -63.57366)
				(arc
					(start 215.07577 -63.573152)
					(mid 215.624091 -63.383194)
					(end 215.13419 -63.69431)
				)
				(arc
					(start 215.13419 -63.69431)
					(mid 215.107849 -63.697817)
					(end 215.081358 -63.699898)
				)
				(xy 215.08085 -63.70066)
				(arc
					(start 214.806022 -63.70066)
					(mid 214.855651 -63.808345)
					(end 214.92591 -63.90386)
				)
				(arc
					(start 215.53932 -63.90386)
					(mid 215.7102 -63.86987)
					(end 215.855042 -63.77305)
				)
				(arc
					(start 215.977978 -63.650114)
					(mid 216.431238 -63.28677)
					(end 216.067894 -63.74003)
				)
				(xy 215.944958 -63.862966) (xy 215.926416 -63.881508)
				(arc
					(start 215.9254 -63.881508)
					(mid 215.758807 -63.987245)
					(end 215.566244 -64.030352)
				)
				(xy 215.565736 -64.03086)
				(arc
					(start 215.090502 -64.03086)
					(mid 215.227333 -64.081565)
					(end 215.372442 -64.0969)
				)
			)
		)
	)
	(zone
		(layer "B.Cu")
		(hatch none 0.5)
		(connect_pads
			(clearance 0)
		)
		(min_thickness 0.25)
		(keepout
			(tracks allowed)
			(vias allowed)
			(pads allowed)
			(copperpour allowed)
			(footprints not_allowed)
		)
		(placement
			(enabled no)
			(sheetname "")
		)
		(fill
			(thermal_gap 0.5)
			(thermal_bridge_width 0.5)
			(island_removal_mode 0)
		)
		(polygon
			(pts
				(arc
					(start 69.000116 -72.00011)
					(mid 73.000108 -68.000118)
					(end 69.000116 -64.000126)
				)
				(arc
					(start 69.000116 -64.000126)
					(mid 65.000124 -68.000118)
					(end 69.000116 -72.00011)
				)
			)
		)
	)
	(zone
		(layer "B.Cu")
		(hatch none 0.5)
		(connect_pads
			(clearance 0)
		)
		(min_thickness 0.25)
		(keepout
			(tracks not_allowed)
			(vias allowed)
			(pads allowed)
			(copperpour not_allowed)
			(footprints allowed)
		)
		(placement
			(enabled no)
			(sheetname "")
		)
		(fill
			(thermal_gap 0.5)
			(thermal_bridge_width 0.5)
			(island_removal_mode 0)
		)
		(polygon
			(pts
				(xy 7.830566 -417.248086) (xy 7.830566 -417.27247)
				(arc
					(start 7.830058 -417.272724)
					(mid 7.804843 -417.458252)
					(end 7.741412 -417.63442)
				)
				(arc
					(start 7.741412 -417.63442)
					(mid 7.356644 -418.069071)
					(end 7.636002 -417.560252)
				)
				(arc
					(start 7.636002 -417.560252)
					(mid 7.686494 -417.406875)
					(end 7.703566 -417.246308)
				)
				(xy 7.537958 -417.243768)
				(arc
					(start 7.53364 -417.243768)
					(mid 6.93852 -417.821999)
					(end 7.516622 -418.417248)
				)
				(arc
					(start 8.380222 -418.429694)
					(mid 8.975344 -417.851336)
					(end 8.396986 -417.256214)
				)
				(arc
					(start 8.167624 -417.252912)
					(mid 8.203729 -417.419251)
					(end 8.269478 -417.576254)
				)
				(arc
					(start 8.269478 -417.576254)
					(mid 8.562919 -418.077016)
					(end 8.166608 -417.652962)
				)
				(arc
					(start 8.166608 -417.652962)
					(mid 8.082922 -417.45843)
					(end 8.039608 -417.251134)
				)
			)
		)
	)
	(zone
		(layer "B.Cu")
		(hatch none 0.5)
		(connect_pads
			(clearance 0)
		)
		(min_thickness 0.25)
		(keepout
			(tracks allowed)
			(vias allowed)
			(pads allowed)
			(copperpour allowed)
			(footprints not_allowed)
		)
		(placement
			(enabled no)
			(sheetname "")
		)
		(fill
			(thermal_gap 0.5)
			(thermal_bridge_width 0.5)
			(island_removal_mode 0)
		)
		(polygon
			(pts
				(arc
					(start 252.499876 -174.999904)
					(mid 256.499868 -170.999912)
					(end 252.499876 -166.99992)
				)
				(arc
					(start 252.499876 -166.99992)
					(mid 248.499884 -170.999912)
					(end 252.499876 -174.999904)
				)
			)
		)
	)
	(zone
		(layer "B.Cu")
		(hatch none 0.5)
		(connect_pads
			(clearance 0)
		)
		(min_thickness 0.25)
		(keepout
			(tracks allowed)
			(vias allowed)
			(pads allowed)
			(copperpour allowed)
			(footprints not_allowed)
		)
		(placement
			(enabled no)
			(sheetname "")
		)
		(fill
			(thermal_gap 0.5)
			(thermal_bridge_width 0.5)
			(island_removal_mode 0)
		)
		(polygon
			(pts
				(arc
					(start 252.499876 -275.500084)
					(mid 256.499868 -271.500092)
					(end 252.499876 -267.5001)
				)
				(arc
					(start 252.499876 -267.5001)
					(mid 248.499884 -271.500092)
					(end 252.499876 -275.500084)
				)
			)
		)
	)
	(zone
		(layer "B.Cu")
		(hatch none 0.5)
		(connect_pads
			(clearance 0.5)
		)
		(min_thickness 0.25)
		(fill
			(thermal_gap 0.5)
			(thermal_bridge_width 0.5)
			(island_removal_mode 0)
		)
		(polygon
			(pts
				(xy 236.727746 -18.4277) (xy 236.727746 -20.7137) (xy 237.870746 -21.8567) (xy 242.188746 -21.8567)
				(xy 242.442746 -21.6027) (xy 242.442746 -8.6487) (xy 241.553746 -7.7597) (xy 235.457746 -7.7597)
				(xy 234.949746 -8.2677) (xy 234.949746 -16.6497)
			)
		)
	)
	(zone
		(layer "B.Cu")
		(hatch none 0.5)
		(connect_pads
			(clearance 0)
		)
		(min_thickness 0.25)
		(keepout
			(tracks allowed)
			(vias allowed)
			(pads allowed)
			(copperpour allowed)
			(footprints not_allowed)
		)
		(placement
			(enabled no)
			(sheetname "")
		)
		(fill
			(thermal_gap 0.5)
			(thermal_bridge_width 0.5)
			(island_removal_mode 0)
		)
		(polygon
			(pts
				(arc
					(start 7.500112 -82.63001)
					(mid 11.500104 -78.630018)
					(end 7.500112 -74.630026)
				)
				(arc
					(start 7.500112 -74.630026)
					(mid 3.50012 -78.630018)
					(end 7.500112 -82.63001)
				)
			)
		)
	)
	(zone
		(layer "B.Cu")
		(hatch none 0.5)
		(connect_pads
			(clearance 0)
		)
		(min_thickness 0.25)
		(keepout
			(tracks not_allowed)
			(vias allowed)
			(pads allowed)
			(copperpour not_allowed)
			(footprints allowed)
		)
		(placement
			(enabled no)
			(sheetname "")
		)
		(fill
			(thermal_gap 0.5)
			(thermal_bridge_width 0.5)
			(island_removal_mode 0)
		)
		(polygon
			(pts
				(arc
					(start 7.491984 -367.574322)
					(mid 7.567208 -367.468885)
					(end 7.603998 -367.344706)
				)
				(arc
					(start 7.312914 -367.331752)
					(mid 6.753606 -367.843308)
					(end 7.265162 -368.402616)
				)
				(arc
					(start 8.127746 -368.441224)
					(mid 8.687314 -367.929795)
					(end 8.175752 -367.37036)
				)
				(xy 8.064246 -367.36528)
				(arc
					(start 8.064246 -367.541048)
					(mid 8.066232 -367.583141)
					(end 8.07212 -367.624868)
				)
				(arc
					(start 8.07212 -367.624868)
					(mid 8.29219 -368.161996)
					(end 7.956296 -367.688622)
				)
				(arc
					(start 7.956296 -367.688622)
					(mid 7.943843 -367.628786)
					(end 7.937754 -367.567972)
				)
				(xy 7.937246 -367.567464) (xy 7.937246 -367.359692)
				(arc
					(start 7.731252 -367.350548)
					(mid 7.689164 -367.507978)
					(end 7.600442 -367.64468)
				)
				(xy 7.600442 -367.645696) (xy 7.5819 -367.664238)
				(arc
					(start 7.535672 -367.710466)
					(mid 7.082412 -368.07381)
					(end 7.445756 -367.62055)
				)
			)
		)
	)
	(zone
		(layer "B.Cu")
		(hatch none 0.5)
		(connect_pads
			(clearance 0)
		)
		(min_thickness 0.25)
		(keepout
			(tracks allowed)
			(vias allowed)
			(pads allowed)
			(copperpour allowed)
			(footprints not_allowed)
		)
		(placement
			(enabled no)
			(sheetname "")
		)
		(fill
			(thermal_gap 0.5)
			(thermal_bridge_width 0.5)
			(island_removal_mode 0)
		)
		(polygon
			(pts
				(arc
					(start 69.000116 -174.999904)
					(mid 73.000108 -170.999912)
					(end 69.000116 -166.99992)
				)
				(arc
					(start 69.000116 -166.99992)
					(mid 65.000124 -170.999912)
					(end 69.000116 -174.999904)
				)
			)
		)
	)
	(zone
		(layer "B.Cu")
		(hatch none 0.5)
		(connect_pads
			(clearance 0)
		)
		(min_thickness 0.25)
		(keepout
			(tracks not_allowed)
			(vias allowed)
			(pads allowed)
			(copperpour not_allowed)
			(footprints allowed)
		)
		(placement
			(enabled no)
			(sheetname "")
		)
		(fill
			(thermal_gap 0.5)
			(thermal_bridge_width 0.5)
			(island_removal_mode 0)
		)
		(polygon
			(pts
				(arc
					(start 29.968444 -31.997396)
					(mid 29.432631 -31.461202)
					(end 28.896564 -31.997142)
				)
				(xy 28.896564 -32.261048) (xy 29.011626 -32.261048)
				(arc
					(start 29.015436 -32.261048)
					(mid 29.12281 -32.245041)
					(end 29.220922 -32.198564)
				)
				(arc
					(start 29.220922 -32.198564)
					(mid 29.59419 -31.754231)
					(end 29.327602 -32.269684)
				)
				(arc
					(start 29.327602 -32.269684)
					(mid 29.193183 -32.348483)
					(end 29.040836 -32.38119)
				)
				(xy 29.040328 -32.381952) (xy 29.026612 -32.381952) (xy 29.015436 -32.381952) (xy 29.011626 -32.381952)
				(xy 28.896564 -32.381952) (xy 28.896564 -32.591248) (xy 29.045154 -32.591248) (xy 29.048964 -32.591248)
				(xy 29.056584 -32.591248) (xy 29.073856 -32.591248)
				(arc
					(start 29.07538 -32.592772)
					(mid 29.093944 -32.59571)
					(end 29.11221 -32.600138)
				)
				(xy 29.114242 -32.599376) (xy 29.130244 -32.606234) (xy 29.137102 -32.608774) (xy 29.140912 -32.610552)
				(xy 29.167074 -32.621474) (xy 29.17063 -32.622744) (xy 29.181044 -32.627316) (xy 29.193744 -32.63265)
				(arc
					(start 29.193998 -32.633412)
					(mid 29.241904 -32.660937)
					(end 29.285692 -32.694626)
				)
				(xy 29.286708 -32.694626) (xy 29.29763 -32.705294) (xy 29.304488 -32.711898) (xy 29.307282 -32.714946)
				(arc
					(start 29.34589 -32.753808)
					(mid 29.576799 -33.286593)
					(end 29.237178 -32.81553)
				)
				(xy 29.221938 -32.80029)
				(arc
					(start 29.219144 -32.79775)
					(mid 29.174885 -32.761466)
					(end 29.124402 -32.734504)
				)
				(xy 29.120592 -32.732726) (xy 29.09443 -32.721804)
				(arc
					(start 29.090874 -32.720534)
					(mid 29.070334 -32.714268)
					(end 29.048964 -32.712152)
				)
				(xy 29.045154 -32.712152) (xy 28.896564 -32.712152)
				(arc
					(start 28.896564 -33.0327)
					(mid 29.432504 -33.56864)
					(end 29.968444 -33.0327)
				)
			)
		)
	)
	(zone
		(layer "B.Cu")
		(hatch none 0.5)
		(connect_pads
			(clearance 0)
		)
		(min_thickness 0.25)
		(keepout
			(tracks not_allowed)
			(vias allowed)
			(pads allowed)
			(copperpour not_allowed)
			(footprints allowed)
		)
		(placement
			(enabled no)
			(sheetname "")
		)
		(fill
			(thermal_gap 0.5)
			(thermal_bridge_width 0.5)
			(island_removal_mode 0)
		)
		(polygon
			(pts
				(arc
					(start 7.374382 -165.563804)
					(mid 6.757924 -165.013894)
					(end 6.208014 -165.630352)
				)
				(xy 6.205474 -165.630606) (xy 6.272022 -166.797228)
				(arc
					(start 6.274562 -166.796974)
					(mid 6.89102 -167.346884)
					(end 7.44093 -166.730426)
				)
				(xy 7.44347 -166.730172) (xy 7.417054 -166.2684)
				(arc
					(start 7.107428 -166.2684)
					(mid 7.06534 -166.276772)
					(end 7.029704 -166.300658)
				)
				(arc
					(start 7.029704 -166.300658)
					(mid 6.967304 -166.38367)
					(end 6.93039 -166.480744)
				)
				(arc
					(start 6.93039 -166.480744)
					(mid 6.848772 -167.055765)
					(end 6.801612 -166.476934)
				)
				(arc
					(start 6.801612 -166.476934)
					(mid 6.850169 -166.333185)
					(end 6.939788 -166.210742)
				)
				(arc
					(start 6.939788 -166.210742)
					(mid 7.003954 -166.165207)
					(end 7.079488 -166.143178)
				)
				(xy 7.081012 -166.1414) (xy 7.409942 -166.1414)
				(arc
					(start 7.398258 -165.936168)
					(mid 7.184099 -165.899416)
					(end 6.982714 -165.817804)
				)
				(arc
					(start 6.982714 -165.817804)
					(mid 6.555425 -165.424952)
					(end 7.05866 -165.714172)
				)
				(arc
					(start 7.05866 -165.714172)
					(mid 7.220131 -165.777666)
					(end 7.390892 -165.808406)
				)
				(xy 7.376922 -165.563804) (xy 7.376668 -165.563804)
			)
		)
	)
	(zone
		(layer "B.Cu")
		(hatch none 0.5)
		(connect_pads
			(clearance 0)
		)
		(min_thickness 0.25)
		(keepout
			(tracks allowed)
			(vias allowed)
			(pads allowed)
			(copperpour allowed)
			(footprints not_allowed)
		)
		(placement
			(enabled no)
			(sheetname "")
		)
		(fill
			(thermal_gap 0.5)
			(thermal_bridge_width 0.5)
			(island_removal_mode 0)
		)
		(polygon
			(pts
				(arc
					(start 69.000116 -484.000048)
					(mid 73.000108 -480.000056)
					(end 69.000116 -476.000064)
				)
				(arc
					(start 69.000116 -476.000064)
					(mid 65.000124 -480.000056)
					(end 69.000116 -484.000048)
				)
			)
		)
	)
	(zone
		(layer "B.Cu")
		(hatch none 0.5)
		(connect_pads
			(clearance 0.5)
		)
		(min_thickness 0.25)
		(fill
			(thermal_gap 0.5)
			(thermal_bridge_width 0.5)
			(island_removal_mode 0)
		)
		(polygon
			(pts
				(xy 27.177746 -10.5537) (xy 27.177746 -17.4117) (xy 28.193746 -18.4277) (xy 40.0304 -18.4277) (xy 40.0304 -18.4404)
				(xy 40.0431 -18.4277) (xy 40.5257 -18.4277) (xy 51.307746 -18.4277) (xy 51.561746 -18.1737) (xy 51.561746 -14.8717)
				(xy 46.481746 -9.7917) (xy 27.939746 -9.7917)
			)
		)
	)
	(zone
		(layer "B.Cu")
		(hatch none 0.5)
		(connect_pads
			(clearance 0)
		)
		(min_thickness 0.25)
		(keepout
			(tracks not_allowed)
			(vias allowed)
			(pads allowed)
			(copperpour not_allowed)
			(footprints allowed)
		)
		(placement
			(enabled no)
			(sheetname "")
		)
		(fill
			(thermal_gap 0.5)
			(thermal_bridge_width 0.5)
			(island_removal_mode 0)
		)
		(polygon
			(pts
				(arc
					(start 7.314184 -117.510814)
					(mid 6.725539 -116.926106)
					(end 6.140704 -117.514624)
				)
				(arc
					(start 6.14172 -117.761258)
					(mid 6.311347 -117.722264)
					(end 6.468872 -117.648228)
				)
				(arc
					(start 6.468872 -117.648228)
					(mid 6.949903 -117.323466)
					(end 6.55193 -117.746018)
				)
				(arc
					(start 6.55193 -117.746018)
					(mid 6.355287 -117.841408)
					(end 6.141974 -117.88902)
				)
				(arc
					(start 6.142736 -118.093236)
					(mid 6.339884 -118.058788)
					(end 6.528054 -117.99062)
				)
				(arc
					(start 6.528054 -117.99062)
					(mid 6.695473 -117.995581)
					(end 6.792214 -118.132352)
				)
				(xy 6.794246 -118.134384)
				(arc
					(start 6.794246 -118.142512)
					(mid 6.731539 -118.71953)
					(end 6.664706 -118.14302)
				)
				(arc
					(start 6.664706 -118.14302)
					(mid 6.631478 -118.105477)
					(end 6.581394 -118.105936)
				)
				(arc
					(start 6.581394 -118.105936)
					(mid 6.367455 -118.182866)
					(end 6.143244 -118.22049)
				)
				(arc
					(start 6.144006 -118.429532)
					(mid 6.732778 -119.01424)
					(end 7.317486 -118.425468)
				)
				(xy 7.314184 -117.514624)
			)
		)
	)
	(zone
		(layer "B.Cu")
		(hatch none 0.5)
		(connect_pads
			(clearance 0)
		)
		(min_thickness 0.25)
		(keepout
			(tracks allowed)
			(vias allowed)
			(pads allowed)
			(copperpour allowed)
			(footprints not_allowed)
		)
		(placement
			(enabled no)
			(sheetname "")
		)
		(fill
			(thermal_gap 0.5)
			(thermal_bridge_width 0.5)
			(island_removal_mode 0)
		)
		(polygon
			(pts
				(arc
					(start 4.500118 -487.400092)
					(mid 8.50011 -483.4001)
					(end 4.500118 -479.400108)
				)
				(arc
					(start 4.500118 -479.400108)
					(mid 0.500126 -483.4001)
					(end 4.500118 -487.400092)
				)
			)
		)
	)
	(zone
		(layer "B.Cu")
		(hatch none 0.5)
		(connect_pads
			(clearance 0)
		)
		(min_thickness 0.25)
		(keepout
			(tracks not_allowed)
			(vias allowed)
			(pads allowed)
			(copperpour not_allowed)
			(footprints allowed)
		)
		(placement
			(enabled no)
			(sheetname "")
		)
		(fill
			(thermal_gap 0.5)
			(thermal_bridge_width 0.5)
			(island_removal_mode 0)
		)
		(polygon
			(pts
				(arc
					(start 6.92785 -112.222026)
					(mid 7.121516 -112.129334)
					(end 7.331456 -112.084358)
				)
				(arc
					(start 7.324852 -111.87557)
					(mid 7.132063 -111.848507)
					(end 6.946392 -111.789972)
				)
				(arc
					(start 6.946392 -111.789972)
					(mid 6.474073 -111.452229)
					(end 7.008876 -111.678212)
				)
				(arc
					(start 7.008876 -111.678212)
					(mid 7.162149 -111.725125)
					(end 7.320788 -111.748062)
				)
				(arc
					(start 7.315454 -111.576612)
					(mid 6.710553 -111.008664)
					(end 6.142482 -111.613442)
				)
				(arc
					(start 6.16966 -112.476788)
					(mid 6.774688 -113.044732)
					(end 7.342632 -112.439704)
				)
				(arc
					(start 7.33552 -112.211612)
					(mid 7.168254 -112.247586)
					(end 7.012686 -112.3188)
				)
				(arc
					(start 7.012686 -112.3188)
					(mid 6.53664 -112.650795)
					(end 6.92785 -112.222026)
				)
			)
		)
	)
	(zone
		(layer "B.Cu")
		(hatch none 0.5)
		(connect_pads
			(clearance 0)
		)
		(min_thickness 0.25)
		(keepout
			(tracks not_allowed)
			(vias allowed)
			(pads allowed)
			(copperpour not_allowed)
			(footprints allowed)
		)
		(placement
			(enabled no)
			(sheetname "")
		)
		(fill
			(thermal_gap 0.5)
			(thermal_bridge_width 0.5)
			(island_removal_mode 0)
		)
		(polygon
			(pts
				(xy 8.299196 -375.854214)
				(arc
					(start 8.190484 -375.865644)
					(mid 8.161409 -376.06117)
					(end 8.091678 -376.246136)
				)
				(arc
					(start 8.091678 -376.246136)
					(mid 7.703968 -376.67845)
					(end 7.98703 -376.17146)
				)
				(arc
					(start 7.98703 -376.17146)
					(mid 8.038566 -376.028979)
					(end 8.062468 -375.87936)
				)
				(xy 7.817104 -375.905268)
				(arc
					(start 7.817358 -375.907808)
					(mid 7.340854 -376.497088)
					(end 7.930134 -376.973592)
				)
				(xy 7.930388 -376.976132) (xy 8.810498 -376.882914) (xy 8.810752 -376.88266)
				(arc
					(start 8.810498 -376.880374)
					(mid 9.287002 -376.291094)
					(end 8.697722 -375.81459)
				)
				(xy 8.697468 -375.81205)
				(arc
					(start 8.535162 -375.829322)
					(mid 8.57046 -375.960812)
					(end 8.626602 -376.084846)
				)
				(arc
					(start 8.626602 -376.084846)
					(mid 8.935352 -376.576225)
					(end 8.526018 -376.164856)
				)
				(arc
					(start 8.526018 -376.164856)
					(mid 8.452729 -376.008977)
					(end 8.408416 -375.84253)
				)
			)
		)
	)
	(zone
		(layer "B.Cu")
		(hatch none 0.5)
		(connect_pads
			(clearance 0)
		)
		(min_thickness 0.25)
		(keepout
			(tracks not_allowed)
			(vias allowed)
			(pads allowed)
			(copperpour not_allowed)
			(footprints allowed)
		)
		(placement
			(enabled no)
			(sheetname "")
		)
		(fill
			(thermal_gap 0.5)
			(thermal_bridge_width 0.5)
			(island_removal_mode 0)
		)
		(polygon
			(pts
				(arc
					(start 9.857486 -131.515104)
					(mid 9.270873 -130.92811)
					(end 8.684006 -131.51485)
				)
				(arc
					(start 8.684006 -132.4737)
					(mid 9.270746 -133.06044)
					(end 9.857486 -132.4737)
				)
				(xy 9.857486 -132.31876)
				(arc
					(start 9.641586 -132.10286)
					(mid 9.559544 -132.068877)
					(end 9.477502 -132.10286)
				)
				(arc
					(start 9.477502 -132.10286)
					(mid 9.433274 -132.153648)
					(end 9.396476 -132.210048)
				)
				(arc
					(start 9.396476 -132.210048)
					(mid 9.207532 -132.758874)
					(end 9.268206 -132.1816)
				)
				(arc
					(start 9.268206 -132.1816)
					(mid 9.320773 -132.09223)
					(end 9.387586 -132.012944)
				)
				(arc
					(start 9.387586 -132.012944)
					(mid 9.545601 -131.942117)
					(end 9.710674 -131.994402)
				)
				(xy 9.71296 -131.994402) (xy 9.857486 -132.138928) (xy 9.857486 -131.8514)
				(arc
					(start 9.806432 -131.800092)
					(mid 9.682338 -131.699856)
					(end 9.539986 -131.62788)
				)
				(arc
					(start 9.539986 -131.62788)
					(mid 8.983085 -131.463039)
					(end 9.562592 -131.50088)
				)
				(arc
					(start 9.562592 -131.50088)
					(mid 9.718485 -131.572971)
					(end 9.857486 -131.673854)
				)
			)
		)
	)
	(zone
		(net "P12V")
		(layer "B.Cu")
		(hatch none 0.5)
		(connect_pads
			(clearance 0.5)
		)
		(min_thickness 0.25)
		(fill yes
			(thermal_gap 0.5)
			(thermal_bridge_width 0.5)
			(island_removal_mode 0)
		)
		(polygon
			(pts
				(xy 257.7338 -363.5502) (xy 241.8588 -363.5502) (xy 240.792 -364.617) (xy 240.792 -382.7272) (xy 241.8588 -383.794)
				(xy 257.9116 -383.794) (xy 258.1148 -383.5908) (xy 258.1148 -363.9312)
			)
		)
	)
	(zone
		(layer "B.Cu")
		(hatch none 0.5)
		(connect_pads
			(clearance 0)
		)
		(min_thickness 0.25)
		(keepout
			(tracks allowed)
			(vias allowed)
			(pads allowed)
			(copperpour allowed)
			(footprints not_allowed)
		)
		(placement
			(enabled no)
			(sheetname "")
		)
		(fill
			(thermal_gap 0.5)
			(thermal_bridge_width 0.5)
			(island_removal_mode 0)
		)
		(polygon
			(pts
				(arc
					(start 4.500118 -479.400108)
					(mid 0.500126 -483.4001)
					(end 4.500118 -487.400092)
				)
				(arc
					(start 4.500118 -487.400092)
					(mid 8.50011 -483.4001)
					(end 4.500118 -479.400108)
				)
			)
		)
	)
	(zone
		(layer "B.Cu")
		(hatch none 0.5)
		(connect_pads
			(clearance 0)
		)
		(min_thickness 0.25)
		(keepout
			(tracks not_allowed)
			(vias allowed)
			(pads allowed)
			(copperpour not_allowed)
			(footprints allowed)
		)
		(placement
			(enabled no)
			(sheetname "")
		)
		(fill
			(thermal_gap 0.5)
			(thermal_bridge_width 0.5)
			(island_removal_mode 0)
		)
		(polygon
			(pts
				(arc
					(start 215.344756 -165.87724)
					(mid 214.865186 -166.111122)
					(end 214.773256 -166.6367)
				)
				(xy 215.097868 -166.6367)
				(arc
					(start 215.09863 -166.6367)
					(mid 215.513484 -166.233555)
					(end 215.22563 -166.735252)
				)
				(arc
					(start 215.22563 -166.735252)
					(mid 215.17678 -166.75322)
					(end 215.125554 -166.76243)
				)
				(xy 215.124284 -166.7637)
				(arc
					(start 214.829644 -166.7637)
					(mid 214.918135 -166.877839)
					(end 215.031828 -166.9669)
				)
				(arc
					(start 215.297766 -166.9669)
					(mid 215.596078 -166.907562)
					(end 215.848946 -166.738554)
				)
				(arc
					(start 215.951054 -166.636446)
					(mid 216.404314 -166.273102)
					(end 216.04097 -166.726362)
				)
				(xy 215.92032 -166.847012)
				(arc
					(start 215.919558 -166.847012)
					(mid 215.752038 -166.971839)
					(end 215.560402 -167.055038)
				)
				(arc
					(start 216.186766 -167.066468)
					(mid 216.78443 -166.490523)
					(end 216.208356 -165.892988)
				)
			)
		)
	)
	(zone
		(layer "B.Cu")
		(hatch none 0.5)
		(connect_pads
			(clearance 0)
		)
		(min_thickness 0.25)
		(keepout
			(tracks allowed)
			(vias allowed)
			(pads allowed)
			(copperpour allowed)
			(footprints not_allowed)
		)
		(placement
			(enabled no)
			(sheetname "")
		)
		(fill
			(thermal_gap 0.5)
			(thermal_bridge_width 0.5)
			(island_removal_mode 0)
		)
		(polygon
			(pts
				(arc
					(start 32.999934 -8.50011)
					(mid 36.999926 -4.500118)
					(end 32.999934 -0.500126)
				)
				(arc
					(start 32.999934 -0.500126)
					(mid 28.999942 -4.500118)
					(end 32.999934 -8.50011)
				)
			)
		)
	)
	(zone
		(layer "B.Cu")
		(hatch none 0.5)
		(connect_pads
			(clearance 0)
		)
		(min_thickness 0.25)
		(keepout
			(tracks not_allowed)
			(vias allowed)
			(pads allowed)
			(copperpour not_allowed)
			(footprints allowed)
		)
		(placement
			(enabled no)
			(sheetname "")
		)
		(fill
			(thermal_gap 0.5)
			(thermal_bridge_width 0.5)
			(island_removal_mode 0)
		)
		(polygon
			(pts
				(xy 7.428992 -423.51579) (xy 7.423912 -423.515536)
				(arc
					(start 7.423658 -423.518076)
					(mid 6.856476 -424.020742)
					(end 7.359142 -424.587924)
				)
				(xy 7.358888 -424.590464) (xy 8.22071 -424.642788) (xy 8.220964 -424.642534)
				(arc
					(start 8.221218 -424.640248)
					(mid 8.7884 -424.137582)
					(end 8.285734 -423.5704)
				)
				(xy 8.285988 -423.56786) (xy 7.982458 -423.549318) (xy 7.98449 -423.570146) (xy 7.985252 -423.570908)
				(xy 7.985252 -423.585894) (xy 7.985252 -423.5958) (xy 7.985252 -423.596054)
				(arc
					(start 7.985252 -423.596308)
					(mid 8.013505 -423.739239)
					(end 8.093964 -423.860722)
				)
				(arc
					(start 8.093964 -423.860722)
					(mid 8.460114 -424.312216)
					(end 8.00862 -423.946066)
				)
				(xy 8.00227 -423.939462) (xy 7.992364 -423.92981)
				(arc
					(start 7.992364 -423.929048)
					(mid 7.902194 -423.786361)
					(end 7.86511 -423.621708)
				)
				(xy 7.864348 -423.6212) (xy 7.864348 -423.607484) (xy 7.864348 -423.596308) (xy 7.864348 -423.596054)
				(arc
					(start 7.864348 -423.5958)
					(mid 7.86304 -423.568741)
					(end 7.859014 -423.541952)
				)
				(arc
					(start 7.598664 -423.526204)
					(mid 7.661586 -423.704154)
					(end 7.634478 -423.890948)
				)
				(arc
					(start 7.634478 -423.890948)
					(mid 7.191918 -424.266436)
					(end 7.536688 -423.799508)
				)
				(arc
					(start 7.536688 -423.799508)
					(mid 7.531465 -423.665162)
					(end 7.462774 -423.549572)
				)
				(xy 7.45998 -423.546778)
			)
		)
	)
	(zone
		(net "GND")
		(layer "B.Cu")
		(hatch none 0.5)
		(connect_pads
			(clearance 0.5)
		)
		(min_thickness 0.25)
		(fill yes
			(thermal_gap 0.5)
			(thermal_bridge_width 0.5)
			(island_removal_mode 0)
		)
		(polygon
			(pts
				(xy 210.249008 -166.290244) (xy 72.0344 -111.0996) (xy 70.0278 -110.6678) (xy 43.1038 -110.623096)
				(xy 43.1038 -113.877344) (xy 45.9994 -116.1542) (xy 52.016152 -118.0846) (xy 52.3494 -118.0846)
				(xy 52.4764 -118.2116) (xy 52.4764 -118.2624) (xy 52.2732 -118.2624) (xy 49.8094 -120.7262) (xy 49.8094 -121.4374)
				(xy 49.4284 -121.8184) (xy 48.1965 -120.5865) (xy 48.133 -120.65) (xy 46.3296 -120.65) (xy 44.55922 -118.87962)
				(xy 11.00836 -118.87962) (xy 9.305036 -117.176296) (xy 8.692896 -117.176296) (xy 7.492746 -118.3767)
				(xy 7.492746 -124.7267) (xy 8.254746 -125.4887) (xy 10.667746 -125.4887) (xy 20.573746 -135.3947)
				(xy 39.750746 -158.8897) (xy 39.750746 -163.4617) (xy 17.144746 -135.1407) (xy 12.191746 -130.0607)
				(xy 11.302746 -129.8067) (xy 9.575546 -129.8067) (xy 9.423146 -129.9591) (xy 9.423146 -130.8481)
				(xy 10.159746 -131.5847) (xy 10.667746 -132.2197) (xy 21.716746 -147.2057) (xy 39.750746 -176.9237)
				(xy 39.750746 -178.8668) (xy 39.9796 -178.8668) (xy 42.164 -181.0512) (xy 42.164 -182.3974) (xy 40.9194 -182.3974)
				(xy 39.7764 -181.2544) (xy 39.7764 -181.102) (xy 39.750746 -181.102) (xy 39.750746 -194.5767) (xy 50.139346 -204.9653)
				(xy 50.139346 -205.079346) (xy 50.418746 -205.358746) (xy 50.418746 -299.6057) (xy 44.449746 -305.5747)
				(xy 44.449746 -352.0567) (xy 45.084746 -352.6917) (xy 45.084746 -364.5027) (xy 30.479746 -379.1077)
				(xy 30.479746 -411.8737) (xy 29.463746 -412.8897) (xy 26.415746 -412.8897) (xy 25.653746 -412.1277)
				(xy 18.668746 -412.1277) (xy 16.509746 -414.2867) (xy 16.509746 -430.0347) (xy 13.969746 -432.5747)
				(xy 1.269746 -432.5747) (xy 0.888746 -432.9557) (xy 0.888746 -445.5795) (xy 1.345946 -446.0367)
				(xy 15.493746 -446.0367) (xy 20.065746 -441.4647) (xy 20.065746 -432.5747) (xy 25.272746 -427.3677)
				(xy 25.272746 -420.5097) (xy 26.161746 -419.6207) (xy 29.717746 -419.6207) (xy 39.242746 -429.1457)
				(xy 39.242746 -457.5937) (xy 39.230046 -457.6064) (xy 39.2938 -457.6064) (xy 39.2938 -459.0796)
				(xy 38.6334 -459.74) (xy 38.6334 -476.3008) (xy 38.3032 -476.631) (xy 30.7086 -476.631) (xy 30.3022 -476.2246)
				(xy 30.3022 -469.0364) (xy 30.028896 -468.763096) (xy 25.025096 -468.763096) (xy 25.018746 -468.7697)
				(xy 1.142746 -468.7697) (xy 0.812546 -469.0999) (xy 0.812546 -505.002546) (xy 1.016 -505.206) (xy 261.366 -505.206)
				(xy 261.62 -504.952) (xy 261.619746 -504.952) (xy 261.619746 -443.2427) (xy 261.62 -443.242446)
				(xy 261.62 -430.911) (xy 257.4163 -426.7073) (xy 257.4163 -425.5389) (xy 257.2258 -425.3484) (xy 247.777 -425.3484)
				(xy 246.9896 -424.561) (xy 246.9896 -424.053) (xy 247.4976 -423.545) (xy 257.937 -423.545) (xy 258.064 -423.418)
				(xy 258.064 -422.8846) (xy 257.9624 -422.783) (xy 252.222 -422.783) (xy 251.841 -422.402) (xy 251.841 -421.386)
				(xy 252.222 -421.005) (xy 257.8862 -421.005) (xy 258.0386 -420.8526) (xy 258.0386 -420.4462) (xy 257.8354 -420.243)
				(xy 247.7516 -420.243) (xy 246.9896 -419.481) (xy 246.9896 -412.5214) (xy 247.396 -412.115) (xy 257.7338 -412.115)
				(xy 257.9116 -411.9372) (xy 257.9116 -411.6832) (xy 257.5814 -411.353) (xy 250.952 -411.353) (xy 250.0884 -410.4894)
				(xy 250.0884 -409.3972) (xy 250.8504 -408.6352) (xy 257.556 -408.6352) (xy 258.0894 -408.1018) (xy 258.0894 -384.7338)
				(xy 257.81 -384.4544) (xy 241.3254 -384.4544) (xy 239.903 -383.032) (xy 239.903 -364.363) (xy 241.4016 -362.8644)
				(xy 258.4196 -362.8644) (xy 259.1308 -362.1532) (xy 261.1628 -362.1532) (xy 261.62 -361.696) (xy 261.62 -322.707)
				(xy 261.619746 -322.707) (xy 261.619746 -1.016) (xy 261.365746 -0.762) (xy 1.015746 -0.762) (xy 0.889 -0.888746)
				(xy 0.889 -42.0878) (xy 1.4224 -42.6212) (xy 7.5184 -42.6212) (xy 8.8138 -43.9166) (xy 8.8138 -51.7398)
				(xy 8.4582 -52.0954) (xy 7.5692 -52.0954) (xy 7.1882 -52.4764) (xy 7.1882 -55.9562) (xy 6.5786 -56.5658)
				(xy 6.2992 -56.5658) (xy 5.5626 -57.3024) (xy 5.5626 -63.2968) (xy 5.1562 -63.7032) (xy 1.1938 -63.7032)
				(xy 0.889 -64.008) (xy 0.889 -89.916) (xy 0.88265 -89.92235) (xy 0.88265 -90.93835) (xy 2.921 -92.9767)
				(xy 20.624546 -92.9767) (xy 20.675346 -93.0275) (xy 20.675346 -96.1771) (xy 8.762746 -108.0897)
				(xy 8.762746 -109.4867) (xy 8.889746 -109.6137) (xy 17.271746 -109.6137) (xy 18.668746 -108.2167)
				(xy 21.462746 -108.2167) (xy 22.675596 -109.429804) (xy 22.6822 -109.4232) (xy 70.1802 -109.4232)
				(xy 71.1454 -109.474) (xy 72.2122 -109.8296) (xy 212.9028 -166.2176) (xy 214.4014 -166.2176) (xy 214.9856 -165.8874)
				(xy 216.5604 -165.862) (xy 216.5858 -165.8874) (xy 217.689938 -165.8874) (xy 219.2274 -164.0586)
				(xy 219.7354 -163.9062) (xy 222.3008 -163.9062) (xy 222.8342 -163.3728) (xy 223.4692 -163.3728)
				(xy 223.7994 -163.703) (xy 223.7994 -165.2524) (xy 223.4946 -165.5572) (xy 222.885 -165.5572) (xy 222.5802 -165.2524)
				(xy 222.5802 -165.0492) (xy 222.4786 -164.9476) (xy 219.71 -164.9476) (xy 216.5604 -168.0972) (xy 211.7598 -168.0972)
				(xy 211.6328 -167.9702) (xy 201.1934 -164.8206) (xy 201.0664 -164.1348) (xy 204.4954 -165.1254)
				(xy 209.810604 -166.728648)
			)
		)
		(polygon
			(pts
				(arc
					(start 16.72209 -90.080338)
					(mid 16.663073 -89.965131)
					(end 16.538956 -90.001344)
				)
				(arc
					(start 16.538956 -90.001344)
					(mid 16.433373 -90.14157)
					(end 16.315182 -90.271346)
				)
				(arc
					(start 13.783056 -92.803218)
					(mid 13.75919 -92.909252)
					(end 13.844778 -92.976192)
				)
				(xy 14.21892 -92.976192)
				(arc
					(start 16.246094 -90.949018)
					(mid 16.546261 -90.548736)
					(end 16.72209 -90.080338)
				)
			)
		)
		(polygon
			(pts
				(xy 27.20594 -412.890208) (xy 27.098752 -412.890208) (xy 27.098752 -419.620192) (xy 27.20594 -419.620192)
			)
		)
		(polygon
			(pts
				(xy 29.464 -496.951) (xy 28.321 -496.951) (xy 28.194 -497.078) (xy 28.321 -497.078) (xy 28.702 -497.459)
				(xy 28.702 -500.126) (xy 27.686 -501.142) (xy 27.813 -501.269) (xy 29.337 -501.269) (xy 29.337 -497.332)
				(xy 29.464 -497.205)
			)
		)
		(polygon
			(pts
				(arc
					(start 9.346438 -487.379772)
					(mid 9.283802 -487.28594)
					(end 9.17321 -487.30789)
				)
				(xy 7.747762 -488.733084) (xy 6.969252 -488.733084)
				(arc
					(start 6.962394 -488.73537)
					(mid 6.717363 -488.753231)
					(end 6.486652 -488.668822)
				)
				(xy 6.474206 -488.660948) (xy 6.408674 -488.660948) (xy 6.408674 -488.725972) (xy 5.078222 -490.056424)
				(arc
					(start 5.07492 -490.07014)
					(mid 5.047968 -490.153832)
					(end 5.01015 -490.233208)
				)
				(arc
					(start 5.01015 -490.233208)
					(mid 5.011052 -490.334349)
					(end 5.098796 -490.384592)
				)
				(xy 5.743194 -490.384592)
				(arc
					(start 5.755132 -490.377226)
					(mid 6.095746 -490.2827)
					(end 6.43636 -490.377226)
				)
				(xy 6.448298 -490.384592) (xy 6.677152 -490.384592) (xy 9.346438 -487.715052)
			)
		)
		(polygon
			(pts
				(xy 11.839194 -480.886008) (xy 11.647932 -480.886008)
				(arc
					(start 11.415776 -481.118164)
					(mid 11.39394 -481.228709)
					(end 11.487658 -481.291392)
				)
				(xy 12.147804 -481.291392)
				(arc
					(start 12.154662 -481.28936)
					(mid 12.903576 -481.8507)
					(end 12.154662 -482.41204)
				)
				(xy 12.147804 -482.410008) (xy 11.273536 -482.410008)
				(arc
					(start 11.08837 -482.59492)
					(mid 11.059235 -482.678185)
					(end 11.10615 -482.752908)
				)
				(arc
					(start 11.10615 -482.752908)
					(mid 11.326052 -483.003762)
					(end 11.373104 -483.33406)
				)
				(arc
					(start 11.373104 -483.33406)
					(mid 11.396697 -483.415084)
					(end 11.473434 -483.450392)
				)
				(xy 14.223238 -483.450392) (xy 14.858238 -484.085392)
				(arc
					(start 14.980666 -484.085392)
					(mid 14.933733 -484.116752)
					(end 14.944852 -484.172006)
				)
				(xy 15.360142 -484.587296) (xy 18.407888 -484.587296) (xy 19.303238 -485.482392) (xy 21.755608 -485.482392)
				(xy 21.717 -485.521) (xy 21.717 -485.775) (xy 22.86 -486.918) (xy 22.86 -494.411) (xy 21.59 -495.681)
				(xy 17.526 -495.681) (xy 14.351 -492.506) (xy 14.351 -492.379) (xy 14.097 -492.125) (xy 11.557 -492.125)
				(xy 11.303 -491.871) (xy 11.303 -489.077) (xy 10.795 -489.077) (xy 10.668 -489.204) (xy 10.668 -492.379)
				(xy 11.303 -493.014) (xy 13.208 -493.014) (xy 14.224 -494.03) (xy 14.224 -495.046) (xy 14.351 -495.173)
				(xy 14.351 -495.427) (xy 13.716 -496.062) (xy 13.716 -496.189) (xy 13.843 -496.316) (xy 23.241 -496.316)
				(xy 23.876 -496.951) (xy 25.527 -496.951) (xy 25.654 -496.824) (xy 25.654 -496.57) (xy 23.368 -494.284)
				(xy 23.368 -486.537) (xy 22.225 -485.394)
				(arc
					(start 21.929344 -485.394)
					(mid 22.023005 -485.331163)
					(end 22.000972 -485.220518)
				)
				(xy 21.978112 -485.197912) (xy 19.297904 -485.197912) (xy 18.415254 -484.315008) (xy 15.494254 -484.315008)
				(arc
					(start 15.235174 -484.055674)
					(mid 15.164549 -484.025907)
					(end 15.093188 -484.053896)
				)
				(arc
					(start 15.093188 -484.053896)
					(mid 15.12128 -483.982714)
					(end 15.091664 -483.912164)
				)
				(xy 13.537438 -482.358192) (xy 13.537438 -480.886008) (xy 12.544298 -480.886008)
				(arc
					(start 12.53236 -480.89312)
					(mid 12.191746 -480.987646)
					(end 11.851132 -480.89312)
				)
			)
		)
		(polygon
			(pts
				(arc
					(start 188.100716 -463.258408)
					(mid 188.111695 -463.203212)
					(end 188.064902 -463.171794)
				)
				(arc
					(start 181.24424 -463.171794)
					(mid 181.223749 -463.198166)
					(end 181.201822 -463.223356)
				)
				(xy 181.201822 -463.24393)
				(arc
					(start 181.217062 -463.258916)
					(mid 181.238482 -463.280847)
					(end 181.258718 -463.303874)
				)
				(xy 181.273958 -463.321908) (xy 188.036962 -463.321908)
			)
		)
		(polygon
			(pts
				(xy 44.522644 -126.098808) (xy 39.751254 -126.098808)
				(arc
					(start 39.751254 -126.910846)
					(mid 39.792107 -126.982503)
					(end 39.872666 -127.000254)
				)
				(arc
					(start 39.872666 -127.000254)
					(mid 40.665527 -127.6477)
					(end 39.872666 -128.295146)
				)
				(arc
					(start 39.872666 -128.295146)
					(mid 39.792095 -128.312882)
					(end 39.751254 -128.384554)
				)
				(xy 39.751254 -131.660392) (xy 40.259254 -131.660392)
				(arc
					(start 45.05833 -126.861316)
					(mid 45.083501 -126.759189)
					(end 45.004736 -126.689612)
				)
				(arc
					(start 45.004736 -126.689612)
					(mid 44.670801 -126.501274)
					(end 44.525438 -126.14656)
				)
			)
		)
		(polygon
			(pts
				(arc
					(start 17.703038 -90.998548)
					(mid 17.624836 -90.899679)
					(end 17.51076 -90.953082)
				)
				(arc
					(start 17.51076 -90.953082)
					(mid 17.276425 -91.341237)
					(end 16.982694 -91.686634)
				)
				(xy 16.913098 -91.755976)
				(arc
					(start 15.865856 -92.803218)
					(mid 15.84199 -92.909252)
					(end 15.927578 -92.976192)
				)
				(xy 16.311626 -92.976192)
				(arc
					(start 17.361154 -91.926664)
					(mid 17.614163 -91.547776)
					(end 17.703038 -91.10091)
				)
			)
		)
		(polygon
			(pts
				(arc
					(start 208.35366 -59.624468)
					(mid 208.293549 -59.656107)
					(end 208.318608 -59.71921)
				)
				(arc
					(start 208.318608 -59.71921)
					(mid 208.622854 -59.903141)
					(end 208.893664 -60.133484)
				)
				(arc
					(start 212.736176 -63.975488)
					(mid 212.843865 -64.066443)
					(end 212.965284 -64.138048)
				)
				(arc
					(start 212.965284 -64.138048)
					(mid 213.029791 -64.120259)
					(end 213.020656 -64.053974)
				)
				(arc
					(start 213.020656 -64.053974)
					(mid 212.992132 -64.028303)
					(end 212.964522 -64.00165)
				)
				(xy 212.739732 -63.777114)
				(arc
					(start 208.894172 -59.931554)
					(mid 208.644672 -59.741477)
					(end 208.35366 -59.624468)
				)
			)
		)
		(polygon
			(pts
				(arc
					(start 236.803692 -29.933392)
					(mid 236.772367 -29.886219)
					(end 236.716824 -29.897324)
				)
				(xy 235.994448 -30.6197) (xy 236.705394 -31.330392)
				(arc
					(start 237.604554 -31.330392)
					(mid 237.687421 -31.287577)
					(end 237.700312 -31.195264)
				)
				(arc
					(start 237.700312 -31.195264)
					(mid 237.667214 -31.016724)
					(end 237.690406 -30.836616)
				)
				(xy 237.692438 -30.829758)
				(arc
					(start 237.692438 -30.809692)
					(mid 237.649623 -30.726825)
					(end 237.55731 -30.713934)
				)
				(arc
					(start 237.55731 -30.713934)
					(mid 236.96075 -30.587157)
					(end 236.801406 -29.998416)
				)
				(xy 236.803438 -29.991558)
			)
		)
		(polygon
			(pts
				(arc
					(start 58.14695 -19.023584)
					(mid 58.157595 -18.916736)
					(end 58.066432 -18.860008)
				)
				(xy 57.836054 -18.860008) (xy 57.836054 -24.914352)
				(arc
					(start 56.673242 -26.077164)
					(mid 56.651406 -26.187709)
					(end 56.745124 -26.250392)
				)
				(xy 60.276994 -26.250392)
				(arc
					(start 60.50661 -26.480008)
					(mid 60.617155 -26.501844)
					(end 60.679838 -26.408126)
				)
				(xy 60.679838 -24.495252)
				(arc
					(start 60.672726 -24.483314)
					(mid 60.5782 -24.1427)
					(end 60.672726 -23.802086)
				)
				(xy 60.679838 -23.790148) (xy 60.679838 -22.240748) (xy 58.335672 -19.896582)
				(arc
					(start 58.329322 -19.893026)
					(mid 58.037977 -19.500272)
					(end 58.14695 -19.023584)
				)
			)
		)
	)
	(zone
		(layer "B.Cu")
		(hatch none 0.5)
		(connect_pads
			(clearance 0)
		)
		(min_thickness 0.25)
		(keepout
			(tracks not_allowed)
			(vias allowed)
			(pads allowed)
			(copperpour not_allowed)
			(footprints allowed)
		)
		(placement
			(enabled no)
			(sheetname "")
		)
		(fill
			(thermal_gap 0.5)
			(thermal_bridge_width 0.5)
			(island_removal_mode 0)
		)
		(polygon
			(pts
				(arc
					(start 8.288782 -383.87274)
					(mid 8.198468 -383.672009)
					(end 8.149336 -383.45745)
				)
				(xy 7.937246 -383.448052) (xy 7.937246 -383.50698)
				(arc
					(start 7.936738 -383.507234)
					(mid 7.915566 -383.669122)
					(end 7.863078 -383.823718)
				)
				(arc
					(start 7.863078 -383.823718)
					(mid 7.484723 -384.263924)
					(end 7.756144 -383.75082)
				)
				(arc
					(start 7.756144 -383.75082)
					(mid 7.796577 -383.61837)
					(end 7.810246 -383.480564)
				)
				(xy 7.810246 -383.442464)
				(arc
					(start 7.675626 -383.436368)
					(mid 7.063238 -383.996311)
					(end 7.623048 -384.608832)
				)
				(arc
					(start 8.485886 -384.647186)
					(mid 9.09828 -384.087116)
					(end 8.53821 -383.474722)
				)
				(arc
					(start 8.278368 -383.463038)
					(mid 8.31965 -383.634173)
					(end 8.390636 -383.79527)
				)
				(arc
					(start 8.390636 -383.79527)
					(mid 8.689191 -384.29355)
					(end 8.288782 -383.87274)
				)
			)
		)
	)
	(zone
		(net "P12V")
		(layer "B.Cu")
		(hatch none 0.5)
		(connect_pads
			(clearance 0.5)
		)
		(min_thickness 0.25)
		(fill yes
			(thermal_gap 0.5)
			(thermal_bridge_width 0.5)
			(island_removal_mode 0)
		)
		(polygon
			(pts
				(xy 1.397 -278.384) (xy 0.762254 -279.018746) (xy 0.762254 -300.736254) (xy 1.016 -300.99) (xy 8.382 -300.99)
				(xy 11.684 -300.99) (xy 13.335 -299.339) (xy 13.335 -279.908) (xy 12.0015 -278.5745) (xy 7.9375 -278.5745)
				(xy 7.747 -278.384)
			)
		)
	)
	(zone
		(layer "B.Cu")
		(hatch none 0.5)
		(connect_pads
			(clearance 0)
		)
		(min_thickness 0.25)
		(keepout
			(tracks allowed)
			(vias allowed)
			(pads allowed)
			(copperpour allowed)
			(footprints not_allowed)
		)
		(placement
			(enabled no)
			(sheetname "")
		)
		(fill
			(thermal_gap 0.5)
			(thermal_bridge_width 0.5)
			(island_removal_mode 0)
		)
		(polygon
			(pts
				(arc
					(start 252.499876 -484.000048)
					(mid 256.499868 -480.000056)
					(end 252.499876 -476.000064)
				)
				(arc
					(start 252.499876 -476.000064)
					(mid 248.499884 -480.000056)
					(end 252.499876 -484.000048)
				)
			)
		)
	)
	(zone
		(layer "B.Cu")
		(hatch none 0.5)
		(connect_pads
			(clearance 0)
		)
		(min_thickness 0.25)
		(keepout
			(tracks not_allowed)
			(vias allowed)
			(pads allowed)
			(copperpour not_allowed)
			(footprints allowed)
		)
		(placement
			(enabled no)
			(sheetname "")
		)
		(fill
			(thermal_gap 0.5)
			(thermal_bridge_width 0.5)
			(island_removal_mode 0)
		)
		(polygon
			(pts
				(arc
					(start 31.773876 -63.350394)
					(mid 31.25724 -62.70117)
					(end 30.608016 -63.217806)
				)
				(xy 30.605476 -63.217552) (xy 30.503368 -64.11595) (xy 30.503622 -64.116204)
				(arc
					(start 30.505908 -64.116458)
					(mid 31.022544 -64.765682)
					(end 31.671768 -64.249046)
				)
				(xy 31.674308 -64.2493) (xy 31.71317 -63.9064)
				(arc
					(start 31.263082 -63.9064)
					(mid 31.237362 -63.909428)
					(end 31.213044 -63.918338)
				)
				(arc
					(start 31.213044 -63.918338)
					(mid 31.038929 -64.47059)
					(end 31.060898 -63.891922)
				)
				(arc
					(start 31.060898 -63.891922)
					(mid 31.076679 -63.869479)
					(end 31.094934 -63.848996)
				)
				(arc
					(start 31.094934 -63.848996)
					(mid 31.159297 -63.803136)
					(end 31.235142 -63.780924)
				)
				(xy 31.236666 -63.7794) (xy 31.727648 -63.7794) (xy 31.750762 -63.5762) (xy 31.57093 -63.5762)
				(arc
					(start 31.570422 -63.575438)
					(mid 31.464807 -63.55807)
					(end 31.365444 -63.518288)
				)
				(arc
					(start 31.365444 -63.518288)
					(mid 30.968372 -63.095012)
					(end 31.45028 -63.418466)
				)
				(arc
					(start 31.45028 -63.418466)
					(mid 31.522217 -63.441476)
					(end 31.597346 -63.4492)
				)
				(xy 31.76524 -63.4492) (xy 31.776416 -63.350648)
			)
		)
	)
	(zone
		(layer "B.Cu")
		(hatch none 0.5)
		(connect_pads
			(clearance 0)
		)
		(min_thickness 0.25)
		(keepout
			(tracks not_allowed)
			(vias allowed)
			(pads allowed)
			(copperpour not_allowed)
			(footprints allowed)
		)
		(placement
			(enabled no)
			(sheetname "")
		)
		(fill
			(thermal_gap 0.5)
			(thermal_bridge_width 0.5)
			(island_removal_mode 0)
		)
		(polygon
			(pts
				(arc
					(start 7.173976 -158.237174)
					(mid 7.365112 -158.152508)
					(end 7.568946 -158.10611)
				)
				(arc
					(start 7.568946 -157.88513)
					(mid 7.365116 -157.83872)
					(end 7.173976 -157.754066)
				)
				(arc
					(start 7.173976 -157.754066)
					(mid 6.751338 -157.355958)
					(end 7.250938 -157.651704)
				)
				(arc
					(start 7.250938 -157.651704)
					(mid 7.405291 -157.718444)
					(end 7.568946 -157.757114)
				)
				(arc
					(start 7.568946 -157.531816)
					(mid 6.984873 -156.947362)
					(end 6.400546 -157.531562)
				)
				(arc
					(start 6.400546 -158.459678)
					(mid 6.984746 -159.043878)
					(end 7.568946 -158.459678)
				)
				(arc
					(start 7.568946 -158.234126)
					(mid 7.405302 -158.272828)
					(end 7.250938 -158.339536)
				)
				(arc
					(start 7.250938 -158.339536)
					(mid 6.75137 -158.635257)
					(end 7.173976 -158.237174)
				)
			)
		)
	)
	(zone
		(layer "B.Cu")
		(hatch none 0.5)
		(connect_pads
			(clearance 0)
		)
		(min_thickness 0.25)
		(keepout
			(tracks not_allowed)
			(vias allowed)
			(pads allowed)
			(copperpour not_allowed)
			(footprints allowed)
		)
		(placement
			(enabled no)
			(sheetname "")
		)
		(fill
			(thermal_gap 0.5)
			(thermal_bridge_width 0.5)
			(island_removal_mode 0)
		)
		(polygon
			(pts
				(arc
					(start 31.979616 -372.061486)
					(mid 31.386018 -371.590316)
					(end 30.914848 -372.183914)
				)
				(xy 30.912308 -372.184168) (xy 31.034736 -373.248428) (xy 31.03499 -373.248682)
				(arc
					(start 31.037276 -373.248428)
					(mid 31.630874 -373.719598)
					(end 32.102044 -373.126)
				)
				(xy 32.104584 -373.125746) (xy 32.094932 -373.041418)
				(arc
					(start 32.074866 -373.041418)
					(mid 31.956971 -373.052182)
					(end 31.842964 -373.08409)
				)
				(arc
					(start 31.842964 -373.08409)
					(mid 31.325989 -373.348316)
					(end 31.77159 -372.97614)
				)
				(arc
					(start 31.77159 -372.97614)
					(mid 31.907084 -372.932847)
					(end 32.048196 -372.914926)
				)
				(xy 32.04845 -372.914418) (xy 32.0802 -372.914418) (xy 32.056832 -372.711218) (xy 31.72333 -372.711218)
				(arc
					(start 31.722314 -372.710202)
					(mid 31.504193 -372.616644)
					(end 31.38932 -372.408958)
				)
				(arc
					(start 31.38932 -372.408958)
					(mid 31.440331 -371.830724)
					(end 31.518606 -372.40591)
				)
				(arc
					(start 31.518606 -372.40591)
					(mid 31.603795 -372.534437)
					(end 31.749746 -372.584218)
				)
				(xy 32.042354 -372.584218) (xy 31.982156 -372.061232)
			)
		)
	)
	(zone
		(net "P12V")
		(layer "B.Cu")
		(hatch none 0.5)
		(connect_pads
			(clearance 0.5)
		)
		(min_thickness 0.25)
		(fill yes
			(thermal_gap 0.5)
			(thermal_bridge_width 0.5)
			(island_removal_mode 0)
		)
		(polygon
			(pts
				(xy 24.637746 -403.4917) (xy 24.383746 -403.2377) (xy 20.065746 -403.2377) (xy 19.303746 -403.9997)
				(xy 11.556746 -403.9997) (xy 9.397746 -406.1587) (xy 9.397746 -424.4467) (xy 8.254746 -425.5897)
				(xy 5.511546 -425.5897) (xy 5.079746 -425.1579) (xy 1.371346 -425.1579) (xy 1.295146 -425.2341)
				(xy 1.295146 -430.1871) (xy 3.428746 -432.3207) (xy 13.588746 -432.3207) (xy 16.129 -429.780446)
				(xy 16.129 -413.7787) (xy 17.906746 -412.000954) (xy 17.906746 -412.0007) (xy 18.160746 -411.7467)
				(xy 23.113746 -411.7467) (xy 24.637746 -410.2227)
			)
		)
	)
	(zone
		(net "GND")
		(layer "B.Cu")
		(hatch none 0.5)
		(connect_pads
			(clearance 0.5)
		)
		(min_thickness 0.25)
		(fill yes
			(thermal_gap 0.5)
			(thermal_bridge_width 0.5)
			(island_removal_mode 0)
		)
		(polygon
			(pts
				(xy 25.837896 -366.197896) (xy 25.527 -365.887) (xy 25.285192 -365.887) (xy 13.334746 -377.8377)
				(xy 13.334746 -384.3147) (xy 10.541 -387.108446) (xy 10.541 -389.4455) (xy 10.9982 -389.9027) (xy 19.049746 -389.9027)
				(xy 25.837896 -383.114296)
			)
		)
	)
	(zone
		(net "P12V_HDD14")
		(layer "B.Cu")
		(hatch none 0.5)
		(connect_pads
			(clearance 0.5)
		)
		(min_thickness 0.25)
		(fill yes
			(thermal_gap 0.5)
			(thermal_bridge_width 0.5)
			(island_removal_mode 0)
		)
		(polygon
			(pts
				(xy 73.532746 -8.9027) (xy 77.088746 -12.4587) (xy 78.993746 -12.4587) (xy 79.247746 -12.2047) (xy 79.247746 -8.3947)
				(xy 77.558646 -6.7056) (xy 73.9648 -6.7056) (xy 73.532746 -7.137654)
			)
		)
	)
	(zone
		(layer "B.Cu")
		(hatch none 0.5)
		(connect_pads
			(clearance 0)
		)
		(min_thickness 0.25)
		(keepout
			(tracks not_allowed)
			(vias allowed)
			(pads allowed)
			(copperpour not_allowed)
			(footprints allowed)
		)
		(placement
			(enabled no)
			(sheetname "")
		)
		(fill
			(thermal_gap 0.5)
			(thermal_bridge_width 0.5)
			(island_removal_mode 0)
		)
		(polygon
			(pts
				(arc
					(start 27.56027 -442.714888)
					(mid 27.395438 -442.612652)
					(end 27.215338 -442.540644)
				)
				(xy 27.22372 -442.876178) (xy 27.223974 -442.876432)
				(arc
					(start 27.22626 -442.876432)
					(mid 27.827478 -443.448186)
					(end 28.399232 -442.846968)
				)
				(xy 28.401772 -442.846968) (xy 28.376372 -441.830968)
				(arc
					(start 28.373832 -441.830968)
					(mid 27.772614 -441.259214)
					(end 27.20086 -441.860432)
				)
				(xy 27.19832 -441.860432)
				(arc
					(start 27.2034 -442.06668)
					(mid 27.301002 -442.089495)
					(end 27.396948 -442.118496)
				)
				(arc
					(start 27.396948 -442.118496)
					(mid 27.512609 -442.128834)
					(end 27.620214 -442.085222)
				)
				(arc
					(start 27.620214 -442.085222)
					(mid 27.89094 -441.572621)
					(end 27.753564 -442.135768)
				)
				(arc
					(start 27.753564 -442.135768)
					(mid 27.570318 -442.246592)
					(end 27.356308 -442.238892)
				)
				(arc
					(start 27.356308 -442.238892)
					(mid 27.282067 -442.216045)
					(end 27.206702 -442.197236)
				)
				(xy 27.21102 -442.3664)
				(arc
					(start 27.212036 -442.407802)
					(mid 27.440001 -442.493002)
					(end 27.646884 -442.621162)
				)
				(arc
					(start 27.646884 -442.621162)
					(mid 28.027589 -443.059644)
					(end 27.56027 -442.714888)
				)
			)
		)
	)
	(zone
		(layer "B.Cu")
		(hatch none 0.5)
		(connect_pads
			(clearance 0)
		)
		(min_thickness 0.25)
		(keepout
			(tracks not_allowed)
			(vias allowed)
			(pads allowed)
			(copperpour not_allowed)
			(footprints allowed)
		)
		(placement
			(enabled no)
			(sheetname "")
		)
		(fill
			(thermal_gap 0.5)
			(thermal_bridge_width 0.5)
			(island_removal_mode 0)
		)
		(polygon
			(pts
				(arc
					(start 7.38886 -353.076002)
					(mid 7.418908 -353.007289)
					(end 7.429246 -352.933)
				)
				(xy 7.429246 -352.601276) (xy 7.00405 -352.786188) (xy 7.003796 -352.786442)
				(arc
					(start 7.004812 -352.788728)
					(mid 6.70054 -353.560934)
					(end 7.47268 -353.864926)
				)
				(xy 7.473696 -353.867212) (xy 8.447532 -353.443794)
				(arc
					(start 8.446516 -353.441508)
					(mid 8.750808 -352.669348)
					(end 7.978648 -352.365056)
				)
				(xy 7.977632 -352.36277)
				(arc
					(start 7.886954 -352.40214)
					(mid 7.908289 -352.486948)
					(end 7.958074 -352.558858)
				)
				(arc
					(start 8.055864 -352.656648)
					(mid 8.419208 -353.109908)
					(end 7.965948 -352.746564)
				)
				(xy 7.868158 -352.648774) (xy 7.849616 -352.630232)
				(arc
					(start 7.849616 -352.628708)
					(mid 7.796215 -352.547381)
					(end 7.765796 -352.454972)
				)
				(xy 7.556246 -352.546158) (xy 7.556246 -352.959416)
				(arc
					(start 7.55523 -352.960178)
					(mid 7.532827 -353.067723)
					(end 7.482078 -353.165156)
				)
				(arc
					(start 7.482078 -353.165156)
					(mid 7.036525 -353.537533)
					(end 7.38886 -353.076002)
				)
			)
		)
	)
	(zone
		(layer "B.Cu")
		(hatch none 0.5)
		(connect_pads
			(clearance 0)
		)
		(min_thickness 0.25)
		(keepout
			(tracks not_allowed)
			(vias allowed)
			(pads allowed)
			(copperpour not_allowed)
			(footprints allowed)
		)
		(placement
			(enabled no)
			(sheetname "")
		)
		(fill
			(thermal_gap 0.5)
			(thermal_bridge_width 0.5)
			(island_removal_mode 0)
		)
		(polygon
			(pts
				(arc
					(start 220.782896 -472.907614)
					(mid 220.196283 -472.32062)
					(end 219.609416 -472.90736)
				)
				(xy 219.609416 -473.277946)
				(arc
					(start 219.963746 -473.277946)
					(mid 220.051142 -473.253578)
					(end 220.113352 -473.187522)
				)
				(arc
					(start 220.113352 -473.187522)
					(mid 220.213107 -472.615623)
					(end 220.246956 -473.195142)
				)
				(arc
					(start 220.246956 -473.195142)
					(mid 220.150947 -473.338335)
					(end 219.991432 -473.403676)
				)
				(xy 219.990162 -473.404946) (xy 219.609416 -473.404946) (xy 219.609416 -473.6084) (xy 219.753434 -473.6084)
				(arc
					(start 219.753688 -473.608908)
					(mid 219.8745 -473.62358)
					(end 219.991178 -473.658184)
				)
				(arc
					(start 219.991178 -473.658184)
					(mid 220.441846 -474.023957)
					(end 219.921074 -473.767658)
				)
				(arc
					(start 219.921074 -473.767658)
					(mid 219.825377 -473.743524)
					(end 219.727018 -473.7354)
				)
				(xy 219.609416 -473.7354)
				(arc
					(start 219.609416 -473.86621)
					(mid 220.196156 -474.45295)
					(end 220.782896 -473.86621)
				)
			)
		)
	)
	(zone
		(layer "B.Cu")
		(hatch none 0.5)
		(connect_pads
			(clearance 0)
		)
		(min_thickness 0.25)
		(keepout
			(tracks not_allowed)
			(vias allowed)
			(pads allowed)
			(copperpour not_allowed)
			(footprints allowed)
		)
		(placement
			(enabled no)
			(sheetname "")
		)
		(fill
			(thermal_gap 0.5)
			(thermal_bridge_width 0.5)
			(island_removal_mode 0)
		)
		(polygon
			(pts
				(arc
					(start 7.342886 -133.514846)
					(mid 6.756273 -132.927852)
					(end 6.169406 -133.514592)
				)
				(xy 6.169406 -133.767068)
				(arc
					(start 6.197346 -133.767068)
					(mid 6.359843 -133.741156)
					(end 6.50621 -133.665976)
				)
				(arc
					(start 6.50621 -133.665976)
					(mid 6.966886 -133.312173)
					(end 6.594856 -133.758178)
				)
				(arc
					(start 6.594856 -133.758178)
					(mid 6.420088 -133.854682)
					(end 6.22427 -133.89356)
				)
				(xy 6.223762 -133.894068) (xy 6.169406 -133.894068) (xy 6.169406 -134.097268) (xy 6.401562 -134.097268)
				(arc
					(start 6.402832 -134.098538)
					(mid 6.491107 -134.120357)
					(end 6.568948 -134.167372)
				)
				(xy 6.570726 -134.167372) (xy 6.589014 -134.185914) (xy 6.589268 -134.185914)
				(arc
					(start 6.599428 -134.196074)
					(mid 6.962772 -134.649334)
					(end 6.509512 -134.28599)
				)
				(arc
					(start 6.499352 -134.275576)
					(mid 6.442337 -134.237606)
					(end 6.375146 -134.224268)
				)
				(xy 6.169406 -134.224268)
				(arc
					(start 6.169406 -134.442708)
					(mid 6.756146 -135.029448)
					(end 7.342886 -134.442708)
				)
			)
		)
	)
	(zone
		(layer "B.Cu")
		(hatch none 0.5)
		(connect_pads
			(clearance 0)
		)
		(min_thickness 0.25)
		(keepout
			(tracks not_allowed)
			(vias allowed)
			(pads allowed)
			(copperpour not_allowed)
			(footprints allowed)
		)
		(placement
			(enabled no)
			(sheetname "")
		)
		(fill
			(thermal_gap 0.5)
			(thermal_bridge_width 0.5)
			(island_removal_mode 0)
		)
		(polygon
			(pts
				(arc
					(start 8.689086 -385.533138)
					(mid 8.127873 -384.971544)
					(end 7.566406 -385.532884)
				)
				(arc
					(start 7.566406 -386.461)
					(mid 8.127746 -387.02234)
					(end 8.689086 -386.461)
				)
				(arc
					(start 8.689086 -386.229098)
					(mid 8.532842 -386.2618)
					(end 8.38708 -386.326888)
				)
				(arc
					(start 8.38708 -386.326888)
					(mid 7.903689 -386.64797)
					(end 8.30453 -386.228336)
				)
				(arc
					(start 8.30453 -386.228336)
					(mid 8.489368 -386.142381)
					(end 8.689086 -386.10159)
				)
				(arc
					(start 8.689086 -385.892294)
					(mid 8.489382 -385.85146)
					(end 8.30453 -385.765548)
				)
				(arc
					(start 8.30453 -385.765548)
					(mid 7.903685 -385.34591)
					(end 8.38708 -385.666996)
				)
				(arc
					(start 8.38708 -385.666996)
					(mid 8.532829 -385.732125)
					(end 8.689086 -385.764786)
				)
			)
		)
	)
	(zone
		(layer "B.Cu")
		(hatch none 0.5)
		(connect_pads
			(clearance 0.5)
		)
		(min_thickness 0.25)
		(fill
			(thermal_gap 0.5)
			(thermal_bridge_width 0.5)
			(island_removal_mode 0)
		)
		(polygon
			(pts
				(xy 29.463746 -497.4717) (xy 29.463746 -503.8217) (xy 30.098746 -504.4567) (xy 34.543746 -504.4567)
				(xy 35.432746 -503.5677) (xy 35.432746 -497.4717) (xy 35.178746 -497.2177) (xy 29.717746 -497.2177)
			)
		)
	)
	(zone
		(layer "B.Cu")
		(hatch none 0.5)
		(connect_pads
			(clearance 0)
		)
		(min_thickness 0.25)
		(keepout
			(tracks not_allowed)
			(vias allowed)
			(pads allowed)
			(copperpour not_allowed)
			(footprints allowed)
		)
		(placement
			(enabled no)
			(sheetname "")
		)
		(fill
			(thermal_gap 0.5)
			(thermal_bridge_width 0.5)
			(island_removal_mode 0)
		)
		(polygon
			(pts
				(arc
					(start 7.619238 -169.531792)
					(mid 7.032625 -168.944798)
					(end 6.445758 -169.531538)
				)
				(arc
					(start 6.445758 -170.459654)
					(mid 7.032498 -171.046394)
					(end 7.619238 -170.459654)
				)
				(xy 7.619238 -170.3324)
				(arc
					(start 7.493 -170.3324)
					(mid 7.399209 -170.339932)
					(end 7.307834 -170.362372)
				)
				(arc
					(start 7.307834 -170.362372)
					(mid 6.785764 -170.615846)
					(end 7.238238 -170.25239)
				)
				(arc
					(start 7.238238 -170.25239)
					(mid 7.350252 -170.219803)
					(end 7.466076 -170.205908)
				)
				(xy 7.466584 -170.2054) (xy 7.619238 -170.2054) (xy 7.619238 -170.0022) (xy 7.33933 -170.0022)
				(arc
					(start 7.338568 -170.001184)
					(mid 7.165619 -169.948059)
					(end 7.034276 -169.823638)
				)
				(arc
					(start 7.034276 -169.823638)
					(mid 6.961377 -169.248223)
					(end 7.168896 -169.789856)
				)
				(arc
					(start 7.168896 -169.789856)
					(mid 7.258472 -169.852934)
					(end 7.365746 -169.8752)
				)
				(xy 7.619238 -169.8752)
			)
		)
	)
	(zone
		(layer "B.Cu")
		(hatch none 0.5)
		(connect_pads
			(clearance 0)
		)
		(min_thickness 0.25)
		(keepout
			(tracks not_allowed)
			(vias allowed)
			(pads allowed)
			(copperpour not_allowed)
			(footprints allowed)
		)
		(placement
			(enabled no)
			(sheetname "")
		)
		(fill
			(thermal_gap 0.5)
			(thermal_bridge_width 0.5)
			(island_removal_mode 0)
		)
		(polygon
			(pts
				(arc
					(start 8.233156 -363.266228)
					(mid 8.263433 -363.411521)
					(end 8.318246 -363.549438)
				)
				(arc
					(start 8.318246 -363.549438)
					(mid 8.606062 -364.053836)
					(end 8.21436 -363.62513)
				)
				(arc
					(start 8.21436 -363.62513)
					(mid 8.151922 -363.479704)
					(end 8.113522 -363.326172)
				)
				(arc
					(start 8.113522 -363.326172)
					(mid 8.088546 -363.343443)
					(end 8.0645 -363.361986)
				)
				(xy 8.062976 -363.359954) (xy 7.89686 -363.494828)
				(arc
					(start 7.89686 -364.125002)
					(mid 7.65882 -364.654411)
					(end 7.76986 -364.084616)
				)
				(xy 7.76986 -363.597952) (xy 7.375398 -363.918246)
				(arc
					(start 7.376922 -363.920278)
					(mid 7.291324 -364.745524)
					(end 8.11657 -364.831122)
				)
				(xy 8.118094 -364.833154) (xy 8.805672 -364.275116) (xy 8.805672 -364.274608)
				(arc
					(start 8.804148 -364.27283)
					(mid 8.944608 -363.527944)
					(end 8.233156 -363.266228)
				)
			)
		)
	)
	(zone
		(layer "B.Cu")
		(hatch none 0.5)
		(connect_pads
			(clearance 0)
		)
		(min_thickness 0.25)
		(keepout
			(tracks allowed)
			(vias allowed)
			(pads allowed)
			(copperpour allowed)
			(footprints not_allowed)
		)
		(placement
			(enabled no)
			(sheetname "")
		)
		(fill
			(thermal_gap 0.5)
			(thermal_bridge_width 0.5)
			(island_removal_mode 0)
		)
		(polygon
			(pts
				(arc
					(start 69.000116 -381)
					(mid 73.000108 -377.000008)
					(end 69.000116 -373.000016)
				)
				(arc
					(start 69.000116 -373.000016)
					(mid 65.000124 -377.000008)
					(end 69.000116 -381)
				)
			)
		)
	)
	(zone
		(layer "B.Cu")
		(hatch none 0.5)
		(connect_pads
			(clearance 0.5)
		)
		(min_thickness 0.25)
		(fill
			(thermal_gap 0.5)
			(thermal_bridge_width 0.5)
			(island_removal_mode 0)
		)
		(polygon
			(pts
				(xy 54.609746 -7.8867) (xy 54.482746 -8.0137) (xy 54.482746 -12.9667) (xy 55.625746 -14.1097) (xy 55.625746 -18.1737)
				(xy 56.006746 -18.5547) (xy 59.689746 -18.5547) (xy 59.943746 -18.3007) (xy 59.943746 -8.3947) (xy 59.435746 -7.8867)
			)
		)
	)
	(zone
		(layer "B.Cu")
		(hatch none 0.5)
		(connect_pads
			(clearance 0.5)
		)
		(min_thickness 0.25)
		(fill
			(thermal_gap 0.5)
			(thermal_bridge_width 0.5)
			(island_removal_mode 0)
		)
		(polygon
			(pts
				(xy 17.652746 -495.5667) (xy 21.462746 -495.5667) (xy 22.732746 -494.2967) (xy 22.732746 -486.9307)
				(xy 21.589746 -485.7877) (xy 19.176746 -485.7877) (xy 18.281396 -484.892604) (xy 15.23365 -484.892604)
				(xy 14.096746 -483.7557) (xy 11.938 -483.7557) (xy 11.557 -484.1367) (xy 11.557 -491.871) (xy 11.684 -491.998)
				(xy 14.084046 -491.998)
			)
		)
	)
	(zone
		(layer "B.Cu")
		(hatch none 0.5)
		(connect_pads
			(clearance 0)
		)
		(min_thickness 0.25)
		(keepout
			(tracks not_allowed)
			(vias allowed)
			(pads allowed)
			(copperpour not_allowed)
			(footprints allowed)
		)
		(placement
			(enabled no)
			(sheetname "")
		)
		(fill
			(thermal_gap 0.5)
			(thermal_bridge_width 0.5)
			(island_removal_mode 0)
		)
		(polygon
			(pts
				(arc
					(start 7.77875 -399.884138)
					(mid 8.335766 -399.273649)
					(end 7.725156 -398.716754)
				)
				(arc
					(start 7.647686 -398.72031)
					(mid 7.708031 -398.86211)
					(end 7.756652 -399.008346)
				)
				(arc
					(start 7.756652 -399.008346)
					(mid 7.811799 -399.586462)
					(end 7.631938 -399.034254)
				)
				(arc
					(start 7.631938 -399.034254)
					(mid 7.577829 -398.877572)
					(end 7.509256 -398.72666)
				)
				(arc
					(start 7.182612 -398.741646)
					(mid 7.180911 -398.953978)
					(end 7.116064 -399.156174)
				)
				(arc
					(start 7.116064 -399.156174)
					(mid 6.708659 -399.569532)
					(end 7.013448 -399.075656)
				)
				(arc
					(start 7.013448 -399.075656)
					(mid 7.058287 -398.914615)
					(end 7.055104 -398.747488)
				)
				(arc
					(start 6.862318 -398.756378)
					(mid 6.30555 -399.366994)
					(end 6.916166 -399.923762)
				)
			)
		)
	)
	(zone
		(layers "B.Cu" "In2.Cu")
		(hatch none 0.5)
		(connect_pads
			(clearance 0)
		)
		(min_thickness 0.25)
		(keepout
			(tracks not_allowed)
			(vias allowed)
			(pads allowed)
			(copperpour not_allowed)
			(footprints allowed)
		)
		(placement
			(enabled no)
			(sheetname "")
		)
		(fill yes
			(thermal_gap 0.5)
			(thermal_bridge_width 0.5)
			(island_removal_mode 0)
		)
		(polygon
			(pts
				(arc
					(start 13.38834 -176.733454)
					(mid 12.813538 -176.14933)
					(end 12.220194 -176.714658)
				)
				(arc
					(start 12.192254 -177.578004)
					(mid 12.757404 -178.180746)
					(end 13.360146 -177.615596)
				)
				(xy 13.360654 -177.59934)
				(arc
					(start 13.0683 -177.59934)
					(mid 12.7762 -177.888911)
					(end 12.4841 -177.59934)
				)
				(arc
					(start 12.4841 -177.5968)
					(mid 12.7762 -177.3047)
					(end 13.0683 -177.5968)
				)
				(xy 13.360654 -177.5968) (xy 13.388086 -176.752504) (xy 13.38834 -176.735994)
				(arc
					(start 13.09624 -176.735994)
					(mid 12.80414 -177.025565)
					(end 12.51204 -176.735994)
				)
				(arc
					(start 12.51204 -176.733454)
					(mid 12.80414 -176.441354)
					(end 13.09624 -176.733454)
				)
			)
		)
	)
	(zone
		(layers "B.Cu" "In2.Cu")
		(hatch none 0.5)
		(connect_pads
			(clearance 0)
		)
		(min_thickness 0.25)
		(keepout
			(tracks not_allowed)
			(vias allowed)
			(pads allowed)
			(copperpour not_allowed)
			(footprints allowed)
		)
		(placement
			(enabled no)
			(sheetname "")
		)
		(fill yes
			(thermal_gap 0.5)
			(thermal_bridge_width 0.5)
			(island_removal_mode 0)
		)
		(polygon
			(pts
				(arc
					(start 37.223192 -163.920424)
					(mid 36.636452 -163.333684)
					(end 36.049712 -163.920424)
				)
				(arc
					(start 36.049712 -164.879274)
					(mid 36.635182 -165.466013)
					(end 37.223192 -164.881814)
				)
				(arc
					(start 36.928552 -164.881814)
					(mid 36.636452 -165.171385)
					(end 36.344352 -164.881814)
				)
				(arc
					(start 36.344352 -164.879274)
					(mid 36.636452 -164.587174)
					(end 36.928552 -164.879274)
				)
				(xy 37.223192 -164.879274) (xy 37.223192 -163.922964)
				(arc
					(start 36.928552 -163.922964)
					(mid 36.636452 -164.212535)
					(end 36.344352 -163.922964)
				)
				(arc
					(start 36.344352 -163.920424)
					(mid 36.636452 -163.628324)
					(end 36.928552 -163.920424)
				)
			)
		)
	)
	(zone
		(layers "B.Cu" "In2.Cu")
		(hatch none 0.5)
		(connect_pads
			(clearance 0)
		)
		(min_thickness 0.25)
		(keepout
			(tracks not_allowed)
			(vias allowed)
			(pads allowed)
			(copperpour not_allowed)
			(footprints allowed)
		)
		(placement
			(enabled no)
			(sheetname "")
		)
		(fill yes
			(thermal_gap 0.5)
			(thermal_bridge_width 0.5)
			(island_removal_mode 0)
		)
		(polygon
			(pts
				(arc
					(start 32.190182 -273.690842)
					(mid 31.603442 -273.104102)
					(end 31.016702 -273.690842)
				)
				(arc
					(start 31.016702 -274.618958)
					(mid 31.602172 -275.205697)
					(end 32.190182 -274.621498)
				)
				(arc
					(start 31.895542 -274.621498)
					(mid 31.603442 -274.911069)
					(end 31.311342 -274.621498)
				)
				(arc
					(start 31.311342 -274.618958)
					(mid 31.603442 -274.326858)
					(end 31.895542 -274.618958)
				)
				(xy 32.190182 -274.618958) (xy 32.190182 -273.693382)
				(arc
					(start 31.895542 -273.693382)
					(mid 31.603442 -273.982953)
					(end 31.311342 -273.693382)
				)
				(arc
					(start 31.311342 -273.690842)
					(mid 31.603442 -273.398742)
					(end 31.895542 -273.690842)
				)
			)
		)
	)
	(zone
		(layers "B.Cu" "In2.Cu")
		(hatch none 0.5)
		(connect_pads
			(clearance 0)
		)
		(min_thickness 0.25)
		(keepout
			(tracks not_allowed)
			(vias allowed)
			(pads allowed)
			(copperpour not_allowed)
			(footprints allowed)
		)
		(placement
			(enabled no)
			(sheetname "")
		)
		(fill yes
			(thermal_gap 0.5)
			(thermal_bridge_width 0.5)
			(island_removal_mode 0)
		)
		(polygon
			(pts
				(arc
					(start 29.41574 -341.503)
					(mid 28.829 -340.91626)
					(end 28.24226 -341.503)
				)
				(arc
					(start 28.24226 -342.431116)
					(mid 28.82773 -343.017855)
					(end 29.41574 -342.433656)
				)
				(arc
					(start 29.1211 -342.433656)
					(mid 28.829 -342.723227)
					(end 28.5369 -342.433656)
				)
				(arc
					(start 28.5369 -342.431116)
					(mid 28.829 -342.139016)
					(end 29.1211 -342.431116)
				)
				(xy 29.41574 -342.431116) (xy 29.41574 -341.50554)
				(arc
					(start 29.1211 -341.50554)
					(mid 28.829 -341.795111)
					(end 28.5369 -341.50554)
				)
				(arc
					(start 28.5369 -341.503)
					(mid 28.829 -341.2109)
					(end 29.1211 -341.503)
				)
			)
		)
	)
	(zone
		(layers "B.Cu" "In2.Cu")
		(hatch none 0.5)
		(connect_pads
			(clearance 0)
		)
		(min_thickness 0.25)
		(keepout
			(tracks not_allowed)
			(vias allowed)
			(pads allowed)
			(copperpour not_allowed)
			(footprints allowed)
		)
		(placement
			(enabled no)
			(sheetname "")
		)
		(fill yes
			(thermal_gap 0.5)
			(thermal_bridge_width 0.5)
			(island_removal_mode 0)
		)
		(polygon
			(pts
				(arc
					(start 32.463486 -161.4297)
					(mid 31.876746 -160.84296)
					(end 31.290006 -161.4297)
				)
				(arc
					(start 31.290006 -162.2933)
					(mid 31.875476 -162.880039)
					(end 32.463486 -162.29584)
				)
				(arc
					(start 32.168846 -162.29584)
					(mid 31.876746 -162.585411)
					(end 31.584646 -162.29584)
				)
				(arc
					(start 31.584646 -162.2933)
					(mid 31.876746 -162.0012)
					(end 32.168846 -162.2933)
				)
				(xy 32.463486 -162.2933) (xy 32.463486 -161.43224)
				(arc
					(start 32.168846 -161.43224)
					(mid 31.876746 -161.721811)
					(end 31.584646 -161.43224)
				)
				(arc
					(start 31.584646 -161.4297)
					(mid 31.876746 -161.1376)
					(end 32.168846 -161.4297)
				)
			)
		)
	)
	(zone
		(layers "B.Cu" "In2.Cu")
		(hatch none 0.5)
		(connect_pads
			(clearance 0)
		)
		(min_thickness 0.25)
		(keepout
			(tracks not_allowed)
			(vias allowed)
			(pads allowed)
			(copperpour not_allowed)
			(footprints allowed)
		)
		(placement
			(enabled no)
			(sheetname "")
		)
		(fill yes
			(thermal_gap 0.5)
			(thermal_bridge_width 0.5)
			(island_removal_mode 0)
		)
		(polygon
			(pts
				(arc
					(start 15.827502 -135.6741)
					(mid 15.241143 -135.08736)
					(end 14.654022 -135.673338)
				)
				(arc
					(start 14.653006 -136.536938)
					(mid 15.238095 -137.124438)
					(end 15.826486 -136.54024)
				)
				(arc
					(start 15.531846 -136.54024)
					(mid 15.239746 -136.829811)
					(end 14.947646 -136.54024)
				)
				(arc
					(start 14.947646 -136.5377)
					(mid 15.239746 -136.2456)
					(end 15.531846 -136.5377)
				)
				(xy 15.826486 -136.5377) (xy 15.826486 -136.536938) (xy 15.827502 -135.67664)
				(arc
					(start 15.532862 -135.67664)
					(mid 15.240762 -135.966211)
					(end 14.948662 -135.67664)
				)
				(arc
					(start 14.948662 -135.6741)
					(mid 15.240762 -135.382)
					(end 15.532862 -135.6741)
				)
			)
		)
	)
	(zone
		(layers "B.Cu" "In2.Cu")
		(hatch none 0.5)
		(connect_pads
			(clearance 0)
		)
		(min_thickness 0.25)
		(keepout
			(tracks not_allowed)
			(vias allowed)
			(pads allowed)
			(copperpour not_allowed)
			(footprints allowed)
		)
		(placement
			(enabled no)
			(sheetname "")
		)
		(fill yes
			(thermal_gap 0.5)
			(thermal_bridge_width 0.5)
			(island_removal_mode 0)
		)
		(polygon
			(pts
				(arc
					(start 22.481286 -135.1915)
					(mid 21.894546 -134.60476)
					(end 21.307806 -135.1915)
				)
				(arc
					(start 21.307806 -136.15035)
					(mid 21.893276 -136.737089)
					(end 22.481286 -136.15289)
				)
				(arc
					(start 22.186646 -136.15289)
					(mid 21.894546 -136.442461)
					(end 21.602446 -136.15289)
				)
				(arc
					(start 21.602446 -136.15035)
					(mid 21.894546 -135.85825)
					(end 22.186646 -136.15035)
				)
				(xy 22.481286 -136.15035) (xy 22.481286 -135.19404)
				(arc
					(start 22.186646 -135.19404)
					(mid 21.894546 -135.483611)
					(end 21.602446 -135.19404)
				)
				(arc
					(start 21.602446 -135.1915)
					(mid 21.894546 -134.8994)
					(end 22.186646 -135.1915)
				)
			)
		)
	)
	(zone
		(layers "B.Cu" "In2.Cu")
		(hatch none 0.5)
		(connect_pads
			(clearance 0)
		)
		(min_thickness 0.25)
		(keepout
			(tracks not_allowed)
			(vias allowed)
			(pads allowed)
			(copperpour not_allowed)
			(footprints allowed)
		)
		(placement
			(enabled no)
			(sheetname "")
		)
		(fill yes
			(thermal_gap 0.5)
			(thermal_bridge_width 0.5)
			(island_removal_mode 0)
		)
		(polygon
			(pts
				(arc
					(start 16.945102 -119.645684)
					(mid 16.35887 -119.058944)
					(end 15.771622 -119.644668)
				)
				(arc
					(start 15.770098 -120.508268)
					(mid 16.35506 -121.096022)
					(end 16.943578 -120.511824)
				)
				(arc
					(start 16.648938 -120.511824)
					(mid 16.356838 -120.801395)
					(end 16.064738 -120.511824)
				)
				(arc
					(start 16.064738 -120.509284)
					(mid 16.356838 -120.217184)
					(end 16.648938 -120.509284)
				)
				(xy 16.943578 -120.509284) (xy 16.943578 -120.508268) (xy 16.945102 -119.648224)
				(arc
					(start 16.650462 -119.648224)
					(mid 16.358362 -119.937795)
					(end 16.066262 -119.648224)
				)
				(arc
					(start 16.066262 -119.645684)
					(mid 16.358362 -119.353584)
					(end 16.650462 -119.645684)
				)
			)
		)
	)
	(zone
		(layers "B.Cu" "In2.Cu")
		(hatch none 0.5)
		(connect_pads
			(clearance 0)
		)
		(min_thickness 0.25)
		(keepout
			(tracks not_allowed)
			(vias allowed)
			(pads allowed)
			(copperpour not_allowed)
			(footprints allowed)
		)
		(placement
			(enabled no)
			(sheetname "")
		)
		(fill yes
			(thermal_gap 0.5)
			(thermal_bridge_width 0.5)
			(island_removal_mode 0)
		)
		(polygon
			(pts
				(arc
					(start 11.0744 -440.63666)
					(mid 10.48766 -441.2234)
					(end 11.0744 -441.81014)
				)
				(xy 11.937746 -441.81014)
				(arc
					(start 11.938 -441.81014)
					(mid 12.351989 -441.639185)
					(end 12.52474 -441.22594)
				)
				(arc
					(start 12.2301 -441.22594)
					(mid 11.938 -441.515511)
					(end 11.6459 -441.22594)
				)
				(arc
					(start 11.3665 -441.22594)
					(mid 11.0744 -441.515511)
					(end 10.7823 -441.22594)
				)
				(arc
					(start 10.7823 -441.2234)
					(mid 11.0744 -440.9313)
					(end 11.3665 -441.2234)
				)
				(arc
					(start 11.6459 -441.2234)
					(mid 11.938 -440.9313)
					(end 12.2301 -441.2234)
				)
				(arc
					(start 12.52474 -441.2234)
					(mid 12.352888 -440.808512)
					(end 11.938 -440.63666)
				)
			)
		)
	)
	(zone
		(layers "B.Cu" "In2.Cu")
		(hatch none 0.5)
		(connect_pads
			(clearance 0)
		)
		(min_thickness 0.25)
		(keepout
			(tracks not_allowed)
			(vias allowed)
			(pads allowed)
			(copperpour not_allowed)
			(footprints allowed)
		)
		(placement
			(enabled no)
			(sheetname "")
		)
		(fill yes
			(thermal_gap 0.5)
			(thermal_bridge_width 0.5)
			(island_removal_mode 0)
		)
		(polygon
			(pts
				(arc
					(start 12.239498 -438.105042)
					(mid 11.652758 -437.518302)
					(end 11.066018 -438.105042)
				)
				(arc
					(start 11.066018 -439.032904)
					(mid 11.651361 -439.619896)
					(end 12.239498 -439.035698)
				)
				(arc
					(start 11.944858 -439.035698)
					(mid 11.652758 -439.325269)
					(end 11.360658 -439.035698)
				)
				(arc
					(start 11.360658 -439.033158)
					(mid 11.652758 -438.741058)
					(end 11.944858 -439.033158)
				)
				(xy 12.239498 -439.033158) (xy 12.239498 -438.107582)
				(arc
					(start 11.944858 -438.107582)
					(mid 11.652758 -438.397153)
					(end 11.360658 -438.107582)
				)
				(arc
					(start 11.360658 -438.105042)
					(mid 11.652758 -437.812942)
					(end 11.944858 -438.105042)
				)
			)
		)
	)
	(zone
		(layers "B.Cu" "In5.Cu")
		(hatch none 0.5)
		(connect_pads
			(clearance 0)
		)
		(min_thickness 0.25)
		(keepout
			(tracks not_allowed)
			(vias allowed)
			(pads allowed)
			(copperpour not_allowed)
			(footprints allowed)
		)
		(placement
			(enabled no)
			(sheetname "")
		)
		(fill yes
			(thermal_gap 0.5)
			(thermal_bridge_width 0.5)
			(island_removal_mode 0)
		)
		(polygon
			(pts
				(arc
					(start 32.082486 -266.8651)
					(mid 31.495746 -266.27836)
					(end 30.909006 -266.8651)
				)
				(arc
					(start 30.909006 -267.728446)
					(mid 31.494349 -268.315438)
					(end 32.082486 -267.73124)
				)
				(arc
					(start 31.787846 -267.73124)
					(mid 31.495746 -268.020811)
					(end 31.203646 -267.73124)
				)
				(arc
					(start 31.203646 -267.7287)
					(mid 31.495746 -267.4366)
					(end 31.787846 -267.7287)
				)
				(xy 32.082486 -267.7287) (xy 32.082486 -266.86764)
				(arc
					(start 31.787846 -266.86764)
					(mid 31.495746 -267.157211)
					(end 31.203646 -266.86764)
				)
				(arc
					(start 31.203646 -266.8651)
					(mid 31.495746 -266.573)
					(end 31.787846 -266.8651)
				)
			)
		)
	)
	(zone
		(layers "B.Cu" "In5.Cu")
		(hatch none 0.5)
		(connect_pads
			(clearance 0)
		)
		(min_thickness 0.25)
		(keepout
			(tracks not_allowed)
			(vias allowed)
			(pads allowed)
			(copperpour not_allowed)
			(footprints allowed)
		)
		(placement
			(enabled no)
			(sheetname "")
		)
		(fill yes
			(thermal_gap 0.5)
			(thermal_bridge_width 0.5)
			(island_removal_mode 0)
		)
		(polygon
			(pts
				(arc
					(start 33.96234 -163.7284)
					(mid 33.730365 -163.261061)
					(end 33.217866 -163.16325)
				)
				(arc
					(start 32.361886 -163.402518)
					(mid 31.945616 -164.123487)
					(end 32.66948 -164.53485)
				)
				(arc
					(start 33.533334 -164.29355)
					(mid 33.842177 -164.084181)
					(end 33.96234 -163.73094)
				)
				(arc
					(start 33.6677 -163.73094)
					(mid 33.512967 -163.986197)
					(end 33.214818 -163.97224)
				)
				(arc
					(start 32.803846 -163.97224)
					(mid 32.511746 -164.261811)
					(end 32.219646 -163.97224)
				)
				(arc
					(start 32.219646 -163.9697)
					(mid 32.511746 -163.6776)
					(end 32.803846 -163.9697)
				)
				(arc
					(start 33.211008 -163.9697)
					(mid 33.11794 -163.865978)
					(end 33.0835 -163.73094)
				)
				(arc
					(start 33.0835 -163.7284)
					(mid 33.3756 -163.4363)
					(end 33.6677 -163.7284)
				)
			)
		)
	)
	(zone
		(layers "B.Cu" "In5.Cu")
		(hatch none 0.5)
		(connect_pads
			(clearance 0)
		)
		(min_thickness 0.25)
		(keepout
			(tracks not_allowed)
			(vias allowed)
			(pads allowed)
			(copperpour not_allowed)
			(footprints allowed)
		)
		(placement
			(enabled no)
			(sheetname "")
		)
		(fill yes
			(thermal_gap 0.5)
			(thermal_bridge_width 0.5)
			(island_removal_mode 0)
		)
		(polygon
			(pts
				(arc
					(start 24.257 -129.81686)
					(mid 23.67026 -130.4036)
					(end 24.257 -130.99034)
				)
				(arc
					(start 25.1206 -130.99034)
					(mid 25.534589 -130.819385)
					(end 25.70734 -130.40614)
				)
				(arc
					(start 25.4127 -130.40614)
					(mid 25.1206 -130.695711)
					(end 24.8285 -130.40614)
				)
				(arc
					(start 24.5491 -130.40614)
					(mid 24.257 -130.695711)
					(end 23.9649 -130.40614)
				)
				(arc
					(start 23.9649 -130.4036)
					(mid 24.257 -130.1115)
					(end 24.5491 -130.4036)
				)
				(arc
					(start 24.8285 -130.4036)
					(mid 25.1206 -130.1115)
					(end 25.4127 -130.4036)
				)
				(arc
					(start 25.70734 -130.4036)
					(mid 25.535488 -129.988712)
					(end 25.1206 -129.81686)
				)
			)
		)
	)
	(zone
		(net "GND")
		(layer "In1.Cu")
		(hatch none 0.5)
		(connect_pads
			(clearance 0.5)
		)
		(min_thickness 0.25)
		(fill yes
			(thermal_gap 0.5)
			(thermal_bridge_width 0.5)
			(island_removal_mode 0)
		)
		(polygon
			(pts
				(arc
					(start 0.999998 -0.763016)
					(mid 0.832426 -0.832426)
					(end 0.763016 -0.999998)
				)
				(xy 0.763016 -53.433726) (xy 0.816356 -53.487066)
				(arc
					(start 5.050028 -53.487066)
					(mid 6.763004 -55.200042)
					(end 5.050028 -56.913018)
				)
				(xy 0.816102 -56.913018) (xy 0.763016 -56.966104) (xy 0.763016 -104.233726) (xy 0.816356 -104.287066)
				(arc
					(start 5.050028 -104.287066)
					(mid 6.574439 -105.218724)
					(end 6.440678 -107.000294)
				)
				(arc
					(start 6.440678 -107.000294)
					(mid 7.003377 -107.018543)
					(end 7.291578 -107.502198)
				)
				(xy 7.294118 -107.502198) (xy 7.325868 -108.36529)
				(arc
					(start 7.323328 -108.36529)
					(mid 6.758686 -108.973112)
					(end 6.150864 -108.40847)
				)
				(xy 6.148578 -108.40847) (xy 6.148324 -108.408216) (xy 6.116574 -107.545378)
				(arc
					(start 6.119114 -107.545378)
					(mid 6.127653 -107.422093)
					(end 6.161786 -107.303316)
				)
				(arc
					(start 6.161786 -107.303316)
					(mid 5.642464 -107.607384)
					(end 5.050028 -107.713018)
				)
				(xy 4.995672 -107.713018) (xy 4.995672 -107.855512) (xy 1.388872 -107.855512) (xy 1.388872 -107.713018)
				(xy 0.816102 -107.713018) (xy 0.763016 -107.766104) (xy 0.763016 -208.233772) (xy 0.816102 -208.286858)
				(arc
					(start 5.050028 -208.286858)
					(mid 6.763258 -210.000088)
					(end 5.050028 -211.713064)
				)
				(xy 0.816102 -211.713064) (xy 0.763016 -211.76615) (xy 0.763016 -303.433734) (xy 0.816356 -303.487074)
				(arc
					(start 5.050028 -303.487074)
					(mid 6.763004 -305.20005)
					(end 5.050028 -306.913026)
				)
				(xy 0.816102 -306.913026) (xy 0.763016 -306.966112) (xy 0.763016 -354.233734) (xy 0.816356 -354.287074)
				(arc
					(start 5.050028 -354.287074)
					(mid 6.763004 -356.00005)
					(end 5.050028 -357.713026)
				)
				(xy 4.995672 -357.713026) (xy 4.995672 -357.85552) (xy 1.388872 -357.85552) (xy 1.388872 -357.713026)
				(xy 0.816102 -357.713026) (xy 0.763016 -357.766112) (xy 0.763016 -458.23378) (xy 0.816102 -458.286866)
				(arc
					(start 5.050028 -458.286866)
					(mid 6.763258 -460.000096)
					(end 5.050028 -461.713072)
				)
				(xy 0.816102 -461.713072) (xy 0.763016 -461.766158)
				(arc
					(start 0.763016 -505.000006)
					(mid 0.832426 -505.167578)
					(end 0.999998 -505.236988)
				)
				(arc
					(start 261.500112 -505.236988)
					(mid 261.667684 -505.167578)
					(end 261.737094 -505.000006)
				)
				(xy 261.737094 -428.396146) (xy 261.183882 -427.842934)
				(arc
					(start 260.149594 -427.842934)
					(mid 258.726388 -427.253265)
					(end 258.136898 -425.829984)
				)
				(xy 258.136898 -411.80131) (xy 257.583686 -411.248098)
				(arc
					(start 251.394976 -411.248098)
					(mid 250.097036 -409.950158)
					(end 251.394976 -408.651964)
				)
				(xy 257.583686 -408.651964) (xy 258.136898 -408.098752)
				(arc
					(start 258.136898 -364.16996)
					(mid 258.726388 -362.746679)
					(end 260.149594 -362.15701)
				)
				(xy 261.183882 -362.15701) (xy 261.737094 -361.603798)
				(arc
					(start 261.737094 -0.999998)
					(mid 261.667684 -0.832426)
					(end 261.500112 -0.763016)
				)
			)
		)
		(polygon
			(pts
				(xy 226.3521 -475.932754) (xy 224.4471 -475.932754) (xy 224.4471 -476.440754) (xy 226.3521 -476.440754)
			)
		)
		(polygon
			(pts
				(xy 41.352216 -475.932754) (xy 39.447216 -475.932754) (xy 39.447216 -476.440754) (xy 41.352216 -476.440754)
			)
		)
		(polygon
			(pts
				(xy 219.606368 -475.720156) (xy 217.699082 -475.720156) (xy 217.699082 -476.586296) (xy 219.606368 -476.586296)
			)
		)
		(polygon
			(pts
				(xy 34.00298 -475.62897) (xy 32.095694 -475.62897) (xy 32.095694 -476.49511) (xy 34.00298 -476.49511)
			)
		)
		(polygon
			(pts
				(xy 226.3521 -475.132908) (xy 224.4471 -475.132908) (xy 224.4471 -475.640908) (xy 226.3521 -475.640908)
			)
		)
		(polygon
			(pts
				(xy 41.352216 -475.132908) (xy 39.447216 -475.132908) (xy 39.447216 -475.640908) (xy 41.352216 -475.640908)
			)
		)
		(polygon
			(pts
				(xy 219.606368 -474.831156) (xy 217.699082 -474.831156) (xy 217.699082 -475.697296) (xy 219.606368 -475.697296)
			)
		)
		(polygon
			(pts
				(xy 34.00298 -474.73997) (xy 32.095694 -474.73997) (xy 32.095694 -475.60611) (xy 34.00298 -475.60611)
			)
		)
		(polygon
			(pts
				(arc
					(start 216.792048 -475.829884)
					(mid 217.375485 -475.239715)
					(end 216.78519 -474.656404)
				)
				(arc
					(start 215.92159 -474.661484)
					(mid 215.338406 -475.25178)
					(end 215.928702 -475.834964)
				)
			)
		)
		(polygon
			(pts
				(arc
					(start 31.927546 -475.163896)
					(mid 31.307532 -474.612462)
					(end 30.756098 -475.232476)
				)
				(xy 30.753558 -475.23273) (xy 30.804104 -476.09506)
				(arc
					(start 30.806644 -476.094806)
					(mid 31.426658 -476.64624)
					(end 31.978092 -476.026226)
				)
				(xy 31.980632 -476.025972) (xy 31.930086 -475.163896) (xy 31.929832 -475.163642)
			)
		)
		(polygon
			(pts
				(xy 226.3521 -473.532708) (xy 224.4471 -473.532708) (xy 224.4471 -474.040708) (xy 226.3521 -474.040708)
			)
		)
		(polygon
			(pts
				(xy 41.352216 -473.532708) (xy 39.447216 -473.532708) (xy 39.447216 -474.040708) (xy 41.352216 -474.040708)
			)
		)
		(polygon
			(pts
				(xy 226.3521 -472.732862) (xy 224.4471 -472.732862) (xy 224.4471 -473.240862) (xy 226.3521 -473.240862)
			)
		)
		(polygon
			(pts
				(xy 41.352216 -472.732862) (xy 39.447216 -472.732862) (xy 39.447216 -473.240862) (xy 41.352216 -473.240862)
			)
		)
		(polygon
			(pts
				(arc
					(start 220.782896 -472.907106)
					(mid 220.196029 -472.32062)
					(end 219.609416 -472.90736)
				)
				(arc
					(start 219.609416 -473.86621)
					(mid 220.196156 -474.45295)
					(end 220.782896 -473.86621)
				)
			)
		)
		(polygon
			(pts
				(arc
					(start 35.638486 -472.819984)
					(mid 35.051619 -472.233498)
					(end 34.465006 -472.820238)
				)
				(arc
					(start 34.465006 -473.748354)
					(mid 35.051746 -474.335094)
					(end 35.638486 -473.748354)
				)
			)
		)
		(polygon
			(pts
				(xy 224.443544 -469.816688) (xy 222.055944 -469.816688) (xy 222.055944 -470.477088) (xy 224.443544 -470.477088)
			)
		)
		(polygon
			(pts
				(xy 39.44366 -469.816688) (xy 37.05606 -469.816688) (xy 37.05606 -470.477088) (xy 39.44366 -470.477088)
			)
		)
		(polygon
			(pts
				(xy 219.606368 -469.497156) (xy 217.699082 -469.497156) (xy 217.699082 -470.363296) (xy 219.606368 -470.363296)
			)
		)
		(polygon
			(pts
				(xy 34.00298 -469.40597) (xy 32.095694 -469.40597) (xy 32.095694 -470.27211) (xy 34.00298 -470.27211)
			)
		)
		(polygon
			(pts
				(xy 219.606368 -468.608156) (xy 217.699082 -468.608156) (xy 217.699082 -469.474296) (xy 219.606368 -469.474296)
			)
		)
		(polygon
			(pts
				(xy 224.443544 -468.546688) (xy 222.055944 -468.546688) (xy 222.055944 -469.207088) (xy 224.443544 -469.207088)
			)
		)
		(polygon
			(pts
				(xy 39.44366 -468.546688) (xy 37.05606 -468.546688) (xy 37.05606 -469.207088) (xy 39.44366 -469.207088)
			)
		)
		(polygon
			(pts
				(xy 34.00298 -468.51697) (xy 32.095694 -468.51697) (xy 32.095694 -469.38311) (xy 34.00298 -469.38311)
			)
		)
		(polygon
			(pts
				(xy 224.443544 -466.006688) (xy 222.055944 -466.006688) (xy 222.055944 -466.667088) (xy 224.443544 -466.667088)
			)
		)
		(polygon
			(pts
				(xy 39.44366 -466.006688) (xy 37.05606 -466.006688) (xy 37.05606 -466.667088) (xy 39.44366 -466.667088)
			)
		)
		(polygon
			(pts
				(xy 224.443544 -464.736688) (xy 222.055944 -464.736688) (xy 222.055944 -465.397088) (xy 224.443544 -465.397088)
			)
		)
		(polygon
			(pts
				(xy 39.44366 -464.736688) (xy 37.05606 -464.736688) (xy 37.05606 -465.397088) (xy 39.44366 -465.397088)
			)
		)
		(polygon
			(pts
				(xy 22.943566 -452.596504) (xy 20.555966 -452.596504) (xy 20.555966 -453.256904) (xy 22.943566 -453.256904)
			)
		)
		(polygon
			(pts
				(xy 22.943566 -451.326504) (xy 20.555966 -451.326504) (xy 20.555966 -451.986904) (xy 22.943566 -451.986904)
			)
		)
		(polygon
			(pts
				(xy 22.943566 -448.786504) (xy 20.555966 -448.786504) (xy 20.555966 -449.446904) (xy 22.943566 -449.446904)
			)
		)
		(polygon
			(pts
				(xy 27.756358 -448.526154) (xy 25.849072 -448.526154) (xy 25.849072 -449.392294) (xy 27.756358 -449.392294)
			)
		)
		(polygon
			(pts
				(xy 27.756358 -447.637154) (xy 25.849072 -447.637154) (xy 25.849072 -448.503294) (xy 27.756358 -448.503294)
			)
		)
		(polygon
			(pts
				(xy 22.943566 -447.516504) (xy 20.555966 -447.516504) (xy 20.555966 -448.176904) (xy 22.943566 -448.176904)
			)
		)
		(polygon
			(pts
				(xy 20.55241 -444.75273) (xy 18.64741 -444.75273) (xy 18.64741 -445.26073) (xy 20.55241 -445.26073)
			)
		)
		(polygon
			(pts
				(xy 20.55241 -443.952884) (xy 18.64741 -443.952884) (xy 18.64741 -444.460884) (xy 20.55241 -444.460884)
			)
		)
		(polygon
			(pts
				(arc
					(start 22.225508 -444.181992)
					(mid 21.613876 -443.62116)
					(end 21.053044 -444.232792)
				)
				(arc
					(start 21.090382 -445.095376)
					(mid 21.701887 -445.656457)
					(end 22.262846 -445.04483)
				)
			)
		)
		(polygon
			(pts
				(xy 20.55241 -442.352684) (xy 18.64741 -442.352684) (xy 18.64741 -442.860684) (xy 20.55241 -442.860684)
			)
		)
		(polygon
			(pts
				(xy 20.55241 -441.552838) (xy 18.64741 -441.552838) (xy 18.64741 -442.060838) (xy 20.55241 -442.060838)
			)
		)
		(polygon
			(pts
				(arc
					(start 28.373832 -441.830968)
					(mid 27.898375 -441.269631)
					(end 27.248358 -441.614052)
				)
				(xy 27.248358 -441.414154) (xy 25.341072 -441.414154) (xy 25.341072 -442.280294) (xy 27.208734 -442.280294)
				(xy 27.209496 -442.303154) (xy 25.341072 -442.303154) (xy 25.341072 -443.169294) (xy 27.248358 -443.169294)
				(arc
					(start 27.248358 -443.021974)
					(mid 27.900946 -443.441736)
					(end 28.399232 -442.846968)
				)
				(xy 28.401772 -442.846968) (xy 28.376372 -441.830968)
			)
		)
		(polygon
			(pts
				(arc
					(start 11.938 -441.81014)
					(mid 12.52474 -441.2234)
					(end 11.938 -440.63666)
				)
				(arc
					(start 11.0744 -440.63666)
					(mid 10.48766 -441.2234)
					(end 11.0744 -441.81014)
				)
			)
		)
		(polygon
			(pts
				(arc
					(start 12.239498 -438.105042)
					(mid 11.652758 -437.518302)
					(end 11.066018 -438.105042)
				)
				(arc
					(start 11.066018 -439.033412)
					(mid 11.652885 -439.619898)
					(end 12.239498 -439.033158)
				)
			)
		)
		(polygon
			(pts
				(xy 4.995672 -424.14444) (xy 1.388872 -424.14444) (xy 1.388872 -424.85564) (xy 4.995672 -424.85564)
			)
		)
		(polygon
			(pts
				(xy 7.423912 -423.515536)
				(arc
					(start 7.423658 -423.518076)
					(mid 6.856476 -424.020742)
					(end 7.359142 -424.587924)
				)
				(xy 7.358888 -424.590464) (xy 8.22071 -424.642788) (xy 8.220964 -424.642534)
				(arc
					(start 8.221218 -424.640248)
					(mid 8.7884 -424.137582)
					(end 8.285734 -423.5704)
				)
				(xy 8.285988 -423.56786)
			)
		)
		(polygon
			(pts
				(xy 4.995672 -423.144442) (xy 1.388872 -423.144442) (xy 1.388872 -423.855642) (xy 4.995672 -423.855642)
			)
		)
		(polygon
			(pts
				(xy 8.142224 -421.362632) (xy 7.278878 -421.34028)
				(arc
					(start 7.278878 -421.34282)
					(mid 6.703314 -421.889428)
					(end 7.249922 -422.464992)
				)
				(xy 7.249922 -422.467532) (xy 8.113014 -422.489884) (xy 8.113268 -422.48963)
				(arc
					(start 8.113268 -422.487344)
					(mid 8.688832 -421.940736)
					(end 8.142224 -421.365172)
				)
			)
		)
		(polygon
			(pts
				(xy 4.995672 -420.144448) (xy 1.388872 -420.144448) (xy 1.388872 -420.855648) (xy 4.995672 -420.855648)
			)
		)
		(polygon
			(pts
				(xy 4.995672 -419.14445) (xy 1.388872 -419.14445) (xy 1.388872 -419.85565) (xy 4.995672 -419.85565)
			)
		)
		(polygon
			(pts
				(arc
					(start 7.53364 -417.243768)
					(mid 6.93852 -417.821999)
					(end 7.516622 -418.417248)
				)
				(arc
					(start 8.380222 -418.429694)
					(mid 8.975344 -417.851336)
					(end 8.396986 -417.256214)
				)
			)
		)
		(polygon
			(pts
				(xy 4.995672 -416.144456) (xy 1.388872 -416.144456) (xy 1.388872 -416.855656) (xy 4.995672 -416.855656)
			)
		)
		(polygon
			(pts
				(xy 4.995672 -415.144458) (xy 1.388872 -415.144458) (xy 1.388872 -415.855658) (xy 4.995672 -415.855658)
			)
		)
		(polygon
			(pts
				(arc
					(start 8.581898 -414.041336)
					(mid 8.779764 -413.272478)
					(end 8.010906 -413.074612)
				)
				(arc
					(start 7.215886 -413.544512)
					(mid 7.007016 -414.313851)
					(end 7.778242 -414.516062)
				)
			)
		)
		(polygon
			(pts
				(xy 4.995672 -412.144464) (xy 1.388872 -412.144464) (xy 1.388872 -412.855664) (xy 4.995672 -412.855664)
			)
		)
		(polygon
			(pts
				(xy 4.995672 -411.144466) (xy 1.388872 -411.144466) (xy 1.388872 -411.855666) (xy 4.995672 -411.855666)
			)
		)
		(polygon
			(pts
				(arc
					(start 8.203946 -410.396436)
					(mid 8.765286 -409.835096)
					(end 8.203946 -409.273756)
				)
				(arc
					(start 7.340346 -409.273756)
					(mid 6.779006 -409.835096)
					(end 7.340346 -410.396436)
				)
			)
		)
		(polygon
			(pts
				(xy 4.995672 -408.144472) (xy 1.388872 -408.144472) (xy 1.388872 -408.855672) (xy 4.995672 -408.855672)
			)
		)
		(polygon
			(pts
				(xy 4.995672 -407.144474) (xy 1.388872 -407.144474) (xy 1.388872 -407.855674) (xy 4.995672 -407.855674)
			)
		)
		(polygon
			(pts
				(arc
					(start 7.77875 -399.884138)
					(mid 8.335766 -399.273649)
					(end 7.725156 -398.716754)
				)
				(arc
					(start 6.862318 -398.756378)
					(mid 6.30555 -399.366994)
					(end 6.916166 -399.923762)
				)
			)
		)
		(polygon
			(pts
				(xy 4.995672 -395.144498) (xy 1.388872 -395.144498) (xy 1.388872 -395.855698) (xy 4.995672 -395.855698)
			)
		)
		(polygon
			(pts
				(xy 4.995672 -394.1445) (xy 1.388872 -394.1445) (xy 1.388872 -394.8557) (xy 4.995672 -394.8557)
			)
		)
		(polygon
			(pts
				(xy 4.995672 -386.144516) (xy 1.388872 -386.144516) (xy 1.388872 -386.855716) (xy 4.995672 -386.855716)
			)
		)
		(polygon
			(pts
				(xy 4.995672 -385.144518) (xy 1.388872 -385.144518) (xy 1.388872 -385.855718) (xy 4.995672 -385.855718)
			)
		)
		(polygon
			(pts
				(arc
					(start 8.689086 -385.53263)
					(mid 8.127619 -384.971544)
					(end 7.566406 -385.532884)
				)
				(arc
					(start 7.566406 -386.461)
					(mid 8.127746 -387.02234)
					(end 8.689086 -386.461)
				)
			)
		)
		(polygon
			(pts
				(arc
					(start 7.675626 -383.436368)
					(mid 7.063238 -383.996311)
					(end 7.623048 -384.608832)
				)
				(arc
					(start 8.485886 -384.647186)
					(mid 9.09828 -384.087116)
					(end 8.53821 -383.474722)
				)
			)
		)
		(polygon
			(pts
				(xy 4.995672 -382.144524) (xy 1.388872 -382.144524) (xy 1.388872 -382.855724) (xy 4.995672 -382.855724)
			)
		)
		(polygon
			(pts
				(xy 4.995672 -381.144526) (xy 1.388872 -381.144526) (xy 1.388872 -381.855726) (xy 4.995672 -381.855726)
			)
		)
		(polygon
			(pts
				(arc
					(start 8.661146 -380.96444)
					(mid 9.247886 -380.3777)
					(end 8.661146 -379.79096)
				)
				(arc
					(start 7.746746 -379.79096)
					(mid 7.160006 -380.3777)
					(end 7.746746 -380.96444)
				)
			)
		)
		(polygon
			(pts
				(xy 4.995672 -378.144532) (xy 1.388872 -378.144532) (xy 1.388872 -378.855732) (xy 4.995672 -378.855732)
			)
		)
		(polygon
			(pts
				(xy 4.995672 -377.144534) (xy 1.388872 -377.144534) (xy 1.388872 -377.855734) (xy 4.995672 -377.855734)
			)
		)
		(polygon
			(pts
				(arc
					(start 8.810498 -376.880374)
					(mid 9.287002 -376.291094)
					(end 8.697722 -375.81459)
				)
				(xy 8.697468 -375.81205) (xy 7.817104 -375.905268)
				(arc
					(start 7.817358 -375.907808)
					(mid 7.340854 -376.497088)
					(end 7.930134 -376.973592)
				)
				(xy 7.930388 -376.976132) (xy 8.810498 -376.882914) (xy 8.810752 -376.88266)
			)
		)
		(polygon
			(pts
				(xy 4.995672 -374.14454) (xy 1.388872 -374.14454) (xy 1.388872 -374.85574) (xy 4.995672 -374.85574)
			)
		)
		(polygon
			(pts
				(xy 4.995672 -373.144542) (xy 1.388872 -373.144542) (xy 1.388872 -373.855742) (xy 4.995672 -373.855742)
			)
		)
		(polygon
			(pts
				(xy 226.3521 -372.932706) (xy 224.4471 -372.932706) (xy 224.4471 -373.440706) (xy 226.3521 -373.440706)
			)
		)
		(polygon
			(pts
				(xy 41.352216 -372.932706) (xy 39.447216 -372.932706) (xy 39.447216 -373.440706) (xy 41.352216 -373.440706)
			)
		)
		(polygon
			(pts
				(xy 219.093796 -372.766082) (xy 217.18651 -372.766082) (xy 217.18651 -373.632222) (xy 219.093796 -373.632222)
			)
		)
		(polygon
			(pts
				(xy 226.3521 -372.13286) (xy 224.4471 -372.13286) (xy 224.4471 -372.64086) (xy 226.3521 -372.64086)
			)
		)
		(polygon
			(pts
				(xy 41.352216 -372.13286) (xy 39.447216 -372.13286) (xy 39.447216 -372.64086) (xy 41.352216 -372.64086)
			)
		)
		(polygon
			(pts
				(xy 219.093796 -371.877082) (xy 217.18651 -371.877082) (xy 217.18651 -372.743222) (xy 219.093796 -372.743222)
			)
		)
		(polygon
			(pts
				(arc
					(start 216.490804 -373.038624)
					(mid 217.067892 -372.442232)
					(end 216.4715 -371.865144)
				)
				(arc
					(start 215.608154 -371.879368)
					(mid 215.031064 -372.475633)
					(end 215.627204 -373.052848)
				)
			)
		)
		(polygon
			(pts
				(arc
					(start 31.917894 -371.866668)
					(mid 31.28565 -371.611851)
					(end 30.914848 -372.183914)
				)
				(xy 30.912308 -372.184168) (xy 31.034736 -373.248428) (xy 31.03499 -373.248682)
				(arc
					(start 31.037276 -373.248428)
					(mid 31.373351 -373.685855)
					(end 31.917386 -373.594884)
				)
				(xy 31.917386 -373.621808) (xy 33.824672 -373.621808) (xy 33.824672 -372.755668) (xy 32.061912 -372.755668)
				(xy 32.059372 -372.732808) (xy 33.824672 -372.732808) (xy 33.824672 -371.866668)
			)
		)
		(polygon
			(pts
				(arc
					(start 7.74319 -370.89334)
					(mid 7.13004 -371.452521)
					(end 7.689088 -372.065804)
				)
				(arc
					(start 8.587486 -372.107206)
					(mid 9.200642 -371.547898)
					(end 8.641334 -370.934742)
				)
			)
		)
		(polygon
			(pts
				(xy 226.3521 -370.53266) (xy 224.4471 -370.53266) (xy 224.4471 -371.04066) (xy 226.3521 -371.04066)
			)
		)
		(polygon
			(pts
				(xy 41.352216 -370.53266) (xy 39.447216 -370.53266) (xy 39.447216 -371.04066) (xy 41.352216 -371.04066)
			)
		)
		(polygon
			(pts
				(xy 4.995672 -370.144548) (xy 1.388872 -370.144548) (xy 1.388872 -370.855748) (xy 4.995672 -370.855748)
			)
		)
		(polygon
			(pts
				(xy 226.3521 -369.732814) (xy 224.4471 -369.732814) (xy 224.4471 -370.240814) (xy 226.3521 -370.240814)
			)
		)
		(polygon
			(pts
				(xy 41.352216 -369.732814) (xy 39.447216 -369.732814) (xy 39.447216 -370.240814) (xy 41.352216 -370.240814)
			)
		)
		(polygon
			(pts
				(arc
					(start 223.61144 -369.971574)
					(mid 223.058863 -369.352569)
					(end 222.439992 -369.90528)
				)
				(xy 222.437452 -369.905026) (xy 222.386398 -370.80444)
				(arc
					(start 222.388938 -370.804694)
					(mid 222.941642 -371.423438)
					(end 223.560386 -370.870734)
				)
				(xy 223.562926 -370.870988) (xy 223.61398 -369.971828) (xy 223.613726 -369.971574)
			)
		)
		(polygon
			(pts
				(arc
					(start 36.908232 -369.934744)
					(mid 36.337748 -369.332256)
					(end 35.73526 -369.90274)
				)
				(xy 35.73272 -369.90274) (xy 35.707574 -370.823998)
				(arc
					(start 35.710114 -370.823998)
					(mid 36.280598 -371.426486)
					(end 36.883086 -370.856002)
				)
				(xy 36.885626 -370.856002) (xy 36.910772 -369.934998) (xy 36.910518 -369.934744)
			)
		)
		(polygon
			(pts
				(xy 4.995672 -369.14455) (xy 1.388872 -369.14455) (xy 1.388872 -369.85575) (xy 4.995672 -369.85575)
			)
		)
		(polygon
			(pts
				(arc
					(start 7.312914 -367.331752)
					(mid 6.753606 -367.843308)
					(end 7.265162 -368.402616)
				)
				(arc
					(start 8.127746 -368.441224)
					(mid 8.687314 -367.929795)
					(end 8.175752 -367.37036)
				)
			)
		)
		(polygon
			(pts
				(xy 224.443544 -366.81664) (xy 222.055944 -366.81664) (xy 222.055944 -367.47704) (xy 224.443544 -367.47704)
			)
		)
		(polygon
			(pts
				(xy 39.44366 -366.81664) (xy 37.05606 -366.81664) (xy 37.05606 -367.47704) (xy 39.44366 -367.47704)
			)
		)
		(polygon
			(pts
				(xy 33.824672 -366.532668) (xy 31.917386 -366.532668) (xy 31.917386 -367.398808) (xy 33.824672 -367.398808)
			)
		)
		(polygon
			(pts
				(xy 219.093796 -366.416082) (xy 217.18651 -366.416082) (xy 217.18651 -367.282222) (xy 219.093796 -367.282222)
			)
		)
		(polygon
			(pts
				(xy 4.995672 -366.144556) (xy 1.388872 -366.144556) (xy 1.388872 -366.855756) (xy 4.995672 -366.855756)
			)
		)
		(polygon
			(pts
				(xy 33.824672 -365.643668) (xy 31.917386 -365.643668) (xy 31.917386 -366.509808) (xy 33.824672 -366.509808)
			)
		)
		(polygon
			(pts
				(xy 224.443544 -365.54664) (xy 222.055944 -365.54664) (xy 222.055944 -366.20704) (xy 224.443544 -366.20704)
			)
		)
		(polygon
			(pts
				(xy 39.44366 -365.54664) (xy 37.05606 -365.54664) (xy 37.05606 -366.20704) (xy 39.44366 -366.20704)
			)
		)
		(polygon
			(pts
				(xy 219.093796 -365.527082) (xy 217.18651 -365.527082) (xy 217.18651 -366.393222) (xy 219.093796 -366.393222)
			)
		)
		(polygon
			(pts
				(arc
					(start 27.24023 -365.912654)
					(mid 26.644981 -365.334548)
					(end 26.06675 -365.929672)
				)
				(arc
					(start 26.083006 -367.02365)
					(mid 26.678382 -367.601754)
					(end 27.256486 -367.006378)
				)
			)
		)
		(polygon
			(pts
				(xy 4.995672 -365.144558) (xy 1.388872 -365.144558) (xy 1.388872 -365.855758) (xy 4.995672 -365.855758)
			)
		)
		(polygon
			(pts
				(arc
					(start 8.804148 -364.27283)
					(mid 8.889746 -363.447584)
					(end 8.0645 -363.361986)
				)
				(xy 8.062976 -363.359954) (xy 7.375398 -363.918246)
				(arc
					(start 7.376922 -363.920278)
					(mid 7.291324 -364.745524)
					(end 8.11657 -364.831122)
				)
				(xy 8.118094 -364.833154) (xy 8.805672 -364.275116) (xy 8.805672 -364.274608)
			)
		)
		(polygon
			(pts
				(xy 224.443544 -363.00664) (xy 222.055944 -363.00664) (xy 222.055944 -363.66704) (xy 224.443544 -363.66704)
			)
		)
		(polygon
			(pts
				(xy 39.44366 -363.00664) (xy 37.05606 -363.00664) (xy 37.05606 -363.66704) (xy 39.44366 -363.66704)
			)
		)
		(polygon
			(pts
				(xy 4.995672 -362.144564) (xy 1.388872 -362.144564) (xy 1.388872 -362.855764) (xy 4.995672 -362.855764)
			)
		)
		(polygon
			(pts
				(xy 224.443544 -361.73664) (xy 222.055944 -361.73664) (xy 222.055944 -362.39704) (xy 224.443544 -362.39704)
			)
		)
		(polygon
			(pts
				(xy 39.44366 -361.73664) (xy 37.05606 -361.73664) (xy 37.05606 -362.39704) (xy 39.44366 -362.39704)
			)
		)
		(polygon
			(pts
				(arc
					(start 30.4038 -362.2548)
					(mid 29.816933 -361.668314)
					(end 29.23032 -362.255054)
				)
				(arc
					(start 29.23032 -363.213904)
					(mid 29.81706 -363.800644)
					(end 30.4038 -363.213904)
				)
			)
		)
		(polygon
			(pts
				(xy 4.995672 -361.144566) (xy 1.388872 -361.144566) (xy 1.388872 -361.855766) (xy 4.995672 -361.855766)
			)
		)
		(polygon
			(pts
				(xy 4.995672 -358.144318) (xy 1.388872 -358.144318) (xy 1.388872 -358.855518) (xy 4.995672 -358.855518)
			)
		)
		(polygon
			(pts
				(arc
					(start 8.256524 -359.096818)
					(mid 8.8265 -358.498902)
					(end 8.228584 -357.928926)
				)
				(xy 8.228584 -357.926386) (xy 7.351776 -357.947214)
				(arc
					(start 7.351776 -357.949754)
					(mid 6.7818 -358.54767)
					(end 7.379716 -359.117646)
				)
				(xy 7.379716 -359.120186) (xy 8.25627 -359.099358) (xy 8.256524 -359.099104)
			)
		)
		(polygon
			(pts
				(arc
					(start 8.446516 -353.441508)
					(mid 8.750808 -352.669348)
					(end 7.978648 -352.365056)
				)
				(xy 7.977632 -352.36277) (xy 7.00405 -352.786188) (xy 7.003796 -352.786442)
				(arc
					(start 7.004812 -352.788728)
					(mid 6.70054 -353.560934)
					(end 7.47268 -353.864926)
				)
				(xy 7.473696 -353.867212) (xy 8.447532 -353.443794)
			)
		)
		(polygon
			(pts
				(xy 4.995672 -352.144076) (xy 1.388872 -352.144076) (xy 1.388872 -352.855276) (xy 4.995672 -352.855276)
			)
		)
		(polygon
			(pts
				(xy 4.995672 -351.144078) (xy 1.388872 -351.144078) (xy 1.388872 -351.855278) (xy 4.995672 -351.855278)
			)
		)
		(polygon
			(pts
				(xy 22.943566 -349.596456) (xy 20.555966 -349.596456) (xy 20.555966 -350.256856) (xy 22.943566 -350.256856)
			)
		)
		(polygon
			(pts
				(xy 22.943566 -348.326456) (xy 20.555966 -348.326456) (xy 20.555966 -348.986856) (xy 22.943566 -348.986856)
			)
		)
		(polygon
			(pts
				(arc
					(start 25.282144 -348.859348)
					(mid 24.727789 -348.241881)
					(end 24.110188 -348.796102)
				)
				(arc
					(start 24.052022 -349.878904)
					(mid 24.606504 -350.496378)
					(end 25.223978 -349.941896)
				)
			)
		)
		(polygon
			(pts
				(xy 4.995672 -348.144084) (xy 1.388872 -348.144084) (xy 1.388872 -348.855284) (xy 4.995672 -348.855284)
			)
		)
		(polygon
			(pts
				(xy 4.995672 -347.144086) (xy 1.388872 -347.144086) (xy 1.388872 -347.855286) (xy 4.995672 -347.855286)
			)
		)
		(polygon
			(pts
				(arc
					(start 7.075932 -347.594174)
					(mid 6.500241 -347.001594)
					(end 5.907532 -347.577156)
				)
				(arc
					(start 5.894578 -348.491048)
					(mid 6.470396 -349.08363)
					(end 7.062978 -348.507812)
				)
			)
		)
		(polygon
			(pts
				(xy 22.943566 -345.786456) (xy 20.555966 -345.786456) (xy 20.555966 -346.446856) (xy 22.943566 -346.446856)
			)
		)
		(polygon
			(pts
				(xy 27.839924 -345.504262) (xy 25.932638 -345.504262) (xy 25.932638 -346.370402) (xy 27.839924 -346.370402)
			)
		)
		(polygon
			(pts
				(xy 27.839924 -344.615262) (xy 25.932638 -344.615262) (xy 25.932638 -345.481402) (xy 27.839924 -345.481402)
			)
		)
		(polygon
			(pts
				(xy 22.943566 -344.516456) (xy 20.555966 -344.516456) (xy 20.555966 -345.176856) (xy 22.943566 -345.176856)
			)
		)
		(polygon
			(pts
				(arc
					(start 29.138626 -344.885518)
					(mid 28.463364 -344.403151)
					(end 27.980894 -345.078304)
				)
				(arc
					(start 28.12288 -345.93022)
					(mid 28.798266 -346.412566)
					(end 29.280612 -345.73718)
				)
			)
		)
		(polygon
			(pts
				(xy 20.55241 -341.752682) (xy 18.64741 -341.752682) (xy 18.64741 -342.260682) (xy 20.55241 -342.260682)
			)
		)
		(polygon
			(pts
				(xy 20.55241 -340.952836) (xy 18.64741 -340.952836) (xy 18.64741 -341.460836) (xy 20.55241 -341.460836)
			)
		)
		(polygon
			(pts
				(arc
					(start 26.420318 -341.096854)
					(mid 25.778027 -340.958636)
					(end 25.41016 -341.503)
				)
				(arc
					(start 25.41016 -342.431116)
					(mid 25.768387 -342.971529)
					(end 26.405586 -342.851994)
				)
				(xy 28.251912 -342.851994)
				(arc
					(start 28.251912 -342.537034)
					(mid 28.882178 -343.015429)
					(end 29.41574 -342.431116)
				)
				(arc
					(start 29.41574 -341.502746)
					(mid 28.882053 -340.918663)
					(end 28.251912 -341.397082)
				)
				(xy 28.251912 -341.096854)
			)
		)
		(polygon
			(pts
				(arc
					(start 22.65426 -341.08644)
					(mid 22.07006 -340.50224)
					(end 21.48586 -341.08644)
				)
				(arc
					(start 21.48586 -342.045544)
					(mid 22.070187 -342.62949)
					(end 22.65426 -342.04529)
				)
			)
		)
		(polygon
			(pts
				(xy 20.55241 -339.352636) (xy 18.64741 -339.352636) (xy 18.64741 -339.860636) (xy 20.55241 -339.860636)
			)
		)
		(polygon
			(pts
				(xy 26.950924 -339.154262) (xy 25.043638 -339.154262) (xy 25.043638 -340.020402) (xy 26.950924 -340.020402)
			)
		)
		(polygon
			(pts
				(xy 20.55241 -338.55279) (xy 18.64741 -338.55279) (xy 18.64741 -339.06079) (xy 20.55241 -339.06079)
			)
		)
		(polygon
			(pts
				(xy 26.950924 -338.265262) (xy 25.043638 -338.265262) (xy 25.043638 -339.131402) (xy 26.950924 -339.131402)
			)
		)
		(polygon
			(pts
				(arc
					(start 28.330652 -338.66201)
					(mid 27.743912 -338.07527)
					(end 27.157172 -338.66201)
				)
				(arc
					(start 27.157172 -339.621114)
					(mid 27.744039 -340.2076)
					(end 28.330652 -339.62086)
				)
			)
		)
		(polygon
			(pts
				(xy 34.220912 -274.167854) (xy 32.313626 -274.167854) (xy 32.313626 -275.033994) (xy 34.220912 -275.033994)
			)
		)
		(polygon
			(pts
				(xy 34.220912 -273.278854) (xy 32.313626 -273.278854) (xy 32.313626 -274.144994) (xy 34.220912 -274.144994)
			)
		)
		(polygon
			(pts
				(arc
					(start 35.506914 -273.700494)
					(mid 34.921063 -273.112992)
					(end 34.333434 -273.698716)
				)
				(arc
					(start 34.332418 -274.618196)
					(mid 34.918396 -275.205698)
					(end 35.505898 -274.61972)
				)
				(xy 35.505898 -274.618196)
			)
		)
		(polygon
			(pts
				(arc
					(start 32.190182 -273.690588)
					(mid 31.603315 -273.104102)
					(end 31.016702 -273.690842)
				)
				(arc
					(start 31.016702 -274.618958)
					(mid 31.603442 -275.205698)
					(end 32.190182 -274.618958)
				)
			)
		)
		(polygon
			(pts
				(xy 226.3521 -269.932658) (xy 224.4471 -269.932658) (xy 224.4471 -270.440658) (xy 226.3521 -270.440658)
			)
		)
		(polygon
			(pts
				(xy 41.352216 -269.932658) (xy 39.447216 -269.932658) (xy 39.447216 -270.440658) (xy 41.352216 -270.440658)
			)
		)
		(polygon
			(pts
				(xy 218.712796 -269.921482) (xy 216.80551 -269.921482) (xy 216.80551 -270.787622) (xy 218.712796 -270.787622)
			)
		)
		(polygon
			(pts
				(xy 34.233358 -269.710154) (xy 32.326072 -269.710154) (xy 32.326072 -270.576294) (xy 34.233358 -270.576294)
			)
		)
		(polygon
			(pts
				(xy 226.3521 -269.132812) (xy 224.4471 -269.132812) (xy 224.4471 -269.640812) (xy 226.3521 -269.640812)
			)
		)
		(polygon
			(pts
				(xy 41.352216 -269.132812) (xy 39.447216 -269.132812) (xy 39.447216 -269.640812) (xy 41.352216 -269.640812)
			)
		)
		(polygon
			(pts
				(xy 218.712796 -269.032482) (xy 216.80551 -269.032482) (xy 216.80551 -269.898622) (xy 218.712796 -269.898622)
			)
		)
		(polygon
			(pts
				(arc
					(start 216.11971 -270.192754)
					(mid 216.69832 -269.597759)
					(end 216.1032 -269.019274)
				)
				(arc
					(start 215.1888 -269.032228)
					(mid 214.610442 -269.62735)
					(end 215.205564 -270.205708)
				)
			)
		)
		(polygon
			(pts
				(xy 34.233358 -268.821154) (xy 32.326072 -268.821154) (xy 32.326072 -269.687294) (xy 34.233358 -269.687294)
			)
		)
		(polygon
			(pts
				(xy 226.3521 -267.532612) (xy 224.4471 -267.532612) (xy 224.4471 -268.040612) (xy 226.3521 -268.040612)
			)
		)
		(polygon
			(pts
				(xy 41.352216 -267.532612) (xy 39.447216 -267.532612) (xy 39.447216 -268.040612) (xy 41.352216 -268.040612)
			)
		)
		(polygon
			(pts
				(xy 226.3521 -266.732766) (xy 224.4471 -266.732766) (xy 224.4471 -267.240766) (xy 226.3521 -267.240766)
			)
		)
		(polygon
			(pts
				(xy 41.352216 -266.732766) (xy 39.447216 -266.732766) (xy 39.447216 -267.240766) (xy 41.352216 -267.240766)
			)
		)
		(polygon
			(pts
				(arc
					(start 223.656144 -267.024866)
					(mid 223.11779 -266.393432)
					(end 222.48622 -266.931648)
				)
				(arc
					(start 222.417894 -267.792708)
					(mid 222.956374 -268.424152)
					(end 223.587818 -267.885672)
				)
			)
		)
		(polygon
			(pts
				(arc
					(start 32.082486 -266.8651)
					(mid 31.495746 -266.27836)
					(end 30.909006 -266.8651)
				)
				(arc
					(start 30.909006 -267.728954)
					(mid 31.495873 -268.31544)
					(end 32.082486 -267.7287)
				)
			)
		)
		(polygon
			(pts
				(xy 224.443544 -263.816592) (xy 222.055944 -263.816592) (xy 222.055944 -264.476992) (xy 224.443544 -264.476992)
			)
		)
		(polygon
			(pts
				(xy 39.44366 -263.816592) (xy 37.05606 -263.816592) (xy 37.05606 -264.476992) (xy 39.44366 -264.476992)
			)
		)
		(polygon
			(pts
				(xy 218.712796 -263.571482) (xy 216.80551 -263.571482) (xy 216.80551 -264.437622) (xy 218.712796 -264.437622)
			)
		)
		(polygon
			(pts
				(xy 34.233358 -263.487154) (xy 32.326072 -263.487154) (xy 32.326072 -264.353294) (xy 34.233358 -264.353294)
			)
		)
		(polygon
			(pts
				(xy 218.712796 -262.682482) (xy 216.80551 -262.682482) (xy 216.80551 -263.548622) (xy 218.712796 -263.548622)
			)
		)
		(polygon
			(pts
				(xy 34.233358 -262.598154) (xy 32.326072 -262.598154) (xy 32.326072 -263.464294) (xy 34.233358 -263.464294)
			)
		)
		(polygon
			(pts
				(xy 224.443544 -262.546592) (xy 222.055944 -262.546592) (xy 222.055944 -263.206992) (xy 224.443544 -263.206992)
			)
		)
		(polygon
			(pts
				(xy 39.44366 -262.546592) (xy 37.05606 -262.546592) (xy 37.05606 -263.206992) (xy 39.44366 -263.206992)
			)
		)
		(polygon
			(pts
				(xy 224.443544 -260.006592) (xy 222.055944 -260.006592) (xy 222.055944 -260.666992) (xy 224.443544 -260.666992)
			)
		)
		(polygon
			(pts
				(xy 39.44366 -260.006592) (xy 37.05606 -260.006592) (xy 37.05606 -260.666992) (xy 39.44366 -260.666992)
			)
		)
		(polygon
			(pts
				(xy 224.443544 -258.736592) (xy 222.055944 -258.736592) (xy 222.055944 -259.396992) (xy 224.443544 -259.396992)
			)
		)
		(polygon
			(pts
				(xy 39.44366 -258.736592) (xy 37.05606 -258.736592) (xy 37.05606 -259.396992) (xy 39.44366 -259.396992)
			)
		)
		(polygon
			(pts
				(xy 22.943566 -246.596408) (xy 20.555966 -246.596408) (xy 20.555966 -247.256808) (xy 22.943566 -247.256808)
			)
		)
		(polygon
			(pts
				(xy 22.943566 -245.326408) (xy 20.555966 -245.326408) (xy 20.555966 -245.986808) (xy 22.943566 -245.986808)
			)
		)
		(polygon
			(pts
				(xy 22.943566 -242.786408) (xy 20.555966 -242.786408) (xy 20.555966 -243.446808) (xy 22.943566 -243.446808)
			)
		)
		(polygon
			(pts
				(xy 27.514042 -242.51666) (xy 25.606756 -242.51666) (xy 25.606756 -243.3828) (xy 27.514042 -243.3828)
			)
		)
		(polygon
			(pts
				(xy 27.514042 -241.62766) (xy 25.606756 -241.62766) (xy 25.606756 -242.4938) (xy 27.514042 -242.4938)
			)
		)
		(polygon
			(pts
				(xy 22.943566 -241.516408) (xy 20.555966 -241.516408) (xy 20.555966 -242.176808) (xy 22.943566 -242.176808)
			)
		)
		(polygon
			(pts
				(xy 20.55241 -238.752634) (xy 18.64741 -238.752634) (xy 18.64741 -239.260634) (xy 20.55241 -239.260634)
			)
		)
		(polygon
			(pts
				(xy 20.55241 -237.952788) (xy 18.64741 -237.952788) (xy 18.64741 -238.460788) (xy 20.55241 -238.460788)
			)
		)
		(polygon
			(pts
				(arc
					(start 22.528022 -238.079788)
					(mid 22.014434 -237.428024)
					(end 21.36267 -237.941612)
				)
				(arc
					(start 21.26107 -238.799624)
					(mid 21.774529 -239.451657)
					(end 22.426422 -238.938054)
				)
			)
		)
		(polygon
			(pts
				(xy 20.55241 -236.352588) (xy 18.64741 -236.352588) (xy 18.64741 -236.860588) (xy 20.55241 -236.860588)
			)
		)
		(polygon
			(pts
				(xy 26.752042 -236.16666) (xy 24.844756 -236.16666) (xy 24.844756 -237.0328) (xy 26.752042 -237.0328)
			)
		)
		(polygon
			(pts
				(xy 20.55241 -235.552742) (xy 18.64741 -235.552742) (xy 18.64741 -236.060742) (xy 20.55241 -236.060742)
			)
		)
		(polygon
			(pts
				(xy 26.752042 -235.27766) (xy 24.844756 -235.27766) (xy 24.844756 -236.1438) (xy 26.752042 -236.1438)
			)
		)
		(polygon
			(pts
				(arc
					(start 28.296362 -235.819442)
					(mid 27.75496 -235.190547)
					(end 27.12593 -235.731812)
				)
				(arc
					(start 27.061414 -236.59719)
					(mid 27.602942 -237.226094)
					(end 28.231846 -236.684566)
				)
			)
		)
		(polygon
			(pts
				(arc
					(start 13.388086 -176.752504)
					(mid 12.823063 -176.149766)
					(end 12.220194 -176.714658)
				)
				(arc
					(start 12.192254 -177.578004)
					(mid 12.757404 -178.180746)
					(end 13.360146 -177.615596)
				)
			)
		)
		(polygon
			(pts
				(xy 4.995672 -170.14444) (xy 1.388872 -170.14444) (xy 1.388872 -170.85564) (xy 4.995672 -170.85564)
			)
		)
		(polygon
			(pts
				(xy 4.995672 -169.144442) (xy 1.388872 -169.144442) (xy 1.388872 -169.855642) (xy 4.995672 -169.855642)
			)
		)
		(polygon
			(pts
				(arc
					(start 7.619238 -169.531284)
					(mid 7.032371 -168.944798)
					(end 6.445758 -169.531538)
				)
				(arc
					(start 6.445758 -170.459654)
					(mid 7.032498 -171.046394)
					(end 7.619238 -170.459654)
				)
			)
		)
		(polygon
			(pts
				(arc
					(start 20.447 -169.33164)
					(mid 20.982686 -168.795573)
					(end 20.446746 -168.25976)
				)
				(arc
					(start 19.557746 -168.25976)
					(mid 19.021806 -168.7957)
					(end 19.557746 -169.33164)
				)
			)
		)
		(polygon
			(pts
				(xy 226.3521 -166.93261) (xy 224.4471 -166.93261) (xy 224.4471 -167.44061) (xy 226.3521 -167.44061)
			)
		)
		(polygon
			(pts
				(xy 41.352216 -166.93261) (xy 39.447216 -166.93261) (xy 39.447216 -167.44061) (xy 41.352216 -167.44061)
			)
		)
		(polygon
			(pts
				(xy 218.814396 -166.797482) (xy 216.90711 -166.797482) (xy 216.90711 -167.663622) (xy 218.814396 -167.663622)
			)
		)
		(polygon
			(pts
				(xy 34.852864 -166.716964) (xy 32.945578 -166.716964) (xy 32.945578 -167.583104) (xy 34.852864 -167.583104)
			)
		)
		(polygon
			(pts
				(xy 4.995672 -166.144448) (xy 1.388872 -166.144448) (xy 1.388872 -166.855648) (xy 4.995672 -166.855648)
			)
		)
		(polygon
			(pts
				(xy 226.3521 -166.132764) (xy 224.4471 -166.132764) (xy 224.4471 -166.640764) (xy 226.3521 -166.640764)
			)
		)
		(polygon
			(pts
				(xy 41.352216 -166.132764) (xy 39.447216 -166.132764) (xy 39.447216 -166.640764) (xy 41.352216 -166.640764)
			)
		)
		(polygon
			(pts
				(xy 218.814396 -165.908482) (xy 216.90711 -165.908482) (xy 216.90711 -166.774622) (xy 218.814396 -166.774622)
			)
		)
		(polygon
			(pts
				(arc
					(start 215.344756 -165.87724)
					(mid 214.747348 -166.453312)
					(end 215.32342 -167.05072)
				)
				(arc
					(start 216.186766 -167.066468)
					(mid 216.78443 -166.490523)
					(end 216.208356 -165.892988)
				)
			)
		)
		(polygon
			(pts
				(xy 34.852864 -165.827964) (xy 32.945578 -165.827964) (xy 32.945578 -166.694104) (xy 34.852864 -166.694104)
			)
		)
		(polygon
			(pts
				(xy 4.995672 -165.14445) (xy 1.388872 -165.14445) (xy 1.388872 -165.85565) (xy 4.995672 -165.85565)
			)
		)
		(polygon
			(pts
				(arc
					(start 7.374382 -165.563804)
					(mid 6.757924 -165.013894)
					(end 6.208014 -165.630352)
				)
				(xy 6.205474 -165.630606) (xy 6.272022 -166.797228)
				(arc
					(start 6.274562 -166.796974)
					(mid 6.89102 -167.346884)
					(end 7.44093 -166.730426)
				)
				(xy 7.44347 -166.730172) (xy 7.376922 -165.563804)
			)
		)
		(polygon
			(pts
				(xy 226.3521 -164.532564) (xy 224.4471 -164.532564) (xy 224.4471 -165.040564) (xy 226.3521 -165.040564)
			)
		)
		(polygon
			(pts
				(xy 41.352216 -164.532564) (xy 39.447216 -164.532564) (xy 39.447216 -165.040564) (xy 41.352216 -165.040564)
			)
		)
		(polygon
			(pts
				(xy 226.3521 -163.732718) (xy 224.4471 -163.732718) (xy 224.4471 -164.240718) (xy 226.3521 -164.240718)
			)
		)
		(polygon
			(pts
				(xy 41.352216 -163.732718) (xy 39.447216 -163.732718) (xy 39.447216 -164.240718) (xy 41.352216 -164.240718)
			)
		)
		(polygon
			(pts
				(arc
					(start 223.750124 -163.975288)
					(mid 223.163257 -163.388802)
					(end 222.576644 -163.975542)
				)
				(arc
					(start 222.576644 -164.934392)
					(mid 223.163384 -165.521132)
					(end 223.750124 -164.934392)
				)
			)
		)
		(polygon
			(pts
				(arc
					(start 37.223192 -163.92017)
					(mid 36.636325 -163.333684)
					(end 36.049712 -163.920424)
				)
				(arc
					(start 36.049712 -164.879274)
					(mid 36.636452 -165.466014)
					(end 37.223192 -164.879274)
				)
			)
		)
		(polygon
			(pts
				(arc
					(start 33.533334 -164.29355)
					(mid 33.94075 -163.570666)
					(end 33.217866 -163.16325)
				)
				(arc
					(start 32.361886 -163.402518)
					(mid 31.945616 -164.123487)
					(end 32.66948 -164.53485)
				)
			)
		)
		(polygon
			(pts
				(xy 4.995672 -162.144456) (xy 1.388872 -162.144456) (xy 1.388872 -162.855656) (xy 4.995672 -162.855656)
			)
		)
		(polygon
			(pts
				(xy 4.995672 -161.144458) (xy 1.388872 -161.144458) (xy 1.388872 -161.855658) (xy 4.995672 -161.855658)
			)
		)
		(polygon
			(pts
				(arc
					(start 7.332472 -161.531046)
					(mid 6.748145 -160.9471)
					(end 6.164072 -161.5313)
				)
				(arc
					(start 6.164072 -162.459416)
					(mid 6.748272 -163.043616)
					(end 7.332472 -162.459416)
				)
			)
		)
		(polygon
			(pts
				(arc
					(start 32.463486 -161.429446)
					(mid 31.876619 -160.84296)
					(end 31.290006 -161.4297)
				)
				(arc
					(start 31.290006 -162.2933)
					(mid 31.876746 -162.88004)
					(end 32.463486 -162.2933)
				)
			)
		)
		(polygon
			(pts
				(xy 224.443544 -160.816544) (xy 222.055944 -160.816544) (xy 222.055944 -161.476944) (xy 224.443544 -161.476944)
			)
		)
		(polygon
			(pts
				(xy 39.44366 -160.816544) (xy 37.05606 -160.816544) (xy 37.05606 -161.476944) (xy 39.44366 -161.476944)
			)
		)
		(polygon
			(pts
				(xy 218.814396 -160.574482) (xy 216.90711 -160.574482) (xy 216.90711 -161.440622) (xy 218.814396 -161.440622)
			)
		)
		(polygon
			(pts
				(xy 34.852864 -160.493964) (xy 32.945578 -160.493964) (xy 32.945578 -161.360104) (xy 34.852864 -161.360104)
			)
		)
		(polygon
			(pts
				(xy 218.814396 -159.685482) (xy 216.90711 -159.685482) (xy 216.90711 -160.551622) (xy 218.814396 -160.551622)
			)
		)
		(polygon
			(pts
				(xy 34.852864 -159.604964) (xy 32.945578 -159.604964) (xy 32.945578 -160.471104) (xy 34.852864 -160.471104)
			)
		)
		(polygon
			(pts
				(xy 224.443544 -159.546544) (xy 222.055944 -159.546544) (xy 222.055944 -160.206944) (xy 224.443544 -160.206944)
			)
		)
		(polygon
			(pts
				(xy 39.44366 -159.546544) (xy 37.05606 -159.546544) (xy 37.05606 -160.206944) (xy 39.44366 -160.206944)
			)
		)
		(polygon
			(pts
				(xy 4.995672 -158.144464) (xy 1.388872 -158.144464) (xy 1.388872 -158.855664) (xy 4.995672 -158.855664)
			)
		)
		(polygon
			(pts
				(xy 4.995672 -157.144466) (xy 1.388872 -157.144466) (xy 1.388872 -157.855666) (xy 4.995672 -157.855666)
			)
		)
		(polygon
			(pts
				(xy 224.443544 -157.006544) (xy 222.055944 -157.006544) (xy 222.055944 -157.666944) (xy 224.443544 -157.666944)
			)
		)
		(polygon
			(pts
				(xy 39.44366 -157.006544) (xy 37.05606 -157.006544) (xy 37.05606 -157.666944) (xy 39.44366 -157.666944)
			)
		)
		(polygon
			(pts
				(arc
					(start 7.568946 -157.531308)
					(mid 6.984619 -156.947362)
					(end 6.400546 -157.531562)
				)
				(arc
					(start 6.400546 -158.459678)
					(mid 6.984746 -159.043878)
					(end 7.568946 -158.459678)
				)
			)
		)
		(polygon
			(pts
				(xy 224.443544 -155.736544) (xy 222.055944 -155.736544) (xy 222.055944 -156.396944) (xy 224.443544 -156.396944)
			)
		)
		(polygon
			(pts
				(xy 39.44366 -155.736544) (xy 37.05606 -155.736544) (xy 37.05606 -156.396944) (xy 39.44366 -156.396944)
			)
		)
		(polygon
			(pts
				(xy 4.995672 -145.14449) (xy 1.388872 -145.14449) (xy 1.388872 -145.85569) (xy 4.995672 -145.85569)
			)
		)
		(polygon
			(pts
				(xy 4.995672 -144.144492) (xy 1.388872 -144.144492) (xy 1.388872 -144.855692) (xy 4.995672 -144.855692)
			)
		)
		(polygon
			(pts
				(xy 22.943566 -143.59636) (xy 20.555966 -143.59636) (xy 20.555966 -144.25676) (xy 22.943566 -144.25676)
			)
		)
		(polygon
			(pts
				(xy 22.943566 -142.32636) (xy 20.555966 -142.32636) (xy 20.555966 -142.98676) (xy 22.943566 -142.98676)
			)
		)
		(polygon
			(pts
				(xy 22.943566 -139.78636) (xy 20.555966 -139.78636) (xy 20.555966 -140.44676) (xy 22.943566 -140.44676)
			)
		)
		(polygon
			(pts
				(xy 26.980642 -139.519406) (xy 25.073356 -139.519406) (xy 25.073356 -140.385546) (xy 26.980642 -140.385546)
			)
		)
		(polygon
			(pts
				(xy 26.980642 -138.630406) (xy 25.073356 -138.630406) (xy 25.073356 -139.496546) (xy 26.980642 -139.496546)
			)
		)
		(polygon
			(pts
				(xy 22.943566 -138.51636) (xy 20.555966 -138.51636) (xy 20.555966 -139.17676) (xy 22.943566 -139.17676)
			)
		)
		(polygon
			(pts
				(xy 4.995672 -136.144508) (xy 1.388872 -136.144508) (xy 1.388872 -136.855708) (xy 4.995672 -136.855708)
			)
		)
		(polygon
			(pts
				(xy 20.55241 -135.752586) (xy 18.64741 -135.752586) (xy 18.64741 -136.260586) (xy 20.55241 -136.260586)
			)
		)
		(polygon
			(pts
				(xy 4.995672 -135.14451) (xy 1.388872 -135.14451) (xy 1.388872 -135.85571) (xy 4.995672 -135.85571)
			)
		)
		(polygon
			(pts
				(arc
					(start 15.827502 -135.675116)
					(mid 15.241651 -135.087614)
					(end 14.654022 -135.673338)
				)
				(arc
					(start 14.653006 -136.536938)
					(mid 15.238984 -137.12444)
					(end 15.826486 -136.538462)
				)
				(xy 15.826486 -136.5377) (xy 15.826486 -136.536938)
			)
		)
		(polygon
			(pts
				(xy 20.55241 -134.95274) (xy 18.64741 -134.95274) (xy 18.64741 -135.46074) (xy 20.55241 -135.46074)
			)
		)
		(polygon
			(pts
				(arc
					(start 22.481286 -135.191246)
					(mid 21.894419 -134.60476)
					(end 21.307806 -135.1915)
				)
				(arc
					(start 21.307806 -136.15035)
					(mid 21.894546 -136.73709)
					(end 22.481286 -136.15035)
				)
			)
		)
		(polygon
			(pts
				(xy 20.55241 -133.35254) (xy 18.64741 -133.35254) (xy 18.64741 -133.86054) (xy 20.55241 -133.86054)
			)
		)
		(polygon
			(pts
				(xy 27.107642 -133.169406) (xy 25.200356 -133.169406) (xy 25.200356 -134.035546) (xy 27.107642 -134.035546)
			)
		)
		(polygon
			(pts
				(arc
					(start 7.342886 -133.514338)
					(mid 6.756019 -132.927852)
					(end 6.169406 -133.514592)
				)
				(arc
					(start 6.169406 -134.442708)
					(mid 6.756146 -135.029448)
					(end 7.342886 -134.442708)
				)
			)
		)
		(polygon
			(pts
				(xy 20.55241 -132.552694) (xy 18.64741 -132.552694) (xy 18.64741 -133.060694) (xy 20.55241 -133.060694)
			)
		)
		(polygon
			(pts
				(xy 27.107642 -132.280406) (xy 25.200356 -132.280406) (xy 25.200356 -133.146546) (xy 27.107642 -133.146546)
			)
		)
		(polygon
			(pts
				(xy 4.995672 -132.144516) (xy 1.388872 -132.144516) (xy 1.388872 -132.855716) (xy 4.995672 -132.855716)
			)
		)
		(polygon
			(pts
				(xy 4.995672 -131.144518) (xy 1.388872 -131.144518) (xy 1.388872 -131.855718) (xy 4.995672 -131.855718)
			)
		)
		(polygon
			(pts
				(arc
					(start 9.857486 -131.514596)
					(mid 9.270619 -130.92811)
					(end 8.684006 -131.51485)
				)
				(arc
					(start 8.684006 -132.4737)
					(mid 9.270746 -133.06044)
					(end 9.857486 -132.4737)
				)
			)
		)
		(polygon
			(pts
				(arc
					(start 25.1206 -130.99034)
					(mid 25.70734 -130.4036)
					(end 25.1206 -129.81686)
				)
				(arc
					(start 24.257 -129.81686)
					(mid 23.67026 -130.4036)
					(end 24.257 -130.99034)
				)
			)
		)
		(polygon
			(pts
				(xy 4.995672 -128.144524) (xy 1.388872 -128.144524) (xy 1.388872 -128.855724) (xy 4.995672 -128.855724)
			)
		)
		(polygon
			(pts
				(xy 4.995672 -127.144526) (xy 1.388872 -127.144526) (xy 1.388872 -127.855726) (xy 4.995672 -127.855726)
			)
		)
		(polygon
			(pts
				(arc
					(start 7.292086 -127.49911)
					(mid 6.705219 -126.912624)
					(end 6.118606 -127.499364)
				)
				(arc
					(start 6.118606 -128.458214)
					(mid 6.705346 -129.044954)
					(end 7.292086 -128.458214)
				)
			)
		)
		(polygon
			(pts
				(xy 4.995672 -124.144532) (xy 1.388872 -124.144532) (xy 1.388872 -124.855732) (xy 4.995672 -124.855732)
			)
		)
		(polygon
			(pts
				(xy 4.995672 -123.144534) (xy 1.388872 -123.144534) (xy 1.388872 -123.855734) (xy 4.995672 -123.855734)
			)
		)
		(polygon
			(pts
				(arc
					(start 7.265416 -121.477532)
					(mid 6.642862 -120.929146)
					(end 6.094476 -121.5517)
				)
				(xy 6.091936 -121.551954) (xy 6.1468 -122.41403)
				(arc
					(start 6.14934 -122.413776)
					(mid 6.771894 -122.962162)
					(end 7.32028 -122.339608)
				)
				(xy 7.32282 -122.339354) (xy 7.267956 -121.477532) (xy 7.267702 -121.477278)
			)
		)
		(polygon
			(pts
				(xy 4.995672 -120.14454) (xy 1.388872 -120.14454) (xy 1.388872 -120.85574) (xy 4.995672 -120.85574)
			)
		)
		(polygon
			(pts
				(xy 4.995672 -119.144542) (xy 1.388872 -119.144542) (xy 1.388872 -119.855742) (xy 4.995672 -119.855742)
			)
		)
		(polygon
			(pts
				(arc
					(start 16.945102 -119.646954)
					(mid 16.359505 -119.059198)
					(end 15.771622 -119.644668)
				)
				(arc
					(start 15.770098 -120.508268)
					(mid 16.355822 -121.096024)
					(end 16.943578 -120.5103)
				)
				(xy 16.943578 -120.509284) (xy 16.943578 -120.508268)
			)
		)
		(polygon
			(pts
				(xy 4.995672 -116.144548) (xy 1.388872 -116.144548) (xy 1.388872 -116.855748) (xy 4.995672 -116.855748)
			)
		)
		(polygon
			(pts
				(xy 4.995672 -115.14455) (xy 1.388872 -115.14455) (xy 1.388872 -115.85575) (xy 4.995672 -115.85575)
			)
		)
		(polygon
			(pts
				(arc
					(start 7.418832 -115.548156)
					(mid 6.848602 -114.945414)
					(end 6.24586 -115.515644)
				)
				(xy 6.24332 -115.515644) (xy 6.21792 -116.441982)
				(arc
					(start 6.22046 -116.441982)
					(mid 6.294807 -116.744497)
					(end 6.513576 -116.966238)
				)
				(arc
					(start 6.513576 -116.966238)
					(mid 6.242247 -117.182704)
					(end 6.140704 -117.514624)
				)
				(arc
					(start 6.144006 -118.429532)
					(mid 6.732778 -119.01424)
					(end 7.317486 -118.425468)
				)
				(arc
					(start 7.314184 -117.510814)
					(mid 7.235055 -117.218568)
					(end 7.020814 -117.004592)
				)
				(arc
					(start 7.020814 -117.004592)
					(mid 7.286943 -116.795648)
					(end 7.393432 -116.474494)
				)
				(xy 7.395972 -116.474494) (xy 7.421372 -115.54841) (xy 7.421118 -115.548156)
			)
		)
		(polygon
			(pts
				(xy 4.995672 -112.144556) (xy 1.388872 -112.144556) (xy 1.388872 -112.855756) (xy 4.995672 -112.855756)
			)
		)
		(polygon
			(pts
				(xy 4.995672 -111.144558) (xy 1.388872 -111.144558) (xy 1.388872 -111.855758) (xy 4.995672 -111.855758)
			)
		)
		(polygon
			(pts
				(arc
					(start 7.315454 -111.576612)
					(mid 6.710553 -111.008664)
					(end 6.142482 -111.613442)
				)
				(arc
					(start 6.16966 -112.476788)
					(mid 6.774688 -113.044732)
					(end 7.342632 -112.439704)
				)
			)
		)
		(polygon
			(pts
				(xy 4.995672 -108.14431) (xy 1.388872 -108.14431) (xy 1.388872 -108.85551) (xy 4.995672 -108.85551)
			)
		)
		(polygon
			(pts
				(xy 4.995672 -102.144068) (xy 1.388872 -102.144068) (xy 1.388872 -102.855268) (xy 4.995672 -102.855268)
			)
		)
		(polygon
			(pts
				(xy 4.995672 -101.14407) (xy 1.388872 -101.14407) (xy 1.388872 -101.85527) (xy 4.995672 -101.85527)
			)
		)
		(polygon
			(pts
				(arc
					(start 7.266686 -101.4984)
					(mid 6.679819 -100.911914)
					(end 6.093206 -101.498654)
				)
				(arc
					(start 6.093206 -102.457504)
					(mid 6.679946 -103.044244)
					(end 7.266686 -102.457504)
				)
			)
		)
		(polygon
			(pts
				(xy 4.995672 -98.144076) (xy 1.388872 -98.144076) (xy 1.388872 -98.855276) (xy 4.995672 -98.855276)
			)
		)
		(polygon
			(pts
				(xy 4.995672 -97.144078) (xy 1.388872 -97.144078) (xy 1.388872 -97.855278) (xy 4.995672 -97.855278)
			)
		)
		(polygon
			(pts
				(arc
					(start 7.266686 -97.498662)
					(mid 6.679819 -96.912176)
					(end 6.093206 -97.498916)
				)
				(arc
					(start 6.093206 -98.457766)
					(mid 6.679946 -99.044506)
					(end 7.266686 -98.457766)
				)
			)
		)
		(polygon
			(pts
				(xy 226.3521 -63.932562) (xy 224.4471 -63.932562) (xy 224.4471 -64.440562) (xy 226.3521 -64.440562)
			)
		)
		(polygon
			(pts
				(xy 41.352216 -63.932562) (xy 39.447216 -63.932562) (xy 39.447216 -64.440562) (xy 41.352216 -64.440562)
			)
		)
		(polygon
			(pts
				(xy 33.979358 -63.716154) (xy 32.072072 -63.716154) (xy 32.072072 -64.582294) (xy 33.979358 -64.582294)
			)
		)
		(polygon
			(pts
				(xy 226.3521 -63.132716) (xy 224.4471 -63.132716) (xy 224.4471 -63.640716) (xy 226.3521 -63.640716)
			)
		)
		(polygon
			(pts
				(xy 41.352216 -63.132716) (xy 39.447216 -63.132716) (xy 39.447216 -63.640716) (xy 41.352216 -63.640716)
			)
		)
		(polygon
			(pts
				(xy 218.759024 -62.92215) (xy 216.851738 -62.92215) (xy 216.851738 -63.78829) (xy 218.759024 -63.78829)
			)
		)
		(polygon
			(pts
				(arc
					(start 216.71788 -63.81115)
					(mid 216.736985 -63.207468)
					(end 216.213182 -62.906656)
				)
				(arc
					(start 215.349836 -62.92342)
					(mid 214.774524 -63.521463)
					(end 215.372442 -64.0969)
				)
				(xy 216.027 -64.0842) (xy 216.027 -64.5922) (xy 216.11209 -64.67729) (xy 218.759024 -64.67729) (xy 218.759024 -63.81115)
			)
		)
		(polygon
			(pts
				(xy 33.979358 -62.827154) (xy 32.072072 -62.827154) (xy 32.072072 -63.693294) (xy 33.979358 -63.693294)
			)
		)
		(polygon
			(pts
				(arc
					(start 31.773876 -63.350394)
					(mid 31.25724 -62.70117)
					(end 30.608016 -63.217806)
				)
				(xy 30.605476 -63.217552) (xy 30.503368 -64.11595) (xy 30.503622 -64.116204)
				(arc
					(start 30.505908 -64.116458)
					(mid 31.022544 -64.765682)
					(end 31.671768 -64.249046)
				)
				(xy 31.674308 -64.2493) (xy 31.776416 -63.350648)
			)
		)
		(polygon
			(pts
				(xy 226.3521 -61.532516) (xy 224.4471 -61.532516) (xy 224.4471 -62.040516) (xy 226.3521 -62.040516)
			)
		)
		(polygon
			(pts
				(xy 41.352216 -61.532516) (xy 39.447216 -61.532516) (xy 39.447216 -62.040516) (xy 41.352216 -62.040516)
			)
		)
		(polygon
			(pts
				(xy 226.3521 -60.73267) (xy 224.4471 -60.73267) (xy 224.4471 -61.24067) (xy 226.3521 -61.24067)
			)
		)
		(polygon
			(pts
				(xy 41.352216 -60.73267) (xy 39.447216 -60.73267) (xy 39.447216 -61.24067) (xy 41.352216 -61.24067)
			)
		)
		(polygon
			(pts
				(arc
					(start 223.618552 -60.985908)
					(mid 223.031685 -60.399422)
					(end 222.445072 -60.986162)
				)
				(arc
					(start 222.445072 -61.945012)
					(mid 223.031812 -62.531752)
					(end 223.618552 -61.945012)
				)
			)
		)
		(polygon
			(pts
				(arc
					(start 38.686486 -60.890912)
					(mid 38.099619 -60.304426)
					(end 37.513006 -60.891166)
				)
				(arc
					(start 37.513006 -61.850016)
					(mid 38.099746 -62.436756)
					(end 38.686486 -61.850016)
				)
			)
		)
		(polygon
			(pts
				(xy 224.443544 -57.816496) (xy 222.055944 -57.816496) (xy 222.055944 -58.476896) (xy 224.443544 -58.476896)
			)
		)
		(polygon
			(pts
				(xy 39.44366 -57.816496) (xy 37.05606 -57.816496) (xy 37.05606 -58.476896) (xy 39.44366 -58.476896)
			)
		)
		(polygon
			(pts
				(xy 218.759024 -57.58815) (xy 216.851738 -57.58815) (xy 216.851738 -58.45429) (xy 218.759024 -58.45429)
			)
		)
		(polygon
			(pts
				(xy 33.979358 -57.493154) (xy 32.072072 -57.493154) (xy 32.072072 -58.359294) (xy 33.979358 -58.359294)
			)
		)
		(polygon
			(pts
				(xy 218.759024 -56.69915) (xy 216.851738 -56.69915) (xy 216.851738 -57.56529) (xy 218.759024 -57.56529)
			)
		)
		(polygon
			(pts
				(xy 33.979358 -56.604154) (xy 32.072072 -56.604154) (xy 32.072072 -57.470294) (xy 33.979358 -57.470294)
			)
		)
		(polygon
			(pts
				(xy 224.443544 -56.546496) (xy 222.055944 -56.546496) (xy 222.055944 -57.206896) (xy 224.443544 -57.206896)
			)
		)
		(polygon
			(pts
				(xy 39.44366 -56.546496) (xy 37.05606 -56.546496) (xy 37.05606 -57.206896) (xy 39.44366 -57.206896)
			)
		)
		(polygon
			(pts
				(xy 224.443544 -54.006496) (xy 222.055944 -54.006496) (xy 222.055944 -54.666896) (xy 224.443544 -54.666896)
			)
		)
		(polygon
			(pts
				(xy 39.44366 -54.006496) (xy 37.05606 -54.006496) (xy 37.05606 -54.666896) (xy 39.44366 -54.666896)
			)
		)
		(polygon
			(pts
				(xy 224.443544 -52.736496) (xy 222.055944 -52.736496) (xy 222.055944 -53.396896) (xy 224.443544 -53.396896)
			)
		)
		(polygon
			(pts
				(xy 39.44366 -52.736496) (xy 37.05606 -52.736496) (xy 37.05606 -53.396896) (xy 39.44366 -53.396896)
			)
		)
		(polygon
			(pts
				(xy 22.943566 -40.596312) (xy 20.555966 -40.596312) (xy 20.555966 -41.256712) (xy 22.943566 -41.256712)
			)
		)
		(polygon
			(pts
				(xy 22.943566 -39.326312) (xy 20.555966 -39.326312) (xy 20.555966 -39.986712) (xy 22.943566 -39.986712)
			)
		)
		(polygon
			(pts
				(xy 22.943566 -36.786312) (xy 20.555966 -36.786312) (xy 20.555966 -37.446712) (xy 22.943566 -37.446712)
			)
		)
		(polygon
			(pts
				(xy 26.994358 -36.411154) (xy 25.087072 -36.411154) (xy 25.087072 -37.277294) (xy 26.994358 -37.277294)
			)
		)
		(polygon
			(pts
				(xy 26.994358 -35.522154) (xy 25.087072 -35.522154) (xy 25.087072 -36.388294) (xy 26.994358 -36.388294)
			)
		)
		(polygon
			(pts
				(xy 22.943566 -35.516312) (xy 20.555966 -35.516312) (xy 20.555966 -36.176712) (xy 22.943566 -36.176712)
			)
		)
		(polygon
			(pts
				(xy 20.55241 -32.752538) (xy 18.64741 -32.752538) (xy 18.64741 -33.260538) (xy 20.55241 -33.260538)
			)
		)
		(polygon
			(pts
				(xy 28.137358 -32.474154) (xy 26.230072 -32.474154) (xy 26.230072 -33.340294) (xy 28.137358 -33.340294)
			)
		)
		(polygon
			(pts
				(xy 20.55241 -31.952692) (xy 18.64741 -31.952692) (xy 18.64741 -32.460692) (xy 20.55241 -32.460692)
			)
		)
		(polygon
			(pts
				(arc
					(start 22.581108 -32.148526)
					(mid 21.950172 -31.609538)
					(end 21.411184 -32.240474)
				)
				(arc
					(start 21.487384 -33.209738)
					(mid 22.118192 -33.74897)
					(end 22.657308 -33.118044)
				)
			)
		)
		(polygon
			(pts
				(xy 28.137358 -31.585154) (xy 26.230072 -31.585154) (xy 26.230072 -32.451294) (xy 28.137358 -32.451294)
			)
		)
		(polygon
			(pts
				(arc
					(start 29.968444 -31.996888)
					(mid 29.432377 -31.461202)
					(end 28.896564 -31.997142)
				)
				(arc
					(start 28.896564 -33.0327)
					(mid 29.432504 -33.56864)
					(end 29.968444 -33.0327)
				)
			)
		)
		(polygon
			(pts
				(xy 20.55241 -30.352492) (xy 18.64741 -30.352492) (xy 18.64741 -30.860492) (xy 20.55241 -30.860492)
			)
		)
		(polygon
			(pts
				(xy 20.55241 -29.552646) (xy 18.64741 -29.552646) (xy 18.64741 -30.060646) (xy 20.55241 -30.060646)
			)
		)
	)
	(zone
		(layer "In2.Cu")
		(hatch none 0.5)
		(connect_pads
			(clearance 0)
		)
		(min_thickness 0.25)
		(keepout
			(tracks not_allowed)
			(vias allowed)
			(pads allowed)
			(copperpour not_allowed)
			(footprints allowed)
		)
		(placement
			(enabled no)
			(sheetname "")
		)
		(fill
			(thermal_gap 0.5)
			(thermal_bridge_width 0.5)
			(island_removal_mode 0)
		)
		(polygon
			(pts
				(arc
					(start 32.000698 -267.41755)
					(mid 32.041401 -267.413734)
					(end 32.082232 -267.411708)
				)
				(xy 32.082486 -267.4112) (xy 32.082486 -267.2334) (xy 31.912814 -267.2334)
				(arc
					(start 31.912052 -267.232384)
					(mid 31.786617 -267.202966)
					(end 31.677102 -267.135102)
				)
				(xy 31.675578 -267.135102)
				(arc
					(start 31.65221 -267.111734)
					(mid 31.289416 -266.65837)
					(end 31.742126 -267.022072)
				)
				(arc
					(start 31.746952 -267.026644)
					(mid 31.835155 -267.085672)
					(end 31.93923 -267.1064)
				)
				(xy 32.082486 -267.1064)
				(arc
					(start 32.082486 -266.8651)
					(mid 31.495746 -266.27836)
					(end 30.909006 -266.8651)
				)
				(arc
					(start 30.909006 -267.728446)
					(mid 31.495619 -268.31544)
					(end 32.082486 -267.7287)
				)
				(xy 32.082486 -267.538708) (xy 32.033464 -267.541756) (xy 32.030924 -267.54455)
				(arc
					(start 32.008064 -267.54455)
					(mid 31.883717 -267.570351)
					(end 31.764986 -267.615416)
				)
				(arc
					(start 31.764986 -267.615416)
					(mid 31.258033 -267.898452)
					(end 31.69031 -267.510768)
				)
				(arc
					(start 31.69031 -267.510768)
					(mid 31.828802 -267.454365)
					(end 31.974536 -267.420852)
				)
				(xy 31.977838 -267.41755)
			)
		)
	)
	(zone
		(layer "In2.Cu")
		(hatch none 0.5)
		(connect_pads
			(clearance 0)
		)
		(min_thickness 0.25)
		(keepout
			(tracks not_allowed)
			(vias allowed)
			(pads allowed)
			(copperpour not_allowed)
			(footprints allowed)
		)
		(placement
			(enabled no)
			(sheetname "")
		)
		(fill
			(thermal_gap 0.5)
			(thermal_bridge_width 0.5)
			(island_removal_mode 0)
		)
		(polygon
			(pts
				(arc
					(start 32.729678 -164.16401)
					(mid 32.792417 -164.323317)
					(end 32.824928 -164.491416)
				)
				(xy 33.0073 -164.440362) (xy 33.0073 -164.437822)
				(arc
					(start 33.007554 -164.437568)
					(mid 33.047718 -164.168207)
					(end 33.152588 -163.916868)
				)
				(arc
					(start 33.152588 -163.916868)
					(mid 33.552371 -163.49603)
					(end 33.254696 -163.994338)
				)
				(arc
					(start 33.254696 -163.994338)
					(mid 33.172725 -164.192888)
					(end 33.136078 -164.404548)
				)
				(arc
					(start 33.533334 -164.29355)
					(mid 33.94075 -163.570666)
					(end 33.217866 -163.16325)
				)
				(arc
					(start 32.361886 -163.402518)
					(mid 31.945616 -164.123487)
					(end 32.66948 -164.53485)
				)
				(arc
					(start 32.700468 -164.526214)
					(mid 32.676132 -164.379061)
					(end 32.62503 -164.23894)
				)
				(arc
					(start 32.62503 -164.23894)
					(mid 32.341461 -163.732607)
					(end 32.729678 -164.16401)
				)
			)
		)
	)
	(zone
		(layer "In2.Cu")
		(hatch none 0.5)
		(connect_pads
			(clearance 0)
		)
		(min_thickness 0.25)
		(keepout
			(tracks not_allowed)
			(vias allowed)
			(pads allowed)
			(copperpour not_allowed)
			(footprints allowed)
		)
		(placement
			(enabled no)
			(sheetname "")
		)
		(fill
			(thermal_gap 0.5)
			(thermal_bridge_width 0.5)
			(island_removal_mode 0)
		)
		(polygon
			(pts
				(xy 7.28599 -121.810018) (xy 7.289038 -121.810526)
				(arc
					(start 7.276084 -121.60377)
					(mid 7.186946 -121.584594)
					(end 7.095998 -121.578116)
				)
				(arc
					(start 6.964934 -121.578116)
					(mid 6.387969 -121.514616)
					(end 6.964934 -121.451116)
				)
				(xy 7.12216 -121.451116)
				(arc
					(start 7.122414 -121.451624)
					(mid 7.194085 -121.45746)
					(end 7.264908 -121.469912)
				)
				(arc
					(start 7.264908 -121.469912)
					(mid 6.63905 -120.929375)
					(end 6.094476 -121.5517)
				)
				(xy 6.091936 -121.551954) (xy 6.1468 -122.41403)
				(arc
					(start 6.14934 -122.413776)
					(mid 6.771894 -122.962162)
					(end 7.32028 -122.339608)
				)
				(xy 7.32282 -122.339354)
				(arc
					(start 7.297928 -121.949464)
					(mid 7.278996 -121.938704)
					(end 7.257542 -121.934986)
				)
				(arc
					(start 7.062978 -121.934986)
					(mid 7.001255 -121.947263)
					(end 6.948932 -121.98223)
				)
				(arc
					(start 6.918706 -122.012456)
					(mid 6.905936 -122.031568)
					(end 6.901434 -122.054112)
				)
				(xy 6.901434 -122.106944) (xy 6.899148 -122.108976) (xy 6.8961 -122.124724) (xy 6.89737 -122.127518)
				(arc
					(start 6.895084 -122.132598)
					(mid 6.63154 -122.64984)
					(end 6.773926 -122.087132)
				)
				(xy 6.774434 -122.080528) (xy 6.774434 -122.027696)
				(arc
					(start 6.77672 -122.025664)
					(mid 6.788592 -121.983003)
					(end 6.810248 -121.944384)
				)
				(xy 6.810248 -121.941082) (xy 6.877558 -121.873772)
				(arc
					(start 6.87959 -121.873772)
					(mid 6.952635 -121.829928)
					(end 7.035292 -121.809256)
				)
				(xy 7.036562 -121.807986) (xy 7.283958 -121.807986)
			)
		)
	)
	(zone
		(layer "In2.Cu")
		(hatch none 0.5)
		(connect_pads
			(clearance 0)
		)
		(min_thickness 0.25)
		(keepout
			(tracks not_allowed)
			(vias allowed)
			(pads allowed)
			(copperpour not_allowed)
			(footprints allowed)
		)
		(placement
			(enabled no)
			(sheetname "")
		)
		(fill
			(thermal_gap 0.5)
			(thermal_bridge_width 0.5)
			(island_removal_mode 0)
		)
		(polygon
			(pts
				(arc
					(start 24.257 -129.81686)
					(mid 23.67026 -130.4036)
					(end 24.257 -130.99034)
				)
				(arc
					(start 24.521922 -130.99034)
					(mid 24.485419 -130.815301)
					(end 24.404066 -130.656076)
				)
				(arc
					(start 24.404066 -130.656076)
					(mid 24.057211 -130.190123)
					(end 24.497792 -130.5687)
				)
				(arc
					(start 24.497792 -130.5687)
					(mid 24.603645 -130.768694)
					(end 24.649176 -130.99034)
				)
				(xy 24.8285 -130.99034) (xy 24.8285 -130.929126)
				(arc
					(start 24.829008 -130.928872)
					(mid 24.851186 -130.761542)
					(end 24.906224 -130.601974)
				)
				(arc
					(start 24.906224 -130.601974)
					(mid 25.286373 -130.163186)
					(end 25.01265 -130.675126)
				)
				(arc
					(start 25.01265 -130.675126)
					(mid 24.969963 -130.812456)
					(end 24.9555 -130.955542)
				)
				(xy 24.9555 -130.99034)
				(arc
					(start 25.1206 -130.99034)
					(mid 25.70734 -130.4036)
					(end 25.1206 -129.81686)
				)
			)
		)
	)
	(zone
		(net "GND")
		(layer "In2.Cu")
		(hatch none 0.5)
		(connect_pads
			(clearance 0.5)
		)
		(min_thickness 0.25)
		(fill yes
			(thermal_gap 0.5)
			(thermal_bridge_width 0.5)
			(island_removal_mode 0)
		)
		(polygon
			(pts
				(xy 1.0414 -0.762) (xy 0.7874 -1.016) (xy 0.7874 -52.705) (xy 1.4224 -53.34) (xy 6.35 -53.34) (xy 6.858 -53.848)
				(xy 6.858 -56.134) (xy 5.969 -57.023) (xy 1.4224 -57.023) (xy 0.7874 -57.658) (xy 0.7874 -102.997)
				(xy 1.8034 -104.013) (xy 5.8166 -104.013) (xy 6.858 -105.0544) (xy 6.858 -105.7656) (xy 6.9596 -105.7656)
				(xy 8.3566 -107.1626) (xy 8.3566 -107.3912) (xy 8.001 -107.7468) (xy 5.9436 -107.7468) (xy 5.461 -108.2294)
				(xy 5.461 -131.445) (xy 6.6548 -132.6388) (xy 14.1986 -132.6388) (xy 17.1958 -129.6416) (xy 22.4282 -129.6416)
				(xy 23.1394 -128.9304) (xy 24.8666 -128.9304) (xy 25.7302 -129.794) (xy 25.7302 -131.5212) (xy 24.6126 -132.6388)
				(xy 17.4244 -132.6388) (xy 14.097 -135.9662) (xy 5.715 -135.9662) (xy 5.461 -136.2202) (xy 5.461 -167.513)
				(xy 5.6896 -167.7416) (xy 6.0452 -167.7416) (xy 6.5278 -168.1988) (xy 6.5278 -168.5798) (xy 6.8326 -168.8846)
				(xy 10.4648 -168.8846) (xy 10.5918 -169.0116) (xy 10.5918 -169.3672) (xy 8.382 -171.577) (xy 8.382 -173.228)
				(xy 9.4234 -174.2694) (xy 9.4234 -175.641) (xy 8.8646 -176.1998) (xy 5.6896 -176.1998) (xy 5.461 -176.4284)
				(xy 5.461 -191.274954) (xy 8.470646 -194.2846) (xy 8.470646 -196.4436) (xy 15.989046 -203.962) (xy 15.989046 -210.553046)
				(xy 16.5862 -211.1502) (xy 20.0152 -211.1502) (xy 22.8473 -213.9823) (xy 22.8473 -214.8713) (xy 20.32 -217.3986)
				(xy 18.871946 -217.3986) (xy 18.694146 -217.5764) (xy 18.694146 -247.015) (xy 22.987 -251.307854)
				(xy 22.987 -302.387) (xy 22.606 -302.768) (xy 19.685 -302.768) (xy 18.161 -301.244) (xy 18.161 -269.2146)
				(xy 15.265146 -269.2146) (xy 15.239746 -269.24) (xy 15.239746 -400.05) (xy 21.971 -400.05) (xy 25.4 -403.479)
				(xy 25.4 -404.495) (xy 25.145746 -404.495) (xy 18.922746 -410.718) (xy 18.922746 -412.3817) (xy 23.748746 -417.2077)
				(xy 23.748746 -421.7797) (xy 18.795746 -426.7327) (xy 18.795746 -461.6577) (xy 11.302746 -469.1507)
				(xy 1.396746 -469.1507) (xy 0.762 -469.785446) (xy 0.762 -494.03) (xy 1.016 -494.284) (xy 1.016 -494.919)
				(xy 0.762 -495.173) (xy 0.762 -504.952) (xy 1.016 -505.206) (xy 261.366 -505.206) (xy 261.493 -505.079)
				(xy 261.493 -505.078746) (xy 261.619746 -504.952) (xy 261.619746 -443.103254) (xy 261.62 -443.103)
				(xy 261.62 -429.3362) (xy 260.8834 -428.5996) (xy 259.0038 -428.5996) (xy 257.9624 -427.5582) (xy 257.9624 -412.9532)
				(xy 257.5306 -412.5214) (xy 251.079 -412.5214) (xy 250.0376 -411.48) (xy 250.0376 -409.0924) (xy 251.206 -407.924)
				(xy 257.683 -407.924) (xy 258.1148 -407.4922) (xy 258.1148 -363.0422) (xy 259.08 -362.077) (xy 260.985 -362.077)
				(xy 261.62 -361.442) (xy 261.62 -322.719954) (xy 261.619746 -322.7197) (xy 261.619746 -1.016) (xy 261.366 -0.762254)
				(xy 261.366 -0.762)
			)
		)
		(polygon
			(pts
				(xy 99.3394 -384.0226) (xy 98.6282 -384.0226) (xy 98.3742 -384.2766) (xy 98.3742 -384.9878) (xy 98.3996 -385.0132)
				(xy 98.425 -385.0132) (xy 98.7298 -385.5466) (xy 99.0854 -385.5466) (xy 99.3394 -385.2926) (xy 98.7806 -385.2926)
				(xy 98.6028 -385.1148) (xy 98.6028 -384.3274) (xy 98.806 -384.1242) (xy 99.441 -384.1242)
			)
		)
		(polygon
			(pts
				(arc
					(start 19.8374 -357.591106)
					(mid 19.900237 -357.684767)
					(end 20.010882 -357.662734)
				)
				(xy 20.192746 -357.481124)
				(arc
					(start 20.192746 -358.411526)
					(mid 20.255382 -358.505358)
					(end 20.365974 -358.483408)
				)
				(xy 20.776438 -358.072944)
				(arc
					(start 20.776438 -355.374956)
					(mid 20.719225 -355.283565)
					(end 20.6121 -355.2952)
				)
				(arc
					(start 20.6121 -355.2952)
					(mid 20.321367 -355.465488)
					(end 19.995388 -355.550724)
				)
				(arc
					(start 19.995388 -355.550724)
					(mid 19.911388 -355.618295)
					(end 19.935444 -355.723444)
				)
				(arc
					(start 19.935444 -355.723444)
					(mid 19.914513 -355.69316)
					(end 19.905726 -355.657404)
				)
				(arc
					(start 19.905726 -355.657404)
					(mid 19.87543 -355.590506)
					(end 19.807936 -355.561646)
				)
				(arc
					(start 19.807936 -355.561646)
					(mid 19.608509 -355.538455)
					(end 19.415506 -355.48316)
				)
				(arc
					(start 19.415506 -355.48316)
					(mid 19.294383 -355.523118)
					(end 19.30781 -355.650038)
				)
				(xy 19.8374 -356.179628)
			)
		)
		(polygon
			(pts
				(arc
					(start 20.289266 -353.178618)
					(mid 20.410655 -353.138809)
					(end 20.397216 -353.01174)
				)
				(arc
					(start 17.568418 -350.183196)
					(mid 17.457751 -350.161111)
					(end 17.394936 -350.254824)
				)
				(xy 17.394936 -353.737164)
				(arc
					(start 18.530062 -354.87229)
					(mid 18.657054 -354.88583)
					(end 18.69694 -354.764594)
				)
				(arc
					(start 18.69694 -354.764594)
					(mid 18.618493 -354.37237)
					(end 18.669762 -353.97567)
				)
				(arc
					(start 18.669762 -353.97567)
					(mid 18.663951 -353.902301)
					(end 18.610072 -353.852226)
				)
				(arc
					(start 18.610072 -353.852226)
					(mid 18.682894 -353.850205)
					(end 18.735548 -353.799902)
				)
				(arc
					(start 18.735548 -353.799902)
					(mid 19.237951 -353.256764)
					(end 19.960844 -353.099116)
				)
				(arc
					(start 19.960844 -353.099116)
					(mid 20.030577 -353.079463)
					(end 20.069556 -353.018344)
				)
				(arc
					(start 20.069556 -353.018344)
					(mid 20.084875 -353.090968)
					(end 20.145502 -353.13366)
				)
				(arc
					(start 20.145502 -353.13366)
					(mid 20.218073 -353.153937)
					(end 20.289266 -353.178618)
				)
			)
		)
		(polygon
			(pts
				(xy 27.502104 -397.455136) (xy 31.550864 -401.503896)
				(arc
					(start 31.665418 -401.503896)
					(mid 31.712385 -401.472453)
					(end 31.701232 -401.417028)
				)
				(arc
					(start 27.588972 -397.304768)
					(mid 27.533536 -397.293588)
					(end 27.502104 -397.340582)
				)
			)
		)
		(polygon
			(pts
				(arc
					(start 23.183596 -391.52703)
					(mid 23.145964 -391.448349)
					(end 23.061168 -391.427716)
				)
				(arc
					(start 23.061168 -391.427716)
					(mid 22.75001 -391.407406)
					(end 22.493478 -391.230104)
				)
				(arc
					(start 22.493478 -391.230104)
					(mid 22.380921 -391.199666)
					(end 22.3139 -391.295128)
				)
				(xy 22.3139 -392.908536)
				(arc
					(start 23.010114 -393.604496)
					(mid 23.120781 -393.626581)
					(end 23.183596 -393.532868)
				)
			)
		)
		(polygon
			(pts
				(arc
					(start 27.201114 -402.837396)
					(mid 27.294775 -402.774559)
					(end 27.272742 -402.663914)
				)
				(xy 21.811234 -397.202152)
				(arc
					(start 21.787866 -397.20393)
					(mid 21.601591 -397.188492)
					(end 21.429726 -397.11503)
				)
				(arc
					(start 21.429726 -397.11503)
					(mid 21.326596 -397.112035)
					(end 21.274024 -397.200882)
				)
				(arc
					(start 21.274024 -397.200882)
					(mid 21.280378 -397.165516)
					(end 21.298662 -397.134588)
				)
				(arc
					(start 21.298662 -397.134588)
					(mid 21.323443 -397.068316)
					(end 21.298916 -397.002)
				)
				(arc
					(start 21.298916 -397.002)
					(mid 21.320372 -396.216842)
					(end 22.103842 -396.161514)
				)
				(arc
					(start 22.103842 -396.161514)
					(mid 22.178163 -396.182516)
					(end 22.245828 -396.145258)
				)
				(arc
					(start 22.245828 -396.145258)
					(mid 22.907557 -395.965667)
					(end 23.284942 -396.538196)
				)
				(xy 23.283926 -396.560548) (xy 28.661868 -401.938744)
				(arc
					(start 31.514542 -401.938744)
					(mid 31.608203 -401.875907)
					(end 31.58617 -401.765262)
				)
				(xy 26.76144 -396.940532) (xy 26.76144 -395.456918)
				(arc
					(start 25.162002 -393.857226)
					(mid 25.065788 -393.830406)
					(end 24.993092 -393.898882)
				)
				(arc
					(start 24.993092 -393.898882)
					(mid 24.940943 -394.017983)
					(end 24.863806 -394.122656)
				)
				(arc
					(start 24.863806 -394.122656)
					(mid 24.840738 -394.220161)
					(end 24.912574 -394.290042)
				)
				(arc
					(start 24.912574 -394.290042)
					(mid 25.338397 -394.742797)
					(end 25.116028 -395.323314)
				)
				(arc
					(start 25.116028 -395.323314)
					(mid 25.096233 -395.356669)
					(end 25.105868 -395.39418)
				)
				(arc
					(start 25.105868 -395.39418)
					(mid 24.810243 -396.303491)
					(end 24.053546 -395.719046)
				)
				(xy 24.054562 -395.696694)
				(arc
					(start 21.83892 -393.480798)
					(mid 21.728723 -393.45852)
					(end 21.665438 -393.55141)
				)
				(xy 21.665438 -392.984736) (xy 21.665438 -392.938508) (xy 21.665692 -361.093766)
				(arc
					(start 21.665692 -360.933238)
					(mid 21.602973 -360.839372)
					(end 21.49221 -360.861356)
				)
				(xy 21.260054 -361.093766) (xy 21.260054 -392.938508)
				(arc
					(start 21.21789 -392.931142)
					(mid 21.043504 -392.870977)
					(end 20.89658 -392.759438)
				)
				(arc
					(start 20.89658 -392.759438)
					(mid 20.823533 -392.728117)
					(end 20.750276 -392.75893)
				)
				(arc
					(start 20.750276 -392.75893)
					(mid 20.448295 -392.924287)
					(end 20.105624 -392.89101)
				)
				(arc
					(start 20.105624 -392.89101)
					(mid 20.010197 -392.900216)
					(end 19.964908 -392.984736)
				)
				(arc
					(start 19.964908 -394.410692)
					(mid 19.994576 -394.482444)
					(end 20.066254 -394.512292)
				)
				(arc
					(start 20.066254 -394.512292)
					(mid 20.281552 -394.553474)
					(end 20.466558 -394.671042)
				)
				(arc
					(start 20.466558 -394.671042)
					(mid 20.501518 -394.685056)
					(end 20.536408 -394.671042)
				)
				(arc
					(start 20.536408 -394.671042)
					(mid 20.813346 -394.525506)
					(end 21.125688 -394.543534)
				)
				(arc
					(start 21.125688 -394.543534)
					(mid 21.217479 -394.530033)
					(end 21.260054 -394.447522)
				)
				(xy 21.260054 -394.680694)
				(arc
					(start 21.292058 -394.693394)
					(mid 21.398732 -394.749225)
					(end 21.491702 -394.825728)
				)
				(arc
					(start 21.491702 -394.825728)
					(mid 21.602423 -394.848211)
					(end 21.665438 -394.754354)
				)
				(arc
					(start 21.665438 -394.754354)
					(mid 21.643116 -394.817896)
					(end 21.585936 -394.853414)
				)
				(arc
					(start 21.585936 -394.853414)
					(mid 21.522242 -394.897739)
					(end 21.508466 -394.974064)
				)
				(arc
					(start 21.508466 -394.974064)
					(mid 21.22438 -395.606037)
					(end 20.536408 -395.522958)
				)
				(arc
					(start 20.536408 -395.522958)
					(mid 20.501518 -395.509119)
					(end 20.466558 -395.522958)
				)
				(arc
					(start 20.466558 -395.522958)
					(mid 20.232228 -395.657585)
					(end 19.962368 -395.672564)
				)
				(xy 19.936206 -395.667738)
				(arc
					(start 19.463766 -396.140432)
					(mid 19.433992 -396.212224)
					(end 19.463766 -396.283942)
				)
				(arc
					(start 19.482054 -396.302992)
					(mid 19.518046 -396.319379)
					(end 19.554952 -396.305024)
				)
				(arc
					(start 19.554952 -396.305024)
					(mid 20.506182 -396.502397)
					(end 19.962368 -397.307308)
				)
				(arc
					(start 19.962368 -398.643094)
					(mid 20.014286 -398.731464)
					(end 20.1168 -398.729708)
				)
				(arc
					(start 20.1168 -398.729708)
					(mid 20.203689 -398.685991)
					(end 20.296632 -398.657318)
				)
				(arc
					(start 20.296632 -398.657318)
					(mid 20.36484 -398.605604)
					(end 20.369276 -398.520158)
				)
				(arc
					(start 20.369276 -398.520158)
					(mid 20.499622 -397.886873)
					(end 21.133816 -397.760952)
				)
				(arc
					(start 21.133816 -397.760952)
					(mid 21.228993 -397.751368)
					(end 21.274024 -397.666972)
				)
				(xy 21.274024 -397.842232)
				(arc
					(start 21.29155 -397.857472)
					(mid 21.481523 -398.431683)
					(end 21.061426 -398.866868)
				)
				(arc
					(start 21.061426 -398.866868)
					(mid 20.996809 -398.918917)
					(end 20.992592 -399.001742)
				)
				(arc
					(start 20.992592 -399.001742)
					(mid 21.024178 -399.118104)
					(end 21.0312 -399.23847)
				)
				(arc
					(start 21.0312 -399.23847)
					(mid 21.059103 -399.3134)
					(end 21.132546 -399.344896)
				)
				(xy 22.921214 -399.344896) (xy 26.413714 -402.837396)
			)
		)
		(polygon
			(pts
				(arc
					(start 19.405092 -361.497372)
					(mid 19.342456 -361.40354)
					(end 19.231864 -361.42549)
				)
				(xy 19.08556 -361.571794)
				(arc
					(start 19.08556 -362.823252)
					(mid 19.121712 -362.900964)
					(end 19.204432 -362.923328)
				)
				(arc
					(start 19.204432 -362.923328)
					(mid 19.253905 -362.916894)
					(end 19.303746 -362.914692)
				)
				(arc
					(start 19.303746 -362.914692)
					(mid 19.375424 -362.884844)
					(end 19.405092 -362.813092)
				)
			)
		)
		(polygon
			(pts
				(arc
					(start 17.913604 -314.570618)
					(mid 17.93544 -314.460073)
					(end 17.841722 -314.39739)
				)
				(xy 17.770856 -314.39739) (xy 17.770856 -314.456064)
				(arc
					(start 17.773396 -314.463938)
					(mid 17.775677 -314.518811)
					(end 17.749012 -314.566808)
				)
				(xy 16.43126 -315.885068) (xy 16.370808 -315.945774) (xy 16.370808 -353.350068) (xy 16.43126 -353.41052)
				(xy 16.43126 -353.411282)
				(arc
					(start 16.465042 -353.445064)
					(mid 16.575709 -353.467149)
					(end 16.638524 -353.373436)
				)
				(xy 16.638524 -315.845952)
			)
		)
		(polygon
			(pts
				(arc
					(start 16.130778 -314.00623)
					(mid 16.018243 -313.975403)
					(end 15.950946 -314.070746)
				)
				(arc
					(start 15.950946 -316.120018)
					(mid 16.013582 -316.21385)
					(end 16.124174 -316.1919)
				)
				(arc
					(start 17.748504 -314.56757)
					(mid 17.770663 -314.456937)
					(end 17.676876 -314.394088)
				)
				(arc
					(start 16.953738 -314.394088)
					(mid 16.498845 -314.292268)
					(end 16.130778 -314.00623)
				)
			)
		)
		(polygon
			(pts
				(arc
					(start 24.654256 -207.891888)
					(mid 24.717093 -207.985549)
					(end 24.827738 -207.963516)
				)
				(xy 24.939244 -207.852264) (xy 24.939244 -165.126162)
				(arc
					(start 24.827738 -165.01491)
					(mid 24.717071 -164.992825)
					(end 24.654256 -165.086538)
				)
			)
		)
		(polygon
			(pts
				(xy 15.014448 -114.891566)
				(arc
					(start 9.946386 -109.823758)
					(mid 9.835719 -109.801673)
					(end 9.772904 -109.895386)
				)
				(xy 9.772904 -110.250986) (xy 14.856714 -115.334796)
				(arc
					(start 14.96568 -115.334796)
					(mid 15.05061 -115.288959)
					(end 15.058898 -115.19281)
				)
				(arc
					(start 15.058898 -115.19281)
					(mid 15.01878 -115.056698)
					(end 15.01267 -114.914934)
				)
			)
		)
		(polygon
			(pts
				(xy 45.015658 -429.920908)
				(arc
					(start 44.830492 -429.920908)
					(mid 44.741158 -429.974586)
					(end 44.746164 -430.078642)
				)
				(arc
					(start 44.746164 -430.078642)
					(mid 44.6304 -430.855198)
					(end 43.846242 -430.816766)
				)
				(arc
					(start 43.846242 -430.816766)
					(mid 43.774524 -430.787171)
					(end 43.702732 -430.816766)
				)
				(xy 40.869108 -433.65039)
				(arc
					(start 40.869108 -434.68544)
					(mid 40.914945 -434.77037)
					(end 41.011094 -434.778658)
				)
				(arc
					(start 41.011094 -434.778658)
					(mid 41.461816 -434.75082)
					(end 41.825164 -435.018942)
				)
				(arc
					(start 41.825164 -435.018942)
					(mid 41.909746 -435.064209)
					(end 41.994328 -435.018942)
				)
				(arc
					(start 41.994328 -435.018942)
					(mid 42.540625 -434.723852)
					(end 43.090592 -435.012084)
				)
				(arc
					(start 43.090592 -435.012084)
					(mid 43.175786 -435.056263)
					(end 43.259756 -435.009798)
				)
				(arc
					(start 43.259756 -435.009798)
					(mid 43.430483 -434.830958)
					(end 43.65498 -434.72735)
				)
				(xy 43.668696 -434.724048) (xy 45.440092 -432.952398)
				(arc
					(start 45.440092 -430.03089)
					(mid 45.401937 -429.951534)
					(end 45.31614 -429.93183)
				)
				(arc
					(start 45.31614 -429.93183)
					(mid 45.168756 -429.946151)
					(end 45.022516 -429.92294)
				)
			)
		)
		(polygon
			(pts
				(arc
					(start 42.502836 -427.201838)
					(mid 42.48078 -427.118587)
					(end 42.40276 -427.082204)
				)
				(xy 38.114986 -427.082204)
				(arc
					(start 37.73678 -427.460664)
					(mid 37.714944 -427.571209)
					(end 37.808662 -427.633892)
				)
				(arc
					(start 42.431208 -427.633892)
					(mid 42.514075 -427.591077)
					(end 42.526966 -427.498764)
				)
				(arc
					(start 42.526966 -427.498764)
					(mid 42.495658 -427.351863)
					(end 42.502836 -427.201838)
				)
			)
		)
		(polygon
			(pts
				(arc
					(start 45.446188 -427.216824)
					(mid 45.432741 -427.124656)
					(end 45.349922 -427.082204)
				)
				(arc
					(start 44.026582 -427.082204)
					(mid 43.932716 -427.144923)
					(end 43.9547 -427.255686)
				)
				(xy 44.323508 -427.624494) (xy 44.323508 -428.802292) (xy 45.015658 -428.802292)
				(arc
					(start 45.022516 -428.80026)
					(mid 45.168758 -428.777106)
					(end 45.31614 -428.79137)
				)
				(arc
					(start 45.31614 -428.79137)
					(mid 45.401906 -428.771627)
					(end 45.440092 -428.69231)
				)
				(xy 45.440092 -427.576742)
				(arc
					(start 45.43806 -427.569884)
					(mid 45.41487 -427.392732)
					(end 45.446188 -427.216824)
				)
			)
		)
		(polygon
			(pts
				(arc
					(start 248.955052 -420.333424)
					(mid 248.849214 -420.324813)
					(end 248.793508 -420.415212)
				)
				(xy 248.793508 -420.696136) (xy 249.054366 -420.957248)
				(arc
					(start 249.077734 -420.95547)
					(mid 249.255168 -420.968866)
					(end 249.42038 -421.034972)
				)
				(arc
					(start 249.42038 -421.034972)
					(mid 249.522638 -421.03577)
					(end 249.573796 -420.947342)
				)
				(arc
					(start 249.573796 -420.526718)
					(mid 249.534431 -420.44641)
					(end 249.446796 -420.428166)
				)
				(arc
					(start 249.446796 -420.428166)
					(mid 249.190288 -420.436059)
					(end 248.955052 -420.333424)
				)
			)
		)
		(polygon
			(pts
				(arc
					(start 246.996966 -416.285934)
					(mid 246.902707 -416.258653)
					(end 246.829326 -416.32378)
				)
				(arc
					(start 246.829326 -416.32378)
					(mid 246.540493 -416.650769)
					(end 246.10568 -416.686746)
				)
				(arc
					(start 246.10568 -416.686746)
					(mid 246.015421 -416.702054)
					(end 245.974108 -416.783774)
				)
				(xy 245.974108 -417.935918) (xy 245.669308 -418.240718)
				(arc
					(start 245.669308 -418.693092)
					(mid 245.698976 -418.764844)
					(end 245.770654 -418.794692)
				)
				(arc
					(start 245.770654 -418.794692)
					(mid 246.355362 -419.3794)
					(end 245.770654 -419.964108)
				)
				(arc
					(start 245.770654 -419.964108)
					(mid 245.698976 -419.993956)
					(end 245.669308 -420.065708)
				)
				(xy 245.669308 -422.118536) (xy 247.327166 -423.776648)
				(arc
					(start 247.350534 -423.77487)
					(mid 247.521389 -423.786703)
					(end 247.681496 -423.847514)
				)
				(arc
					(start 247.681496 -423.847514)
					(mid 247.788029 -423.843225)
					(end 247.832118 -423.746168)
				)
				(arc
					(start 247.832118 -423.746168)
					(mid 247.82752 -423.686429)
					(end 247.82907 -423.626534)
				)
				(xy 247.830848 -423.603166) (xy 247.077992 -422.850564)
				(arc
					(start 247.077992 -418.867336)
					(mid 247.036908 -418.78547)
					(end 246.946674 -418.770054)
				)
				(arc
					(start 246.946674 -418.770054)
					(mid 246.191127 -418.211)
					(end 246.946674 -417.651946)
				)
				(arc
					(start 246.946674 -417.651946)
					(mid 247.036834 -417.636431)
					(end 247.077992 -417.554664)
				)
				(xy 247.077992 -416.36696)
			)
		)
		(polygon
			(pts
				(xy 38.699186 -390.620504) (xy 26.062686 -390.620504) (xy 26.047446 -390.638284) (xy 26.015696 -390.672828)
				(xy 26.00071 -390.68756) (xy 26.00071 -390.759696)
				(arc
					(start 38.715442 -390.759696)
					(mid 38.762615 -390.728371)
					(end 38.75151 -390.672828)
				)
			)
		)
		(polygon
			(pts
				(arc
					(start 23.519638 -364.85449)
					(mid 23.457002 -364.760658)
					(end 23.34641 -364.782608)
				)
				(xy 23.304754 -364.824264) (xy 23.304754 -388.097776) (xy 23.317708 -388.112508)
				(arc
					(start 23.339298 -388.1374)
					(mid 23.452001 -388.169014)
					(end 23.519638 -388.073392)
				)
			)
		)
		(polygon
			(pts
				(arc
					(start 22.580092 -361.057444)
					(mid 22.517373 -360.963578)
					(end 22.40661 -360.985562)
				)
				(xy 22.3139 -361.078018)
				(arc
					(start 22.3139 -390.415272)
					(mid 22.380897 -390.510798)
					(end 22.493478 -390.480296)
				)
				(arc
					(start 22.493478 -390.480296)
					(mid 22.526453 -390.444195)
					(end 22.562312 -390.410954)
				)
				(xy 22.580092 -390.395714)
			)
		)
		(polygon
			(pts
				(xy 23.742396 -352.8822) (xy 23.603204 -352.8822)
				(arc
					(start 23.603204 -357.710232)
					(mid 23.634529 -357.757405)
					(end 23.690072 -357.7463)
				)
				(xy 23.742396 -357.693976)
			)
		)
		(polygon
			(pts
				(arc
					(start 23.690072 -344.90279)
					(mid 23.634518 -344.891659)
					(end 23.603204 -344.938858)
				)
				(xy 23.603204 -347.218) (xy 23.742396 -347.218) (xy 23.742396 -344.955114)
			)
		)
		(polygon
			(pts
				(arc
					(start 29.895038 -340.482428)
					(mid 29.821293 -340.444247)
					(end 29.743654 -340.473792)
				)
				(xy 29.4894 -340.728046) (xy 29.4894 -342.319864) (xy 29.5275 -342.357964)
				(arc
					(start 29.5275 -347.048836)
					(mid 29.582125 -347.138924)
					(end 29.687266 -347.132148)
				)
				(arc
					(start 29.687266 -347.132148)
					(mid 29.810639 -347.066399)
					(end 29.946092 -347.031818)
				)
				(xy 29.990288 -347.02623) (xy 29.990288 -340.578186)
				(arc
					(start 29.972762 -340.562946)
					(mid 29.93196 -340.524559)
					(end 29.895038 -340.482428)
				)
			)
		)
		(polygon
			(pts
				(arc
					(start 28.85567 -335.57845)
					(mid 28.819582 -335.578936)
					(end 28.783534 -335.57718)
				)
				(xy 28.760166 -335.575402) (xy 28.632404 -335.703164)
				(arc
					(start 28.632404 -339.736938)
					(mid 28.663729 -339.784111)
					(end 28.719272 -339.773006)
				)
				(xy 28.764992 -339.727286) (xy 28.764992 -336.97291) (xy 28.962096 -336.775806)
				(arc
					(start 28.962096 -335.679796)
					(mid 28.930521 -335.606436)
					(end 28.85567 -335.57845)
				)
			)
		)
		(polygon
			(pts
				(arc
					(start 23.799292 -318.588644)
					(mid 23.736573 -318.494778)
					(end 23.62581 -318.516762)
				)
				(xy 22.775164 -319.367154) (xy 22.775164 -334.119982)
				(arc
					(start 23.62581 -334.970374)
					(mid 23.736594 -334.99241)
					(end 23.799292 -334.898492)
				)
			)
		)
		(polygon
			(pts
				(arc
					(start 18.629122 -316.155832)
					(mid 18.573776 -316.050945)
					(end 18.456656 -316.06998)
				)
				(xy 18.123154 -316.403736)
				(arc
					(start 18.123154 -319.71234)
					(mid 18.18579 -319.806172)
					(end 18.296382 -319.784222)
				)
				(xy 20.814538 -317.266066) (xy 20.814538 -317.176912) (xy 20.742656 -317.176912)
				(arc
					(start 20.72767 -317.191898)
					(mid 19.304212 -317.431897)
					(end 18.629122 -316.155832)
				)
			)
		)
		(polygon
			(pts
				(arc
					(start 20.814538 -313.957462)
					(mid 20.751902 -313.86363)
					(end 20.64131 -313.88558)
				)
				(arc
					(start 19.593052 -314.933584)
					(mid 19.573921 -315.050751)
					(end 19.678904 -315.10605)
				)
				(arc
					(start 19.678904 -315.10605)
					(mid 20.193204 -315.142927)
					(end 20.647406 -315.386974)
				)
				(arc
					(start 20.647406 -315.386974)
					(mid 20.755638 -315.401552)
					(end 20.814538 -315.309504)
				)
			)
		)
		(polygon
			(pts
				(arc
					(start 31.28899 -269.062454)
					(mid 31.195124 -269.125173)
					(end 31.217108 -269.235936)
				)
				(xy 31.369 -269.387828) (xy 31.369 -269.062454)
			)
		)
		(polygon
			(pts
				(xy 33.172146 -265.6967) (xy 32.791146 -265.6967) (xy 32.181546 -266.3063) (xy 31.419546 -266.3063)
				(xy 31.013146 -266.7127) (xy 31.013146 -267.9065) (xy 31.317946 -268.2113) (xy 32.004 -268.2113)
				(xy 32.004 -268.097) (xy 32.321246 -268.097) (xy 33.172146 -267.2461)
			)
		)
		(polygon
			(pts
				(arc
					(start 23.640796 -211.60867)
					(mid 23.57089 -211.51214)
					(end 23.457408 -211.548472)
				)
				(arc
					(start 23.457408 -211.548472)
					(mid 23.087875 -211.77706)
					(end 22.662642 -211.687664)
				)
				(arc
					(start 22.662642 -211.687664)
					(mid 22.558626 -211.682733)
					(end 22.504908 -211.771992)
				)
				(arc
					(start 22.504908 -213.08441)
					(mid 22.567544 -213.178242)
					(end 22.678136 -213.156292)
				)
				(xy 23.640796 -212.193886)
			)
		)
		(polygon
			(pts
				(arc
					(start 26.599388 -211.573872)
					(mid 26.536752 -211.48004)
					(end 26.42616 -211.50199)
				)
				(xy 24.628602 -213.299294)
				(arc
					(start 24.63038 -213.322662)
					(mid 24.58066 -213.608049)
					(end 24.400002 -213.834472)
				)
				(arc
					(start 24.400002 -213.834472)
					(mid 24.359903 -213.908566)
					(end 24.389588 -213.98738)
				)
				(xy 24.702008 -214.2998) (xy 26.1874 -214.2998) (xy 26.1874 -217.8558) (xy 26.0858 -217.8558)
				(arc
					(start 26.0858 -230.138224)
					(mid 26.148519 -230.23209)
					(end 26.259282 -230.210106)
				)
				(xy 26.599388 -229.87)
			)
		)
		(polygon
			(pts
				(arc
					(start 26.085292 -208.143094)
					(mid 26.022573 -208.049228)
					(end 25.91181 -208.071212)
				)
				(xy 25.092152 -208.890616)
				(arc
					(start 25.09393 -208.913984)
					(mid 24.940306 -209.356402)
					(end 24.511254 -209.544158)
				)
				(arc
					(start 24.511254 -209.544158)
					(mid 24.439576 -209.574006)
					(end 24.409908 -209.645758)
				)
				(xy 24.409908 -212.045042)
				(arc
					(start 24.427434 -212.060282)
					(mid 24.488309 -212.120539)
					(end 24.539702 -212.18906)
				)
				(arc
					(start 24.539702 -212.18906)
					(mid 24.614371 -212.235278)
					(end 24.697182 -212.206078)
				)
				(xy 26.085292 -210.817968)
			)
		)
		(polygon
			(pts
				(arc
					(start 22.678136 -167.295576)
					(mid 22.567352 -167.27354)
					(end 22.504654 -167.367458)
				)
				(xy 22.504654 -175.34636) (xy 22.504908 -191.274954)
				(arc
					(start 22.504908 -206.704692)
					(mid 22.534576 -206.776444)
					(end 22.606254 -206.806292)
				)
				(arc
					(start 22.606254 -206.806292)
					(mid 22.694389 -206.813011)
					(end 22.780498 -206.832962)
				)
				(arc
					(start 22.780498 -206.832962)
					(mid 22.847432 -206.8307)
					(end 22.898354 -206.787242)
				)
				(arc
					(start 22.898354 -206.787242)
					(mid 22.889053 -206.810842)
					(end 22.885908 -206.83601)
				)
				(arc
					(start 22.885908 -207.97901)
					(mid 22.948222 -208.072538)
					(end 23.058628 -208.051146)
				)
				(arc
					(start 23.058628 -208.051146)
					(mid 22.965479 -208.078125)
					(end 22.892258 -208.01457)
				)
				(arc
					(start 22.892258 -208.01457)
					(mid 22.842695 -207.959302)
					(end 22.768814 -207.952594)
				)
				(arc
					(start 22.768814 -207.952594)
					(mid 22.68835 -207.969891)
					(end 22.606254 -207.975708)
				)
				(arc
					(start 22.606254 -207.975708)
					(mid 22.534576 -208.005556)
					(end 22.504908 -208.077308)
				)
				(arc
					(start 22.504908 -209.166206)
					(mid 22.549372 -209.250218)
					(end 22.643846 -209.260694)
				)
				(arc
					(start 22.643846 -209.260694)
					(mid 23.444726 -209.804)
					(end 22.643846 -210.347306)
				)
				(arc
					(start 22.643846 -210.347306)
					(mid 22.549374 -210.357783)
					(end 22.504908 -210.441794)
				)
				(arc
					(start 22.504908 -210.630008)
					(mid 22.558586 -210.719342)
					(end 22.662642 -210.714336)
				)
				(arc
					(start 22.662642 -210.714336)
					(mid 23.08788 -210.624916)
					(end 23.457408 -210.853528)
				)
				(arc
					(start 23.457408 -210.853528)
					(mid 23.570876 -210.889816)
					(end 23.640796 -210.79333)
				)
				(arc
					(start 23.640796 -207.71485)
					(mid 23.578077 -207.620984)
					(end 23.467314 -207.642968)
				)
				(xy 23.131018 -207.97901)
				(arc
					(start 24.040592 -207.06969)
					(mid 24.068797 -206.980012)
					(end 24.011382 -206.905606)
				)
				(arc
					(start 24.011382 -206.905606)
					(mid 23.906905 -206.843356)
					(end 23.81758 -206.760826)
				)
				(arc
					(start 23.81758 -206.760826)
					(mid 23.784689 -206.74387)
					(end 23.749 -206.753714)
				)
				(arc
					(start 23.749 -206.753714)
					(mid 23.677655 -206.799637)
					(end 23.60041 -206.83474)
				)
				(xy 23.640796 -206.817976) (xy 23.640796 -168.257982)
			)
		)
	)
	(zone
		(net "P3V3")
		(layer "In2.Cu")
		(hatch none 0.5)
		(connect_pads
			(clearance 0.5)
		)
		(min_thickness 0.25)
		(fill yes
			(thermal_gap 0.5)
			(thermal_bridge_width 0.5)
			(island_removal_mode 0)
		)
		(polygon
			(pts
				(xy 38.226746 -238.2647) (xy 40.004746 -238.2647) (xy 41.579546 -238.2647) (xy 41.585896 -238.258096)
				(xy 42.221404 -238.258096) (xy 54.4068 -226.0727) (xy 57.022746 -226.0727) (xy 57.403746 -225.6917)
				(xy 57.403746 -224.5487) (xy 56.768746 -223.9137) (xy 52.069746 -223.9137) (xy 40.131746 -235.8517)
				(xy 38.607746 -235.8517) (xy 37.845746 -236.6137) (xy 37.845746 -237.8837)
			)
		)
	)
	(zone
		(layer "In2.Cu")
		(hatch none 0.5)
		(connect_pads
			(clearance 0)
		)
		(min_thickness 0.25)
		(keepout
			(tracks not_allowed)
			(vias allowed)
			(pads allowed)
			(copperpour not_allowed)
			(footprints allowed)
		)
		(placement
			(enabled no)
			(sheetname "")
		)
		(fill
			(thermal_gap 0.5)
			(thermal_bridge_width 0.5)
			(island_removal_mode 0)
		)
		(polygon
			(pts
				(arc
					(start 6.169406 -134.442708)
					(mid 6.756146 -135.029448)
					(end 7.342886 -134.442708)
				)
				(arc
					(start 7.342886 -134.208266)
					(mid 7.1774 -134.250889)
					(end 7.021576 -134.321042)
				)
				(arc
					(start 7.021576 -134.321042)
					(mid 6.523275 -134.618712)
					(end 6.944106 -134.218934)
				)
				(arc
					(start 6.944106 -134.218934)
					(mid 7.13692 -134.130499)
					(end 7.342886 -134.079742)
				)
				(arc
					(start 7.342886 -133.900418)
					(mid 7.25518 -133.914597)
					(end 7.168642 -133.934708)
				)
				(arc
					(start 7.168642 -133.934708)
					(mid 6.952848 -133.929133)
					(end 6.77545 -133.806184)
				)
				(arc
					(start 6.77545 -133.806184)
					(mid 6.666882 -133.236329)
					(end 6.91007 -133.763004)
				)
				(arc
					(start 6.91007 -133.763004)
					(mid 7.016836 -133.815149)
					(end 7.135622 -133.81228)
				)
				(arc
					(start 7.135622 -133.81228)
					(mid 7.238519 -133.788524)
					(end 7.342886 -133.772402)
				)
				(arc
					(start 7.342886 -133.514846)
					(mid 6.756273 -132.927852)
					(end 6.169406 -133.514592)
				)
			)
		)
	)
	(zone
		(net "GND")
		(layer "In2.Cu")
		(hatch none 0.5)
		(connect_pads
			(clearance 0.5)
		)
		(min_thickness 0.25)
		(fill yes
			(thermal_gap 0.5)
			(thermal_bridge_width 0.5)
			(island_removal_mode 0)
		)
		(polygon
			(pts
				(xy 1.904746 -218.7067) (xy 1.396746 -219.2147) (xy 1.396746 -303.021746) (xy 1.651 -303.276) (xy 5.842 -303.276)
				(xy 6.858 -304.292) (xy 6.858 -305.943) (xy 5.715 -307.086) (xy 2.031746 -307.086) (xy 1.396746 -307.721)
				(xy 1.396746 -342.9127) (xy 1.777746 -343.2937) (xy 4.901946 -343.2937) (xy 5.562346 -343.9541)
				(xy 5.562346 -354.0633) (xy 6.806946 -355.3079) (xy 6.806946 -356.7811) (xy 6.603746 -356.9843)
				(xy 5.562346 -358.0257) (xy 5.562346 -430.9999) (xy 4.012946 -432.5493) (xy 1.218946 -432.5493)
				(xy 0.888746 -432.8795) (xy 0.888746 -445.6049) (xy 1.295146 -446.0113) (xy 4.3815 -446.0113) (xy 4.572 -445.8208)
				(xy 4.572 -437.1086) (xy 4.901946 -436.778654) (xy 9.778746 -431.901854) (xy 9.778746 -343.2937)
				(xy 9.778746 -218.9607) (xy 9.524746 -218.7067)
			)
		)
		(polygon
			(pts
				(arc
					(start 7.57047 -390.288526)
					(mid 7.362189 -390.3559)
					(end 7.14375 -390.341866)
				)
				(arc
					(start 7.14375 -390.341866)
					(mid 7.05601 -390.359973)
					(end 7.01675 -390.440418)
				)
				(xy 7.01675 -390.662922) (xy 7.425182 -391.071354)
				(arc
					(start 7.425182 -391.873232)
					(mid 7.462929 -391.95226)
					(end 7.548118 -391.972546)
				)
				(arc
					(start 7.548118 -391.972546)
					(mid 7.886197 -392.000806)
					(end 8.151622 -392.212068)
				)
				(arc
					(start 8.151622 -392.212068)
					(mid 8.265631 -392.251564)
					(end 8.337042 -392.15441)
				)
				(arc
					(start 8.337042 -390.711182)
					(mid 8.30293 -390.63498)
					(end 8.22325 -390.61009)
				)
				(arc
					(start 8.22325 -390.61009)
					(mid 7.885017 -390.549194)
					(end 7.639304 -390.308846)
				)
				(arc
					(start 7.639304 -390.308846)
					(mid 7.609076 -390.284409)
					(end 7.57047 -390.288526)
				)
			)
		)
		(polygon
			(pts
				(xy 8.762238 -393.963144)
				(arc
					(start 8.762238 -394.469112)
					(mid 8.791996 -394.540954)
					(end 8.863838 -394.570712)
				)
				(arc
					(start 8.863838 -394.570712)
					(mid 9.031557 -394.595283)
					(end 9.185148 -394.666978)
				)
				(arc
					(start 9.185148 -394.666978)
					(mid 9.288984 -394.671401)
					(end 9.342374 -394.582142)
				)
				(arc
					(start 9.342374 -393.628372)
					(mid 9.279738 -393.53454)
					(end 9.169146 -393.55649)
				)
			)
		)
		(polygon
			(pts
				(arc
					(start 9.165336 -263.063228)
					(mid 9.08902 -263.140518)
					(end 9.009126 -263.214104)
				)
				(xy 8.991854 -263.229344)
				(arc
					(start 8.991854 -265.470386)
					(mid 9.05449 -265.564218)
					(end 9.165082 -265.542268)
				)
				(xy 9.34085 -265.3665)
				(arc
					(start 9.34085 -263.132824)
					(mid 9.276715 -263.038384)
					(end 9.165336 -263.063228)
				)
			)
		)
		(polygon
			(pts
				(xy 8.991854 -256.886964) (xy 8.991854 -259.761736)
				(arc
					(start 9.009126 -259.776976)
					(mid 9.089027 -259.850554)
					(end 9.165336 -259.927852)
				)
				(arc
					(start 9.165336 -259.927852)
					(mid 9.276686 -259.952625)
					(end 9.34085 -259.858256)
				)
				(arc
					(start 9.34085 -256.783078)
					(mid 9.278214 -256.689246)
					(end 9.167622 -256.711196)
				)
			)
		)
		(polygon
			(pts
				(arc
					(start 8.943594 -405.801068)
					(mid 8.895228 -405.80359)
					(end 8.84682 -405.802084)
				)
				(arc
					(start 8.84682 -405.802084)
					(mid 8.770256 -405.82902)
					(end 8.737854 -405.90343)
				)
				(xy 8.737854 -407.475436)
				(arc
					(start 8.88111 -407.618692)
					(mid 8.991655 -407.640528)
					(end 9.054338 -407.54681)
				)
				(arc
					(start 9.054338 -405.902414)
					(mid 9.021362 -405.827237)
					(end 8.943594 -405.801068)
				)
			)
		)
		(polygon
			(pts
				(arc
					(start 9.692386 -400.373342)
					(mid 9.611362 -400.396935)
					(end 9.576054 -400.473672)
				)
				(xy 9.576054 -403.265386)
				(arc
					(start 9.605264 -403.29485)
					(mid 9.711298 -403.318716)
					(end 9.778238 -403.233128)
				)
				(arc
					(start 9.778238 -400.379692)
					(mid 9.735194 -400.378105)
					(end 9.692386 -400.373342)
				)
			)
		)
		(polygon
			(pts
				(arc
					(start 7.918958 -393.224766)
					(mid 7.847116 -393.254524)
					(end 7.817358 -393.326366)
				)
				(xy 7.817358 -396.615412)
				(arc
					(start 8.23341 -397.03121)
					(mid 8.343955 -397.053046)
					(end 8.406638 -396.959328)
				)
				(arc
					(start 8.406638 -393.20724)
					(mid 8.352575 -393.117447)
					(end 8.247888 -393.123166)
				)
				(arc
					(start 8.247888 -393.123166)
					(mid 8.091072 -393.198739)
					(end 7.918958 -393.224766)
				)
			)
		)
		(polygon
			(pts
				(arc
					(start 6.86308 -369.70335)
					(mid 6.925799 -369.797216)
					(end 7.036562 -369.775232)
				)
				(arc
					(start 8.151876 -368.660172)
					(mid 8.175827 -368.554376)
					(end 8.090662 -368.487198)
				)
				(arc
					(start 8.090662 -368.487198)
					(mid 7.898443 -368.432624)
					(end 7.735824 -368.31651)
				)
				(arc
					(start 7.735824 -368.31651)
					(mid 7.701906 -368.301541)
					(end 7.666736 -368.313462)
				)
				(arc
					(start 7.666736 -368.313462)
					(mid 7.350358 -368.448613)
					(end 7.012686 -368.38255)
				)
				(arc
					(start 7.012686 -368.38255)
					(mid 6.912752 -368.385054)
					(end 6.863334 -368.471958)
				)
			)
		)
	)
	(zone
		(net "12V_PRE_14")
		(layer "In2.Cu")
		(hatch none 0.5)
		(connect_pads
			(clearance 0.5)
		)
		(min_thickness 0.25)
		(fill yes
			(thermal_gap 0.5)
			(thermal_bridge_width 0.5)
			(island_removal_mode 0)
		)
		(polygon
			(pts
				(xy 37.972746 -10.6807) (xy 40.766746 -7.8867) (xy 69.341746 -7.8867) (xy 70.611746 -9.1567) (xy 72.770746 -11.3157)
				(xy 73.532746 -11.3157) (xy 74.294746 -10.5537) (xy 74.294746 -9.2837) (xy 71.373746 -6.3627) (xy 70.865746 -5.8547)
				(xy 39.750746 -5.8547) (xy 39.242746 -6.3627) (xy 36.956746 -8.6487) (xy 36.321746 -9.2837) (xy 27.558746 -9.2837)
				(xy 26.796746 -9.2837) (xy 24.002746 -12.0777) (xy 21.970746 -12.0777) (xy 21.589746 -12.0777) (xy 21.081746 -12.5857)
				(xy 21.081746 -13.9827) (xy 21.462746 -14.3637) (xy 24.764746 -14.3637) (xy 25.653746 -14.3637)
				(xy 28.701746 -11.3157) (xy 37.337746 -11.3157) (xy 37.591746 -11.0617)
			)
		)
	)
	(zone
		(net "P12V_HDD14")
		(layer "In2.Cu")
		(hatch none 0.5)
		(connect_pads
			(clearance 0.5)
		)
		(min_thickness 0.25)
		(fill yes
			(thermal_gap 0.5)
			(thermal_bridge_width 0.5)
			(island_removal_mode 0)
		)
		(polygon
			(pts
				(xy 20.446746 -11.8237) (xy 23.621746 -11.8237) (xy 24.637746 -10.8077) (xy 26.479246 -8.9662) (xy 36.004246 -8.9662)
				(xy 36.702746 -8.2677) (xy 39.496746 -5.4737) (xy 70.992746 -5.4737) (xy 77.977746 -12.4587) (xy 79.120746 -12.4587)
				(xy 79.374746 -12.4587) (xy 80.263746 -11.5697) (xy 80.263746 -10.5537) (xy 72.262746 -2.5527) (xy 37.972746 -2.5527)
				(xy 34.543746 -5.9817) (xy 34.162746 -6.3627) (xy 33.654746 -6.3627) (xy 33.591246 -6.2992) (xy 24.320246 -6.2992)
				(xy 20.192746 -10.4267) (xy 20.192746 -11.5697)
			)
		)
	)
	(zone
		(layer "In2.Cu")
		(hatch none 0.5)
		(connect_pads
			(clearance 0)
		)
		(min_thickness 0.25)
		(keepout
			(tracks not_allowed)
			(vias allowed)
			(pads allowed)
			(copperpour not_allowed)
			(footprints allowed)
		)
		(placement
			(enabled no)
			(sheetname "")
		)
		(fill
			(thermal_gap 0.5)
			(thermal_bridge_width 0.5)
			(island_removal_mode 0)
		)
		(polygon
			(pts
				(arc
					(start 7.291578 -118.042436)
					(mid 7.086346 -117.957426)
					(end 6.881114 -118.042436)
				)
				(arc
					(start 6.881114 -118.042436)
					(mid 6.841595 -118.091263)
					(end 6.813296 -118.147338)
				)
				(arc
					(start 6.813296 -118.147338)
					(mid 6.713154 -118.71904)
					(end 6.682486 -118.139464)
				)
				(arc
					(start 6.682486 -118.139464)
					(mid 6.724701 -118.038931)
					(end 6.791198 -117.95252)
				)
				(arc
					(start 6.791198 -117.95252)
					(mid 7.043919 -117.832428)
					(end 7.315708 -117.898926)
				)
				(arc
					(start 7.314946 -117.697758)
					(mid 7.196416 -117.662396)
					(end 7.073138 -117.652292)
				)
				(arc
					(start 6.982968 -117.654324)
					(mid 6.446393 -117.432648)
					(end 7.01929 -117.526562)
				)
				(xy 7.07009 -117.525292) (xy 7.096506 -117.524784)
				(arc
					(start 7.097014 -117.525292)
					(mid 7.207144 -117.535345)
					(end 7.314438 -117.562122)
				)
				(xy 7.314184 -117.514624)
				(arc
					(start 7.314184 -117.510814)
					(mid 6.725539 -116.926106)
					(end 6.140704 -117.514624)
				)
				(arc
					(start 6.144006 -118.429532)
					(mid 6.732778 -119.01424)
					(end 7.317486 -118.425468)
				)
				(xy 7.316216 -118.065296)
			)
		)
	)
	(zone
		(layers "In2.Cu" "In5.Cu")
		(hatch none 0.5)
		(connect_pads
			(clearance 0)
		)
		(min_thickness 0.25)
		(keepout
			(tracks not_allowed)
			(vias allowed)
			(pads allowed)
			(copperpour not_allowed)
			(footprints allowed)
		)
		(placement
			(enabled no)
			(sheetname "")
		)
		(fill yes
			(thermal_gap 0.5)
			(thermal_bridge_width 0.5)
			(island_removal_mode 0)
		)
		(polygon
			(pts
				(arc
					(start 27.24023 -365.912654)
					(mid 26.644981 -365.334548)
					(end 26.06675 -365.929672)
				)
				(arc
					(start 26.083006 -367.02365)
					(mid 26.672794 -367.60181)
					(end 27.256486 -367.017554)
				)
				(arc
					(start 26.961846 -367.017554)
					(mid 26.669746 -367.307125)
					(end 26.377646 -367.017554)
				)
				(arc
					(start 26.377646 -367.015014)
					(mid 26.669746 -366.722914)
					(end 26.961846 -367.015014)
				)
				(xy 27.256486 -367.015014) (xy 27.256486 -367.006378) (xy 27.240484 -365.923576)
				(arc
					(start 26.94559 -365.923576)
					(mid 26.65349 -366.213147)
					(end 26.36139 -365.923576)
				)
				(arc
					(start 26.36139 -365.921036)
					(mid 26.65349 -365.628936)
					(end 26.94559 -365.921036)
				)
				(xy 27.24023 -365.921036)
			)
		)
	)
	(zone
		(layers "In2.Cu" "In5.Cu")
		(hatch none 0.5)
		(connect_pads
			(clearance 0)
		)
		(min_thickness 0.25)
		(keepout
			(tracks not_allowed)
			(vias allowed)
			(pads allowed)
			(copperpour not_allowed)
			(footprints allowed)
		)
		(placement
			(enabled no)
			(sheetname "")
		)
		(fill yes
			(thermal_gap 0.5)
			(thermal_bridge_width 0.5)
			(island_removal_mode 0)
		)
		(polygon
			(pts
				(arc
					(start 29.968444 -31.997142)
					(mid 29.432504 -31.461202)
					(end 28.896564 -31.997142)
				)
				(arc
					(start 28.896564 -33.0327)
					(mid 29.431234 -33.568638)
					(end 29.968444 -33.03524)
				)
				(arc
					(start 29.724604 -33.03524)
					(mid 29.432504 -33.324811)
					(end 29.140404 -33.03524)
				)
				(arc
					(start 29.140404 -33.0327)
					(mid 29.432504 -32.7406)
					(end 29.724604 -33.0327)
				)
				(xy 29.968444 -33.0327) (xy 29.968444 -31.999682)
				(arc
					(start 29.724604 -31.999682)
					(mid 29.432504 -32.289253)
					(end 29.140404 -31.999682)
				)
				(arc
					(start 29.140404 -31.997142)
					(mid 29.432504 -31.705042)
					(end 29.724604 -31.997142)
				)
			)
		)
	)
	(zone
		(layers "In2.Cu" "In5.Cu")
		(hatch none 0.5)
		(connect_pads
			(clearance 0)
		)
		(min_thickness 0.25)
		(keepout
			(tracks not_allowed)
			(vias allowed)
			(pads allowed)
			(copperpour not_allowed)
			(footprints allowed)
		)
		(placement
			(enabled no)
			(sheetname "")
		)
		(fill yes
			(thermal_gap 0.5)
			(thermal_bridge_width 0.5)
			(island_removal_mode 0)
		)
		(polygon
			(pts
				(arc
					(start 7.340346 -409.273756)
					(mid 6.779006 -409.835096)
					(end 7.340346 -410.396436)
				)
				(arc
					(start 8.203946 -410.396436)
					(mid 8.599974 -410.23292)
					(end 8.765286 -409.837636)
				)
				(arc
					(start 8.496046 -409.837636)
					(mid 8.203946 -410.127207)
					(end 7.911846 -409.837636)
				)
				(arc
					(start 7.632446 -409.837636)
					(mid 7.340346 -410.127207)
					(end 7.048246 -409.837636)
				)
				(arc
					(start 7.048246 -409.835096)
					(mid 7.340346 -409.542996)
					(end 7.632446 -409.835096)
				)
				(arc
					(start 7.911846 -409.835096)
					(mid 8.203946 -409.542996)
					(end 8.496046 -409.835096)
				)
				(arc
					(start 8.765286 -409.835096)
					(mid 8.600873 -409.438169)
					(end 8.203946 -409.273756)
				)
				(xy 7.3406 -409.273756)
			)
		)
	)
	(zone
		(layers "In2.Cu" "In5.Cu")
		(hatch none 0.5)
		(connect_pads
			(clearance 0)
		)
		(min_thickness 0.25)
		(keepout
			(tracks not_allowed)
			(vias allowed)
			(pads allowed)
			(copperpour not_allowed)
			(footprints allowed)
		)
		(placement
			(enabled no)
			(sheetname "")
		)
		(fill yes
			(thermal_gap 0.5)
			(thermal_bridge_width 0.5)
			(island_removal_mode 0)
		)
		(polygon
			(pts
				(arc
					(start 7.419086 -115.5319)
					(mid 6.840475 -114.945216)
					(end 6.24586 -115.515644)
				)
				(xy 6.24332 -115.515644) (xy 6.21792 -116.441982)
				(arc
					(start 6.22046 -116.441982)
					(mid 6.79069 -117.044724)
					(end 7.393432 -116.474494)
				)
				(xy 7.395972 -116.474494) (xy 7.396226 -116.460778)
				(arc
					(start 7.099046 -116.460778)
					(mid 6.806946 -116.750349)
					(end 6.514846 -116.460778)
				)
				(arc
					(start 6.514846 -116.458238)
					(mid 6.806946 -116.166138)
					(end 7.099046 -116.458238)
				)
				(xy 7.39648 -116.458238) (xy 7.421372 -115.54841) (xy 7.421118 -115.548156) (xy 7.418832 -115.548156)
				(xy 7.419086 -115.53444)
				(arc
					(start 7.124446 -115.53444)
					(mid 6.832346 -115.824011)
					(end 6.540246 -115.53444)
				)
				(arc
					(start 6.540246 -115.5319)
					(mid 6.832346 -115.2398)
					(end 7.124446 -115.5319)
				)
			)
		)
	)
	(zone
		(layers "In2.Cu" "In5.Cu")
		(hatch none 0.5)
		(connect_pads
			(clearance 0)
		)
		(min_thickness 0.25)
		(keepout
			(tracks not_allowed)
			(vias allowed)
			(pads allowed)
			(copperpour not_allowed)
			(footprints allowed)
		)
		(placement
			(enabled no)
			(sheetname "")
		)
		(fill yes
			(thermal_gap 0.5)
			(thermal_bridge_width 0.5)
			(island_removal_mode 0)
		)
		(polygon
			(pts
				(arc
					(start 7.292086 -127.499364)
					(mid 6.705346 -126.912624)
					(end 6.118606 -127.499364)
				)
				(arc
					(start 6.118606 -128.458214)
					(mid 6.704076 -129.044953)
					(end 7.292086 -128.460754)
				)
				(arc
					(start 6.997446 -128.460754)
					(mid 6.705346 -128.750325)
					(end 6.413246 -128.460754)
				)
				(arc
					(start 6.413246 -128.458214)
					(mid 6.705346 -128.166114)
					(end 6.997446 -128.458214)
				)
				(xy 7.292086 -128.458214) (xy 7.292086 -127.501904)
				(arc
					(start 6.997446 -127.501904)
					(mid 6.705346 -127.791475)
					(end 6.413246 -127.501904)
				)
				(arc
					(start 6.413246 -127.499364)
					(mid 6.705346 -127.207264)
					(end 6.997446 -127.499364)
				)
			)
		)
	)
	(zone
		(layers "In2.Cu" "In5.Cu")
		(hatch none 0.5)
		(connect_pads
			(clearance 0)
		)
		(min_thickness 0.25)
		(keepout
			(tracks not_allowed)
			(vias allowed)
			(pads allowed)
			(copperpour not_allowed)
			(footprints allowed)
		)
		(placement
			(enabled no)
			(sheetname "")
		)
		(fill yes
			(thermal_gap 0.5)
			(thermal_bridge_width 0.5)
			(island_removal_mode 0)
		)
		(polygon
			(pts
				(arc
					(start 22.65426 -341.08644)
					(mid 22.07006 -340.50224)
					(end 21.48586 -341.08644)
				)
				(arc
					(start 21.48586 -342.045036)
					(mid 22.068663 -342.629488)
					(end 22.65426 -342.04783)
				)
				(arc
					(start 22.36216 -342.04783)
					(mid 22.07006 -342.337401)
					(end 21.77796 -342.04783)
				)
				(arc
					(start 21.77796 -342.04529)
					(mid 22.07006 -341.75319)
					(end 22.36216 -342.04529)
				)
				(xy 22.65426 -342.04529) (xy 22.65426 -341.08898)
				(arc
					(start 22.36216 -341.08898)
					(mid 22.07006 -341.378551)
					(end 21.77796 -341.08898)
				)
				(arc
					(start 21.77796 -341.08644)
					(mid 22.07006 -340.79434)
					(end 22.36216 -341.08644)
				)
			)
		)
	)
	(zone
		(layers "In2.Cu" "In5.Cu")
		(hatch none 0.5)
		(connect_pads
			(clearance 0)
		)
		(min_thickness 0.25)
		(keepout
			(tracks not_allowed)
			(vias allowed)
			(pads allowed)
			(copperpour not_allowed)
			(footprints allowed)
		)
		(placement
			(enabled no)
			(sheetname "")
		)
		(fill yes
			(thermal_gap 0.5)
			(thermal_bridge_width 0.5)
			(island_removal_mode 0)
		)
		(polygon
			(pts
				(arc
					(start 8.799322 -352.903282)
					(mid 8.534323 -352.412623)
					(end 7.978648 -352.365056)
				)
				(xy 7.977632 -352.36277) (xy 7.00405 -352.786188) (xy 7.003796 -352.786442)
				(arc
					(start 7.004812 -352.788728)
					(mid 6.70054 -353.560934)
					(end 7.47268 -353.864926)
				)
				(xy 7.473696 -353.867212) (xy 8.447532 -353.443794)
				(arc
					(start 8.446516 -353.441508)
					(mid 8.536237 -353.392761)
					(end 8.616188 -353.32924)
				)
				(arc
					(start 7.530846 -353.32924)
					(mid 7.238746 -353.618811)
					(end 6.946646 -353.32924)
				)
				(arc
					(start 6.946646 -353.3267)
					(mid 7.238746 -353.0346)
					(end 7.530846 -353.3267)
				)
				(arc
					(start 8.618728 -353.3267)
					(mid 8.751772 -353.134607)
					(end 8.799322 -352.905822)
				)
				(arc
					(start 8.504682 -352.905822)
					(mid 8.212582 -353.195393)
					(end 7.920482 -352.905822)
				)
				(arc
					(start 7.920482 -352.903282)
					(mid 8.212582 -352.611182)
					(end 8.504682 -352.903282)
				)
			)
		)
	)
	(zone
		(layers "In2.Cu" "In5.Cu")
		(hatch none 0.5)
		(connect_pads
			(clearance 0)
		)
		(min_thickness 0.25)
		(keepout
			(tracks not_allowed)
			(vias allowed)
			(pads allowed)
			(copperpour not_allowed)
			(footprints allowed)
		)
		(placement
			(enabled no)
			(sheetname "")
		)
		(fill yes
			(thermal_gap 0.5)
			(thermal_bridge_width 0.5)
			(island_removal_mode 0)
		)
		(polygon
			(pts
				(arc
					(start 217.067892 -372.451884)
					(mid 216.892614 -372.033598)
					(end 216.4715 -371.865144)
				)
				(arc
					(start 215.608154 -371.879368)
					(mid 215.031064 -372.475633)
					(end 215.627204 -373.052848)
				)
				(arc
					(start 216.490804 -373.038624)
					(mid 216.898603 -372.864306)
					(end 217.067892 -372.454424)
				)
				(arc
					(start 216.773252 -372.454424)
					(mid 216.488269 -372.743908)
					(end 216.18956 -372.468648)
				)
				(arc
					(start 215.909652 -372.468648)
					(mid 215.617552 -372.758219)
					(end 215.325452 -372.468648)
				)
				(arc
					(start 215.325452 -372.466108)
					(mid 215.617552 -372.174008)
					(end 215.909652 -372.466108)
				)
				(xy 216.189306 -372.466108) (xy 216.189052 -372.454424)
				(arc
					(start 216.189052 -372.451884)
					(mid 216.481152 -372.159784)
					(end 216.773252 -372.451884)
				)
			)
		)
	)
	(zone
		(layers "In2.Cu" "In5.Cu")
		(hatch none 0.5)
		(connect_pads
			(clearance 0)
		)
		(min_thickness 0.25)
		(keepout
			(tracks not_allowed)
			(vias allowed)
			(pads allowed)
			(copperpour not_allowed)
			(footprints allowed)
		)
		(placement
			(enabled no)
			(sheetname "")
		)
		(fill yes
			(thermal_gap 0.5)
			(thermal_bridge_width 0.5)
			(island_removal_mode 0)
		)
		(polygon
			(pts
				(arc
					(start 31.777686 -63.2841)
					(mid 31.224149 -62.6983)
					(end 30.608016 -63.217806)
				)
				(xy 30.605476 -63.217552) (xy 30.503368 -64.11595) (xy 30.503622 -64.116204)
				(arc
					(start 30.505908 -64.116458)
					(mid 31.022544 -64.765682)
					(end 31.671768 -64.249046)
				)
				(xy 31.674308 -64.2493) (xy 31.681674 -64.185292)
				(arc
					(start 31.380938 -64.185292)
					(mid 31.088838 -64.474863)
					(end 30.796738 -64.185292)
				)
				(arc
					(start 30.796738 -64.182752)
					(mid 31.088838 -63.890652)
					(end 31.380938 -64.182752)
				)
				(xy 31.681928 -64.182752) (xy 31.776416 -63.350648)
				(arc
					(start 31.773876 -63.350394)
					(mid 31.776648 -63.318569)
					(end 31.777686 -63.28664)
				)
				(arc
					(start 31.483046 -63.28664)
					(mid 31.190946 -63.576211)
					(end 30.898846 -63.28664)
				)
				(arc
					(start 30.898846 -63.2841)
					(mid 31.190946 -62.992)
					(end 31.483046 -63.2841)
				)
			)
		)
	)
	(zone
		(layers "In2.Cu" "In5.Cu")
		(hatch none 0.5)
		(connect_pads
			(clearance 0)
		)
		(min_thickness 0.25)
		(keepout
			(tracks not_allowed)
			(vias allowed)
			(pads allowed)
			(copperpour not_allowed)
			(footprints allowed)
		)
		(placement
			(enabled no)
			(sheetname "")
		)
		(fill yes
			(thermal_gap 0.5)
			(thermal_bridge_width 0.5)
			(island_removal_mode 0)
		)
		(polygon
			(pts
				(arc
					(start 223.618552 -60.986162)
					(mid 223.031812 -60.399422)
					(end 222.445072 -60.986162)
				)
				(arc
					(start 222.445072 -61.945012)
					(mid 223.030542 -62.531751)
					(end 223.618552 -61.947552)
				)
				(arc
					(start 223.323912 -61.947552)
					(mid 223.031812 -62.237123)
					(end 222.739712 -61.947552)
				)
				(arc
					(start 222.739712 -61.945012)
					(mid 223.031812 -61.652912)
					(end 223.323912 -61.945012)
				)
				(xy 223.618552 -61.945012) (xy 223.618552 -60.988702)
				(arc
					(start 223.323912 -60.988702)
					(mid 223.031812 -61.278273)
					(end 222.739712 -60.988702)
				)
				(arc
					(start 222.739712 -60.986162)
					(mid 223.031812 -60.694062)
					(end 223.323912 -60.986162)
				)
			)
		)
	)
	(zone
		(layers "In2.Cu" "In5.Cu")
		(hatch none 0.5)
		(connect_pads
			(clearance 0)
		)
		(min_thickness 0.25)
		(keepout
			(tracks not_allowed)
			(vias allowed)
			(pads allowed)
			(copperpour not_allowed)
			(footprints allowed)
		)
		(placement
			(enabled no)
			(sheetname "")
		)
		(fill yes
			(thermal_gap 0.5)
			(thermal_bridge_width 0.5)
			(island_removal_mode 0)
		)
		(polygon
			(pts
				(arc
					(start 215.344756 -165.87724)
					(mid 214.747348 -166.453312)
					(end 215.32342 -167.05072)
				)
				(arc
					(start 216.186766 -167.066468)
					(mid 216.613457 -166.893877)
					(end 216.784174 -166.46652)
				)
				(arc
					(start 216.489534 -166.46652)
					(mid 216.197688 -166.771873)
					(end 215.905842 -166.46652)
				)
				(arc
					(start 215.626188 -166.46652)
					(mid 215.334088 -166.756091)
					(end 215.041988 -166.46652)
				)
				(arc
					(start 215.041988 -166.46398)
					(mid 215.334088 -166.17188)
					(end 215.626188 -166.46398)
				)
				(arc
					(start 215.906096 -166.46398)
					(mid 216.197688 -166.187711)
					(end 216.48928 -166.46398)
				)
				(arc
					(start 216.784174 -166.46398)
					(mid 216.610744 -166.063077)
					(end 216.208356 -165.892988)
				)
			)
		)
	)
	(zone
		(layers "In2.Cu" "In5.Cu")
		(hatch none 0.5)
		(connect_pads
			(clearance 0)
		)
		(min_thickness 0.25)
		(keepout
			(tracks not_allowed)
			(vias allowed)
			(pads allowed)
			(copperpour not_allowed)
			(footprints allowed)
		)
		(placement
			(enabled no)
			(sheetname "")
		)
		(fill yes
			(thermal_gap 0.5)
			(thermal_bridge_width 0.5)
			(island_removal_mode 0)
		)
		(polygon
			(pts
				(arc
					(start 31.979616 -372.061486)
					(mid 31.386018 -371.590316)
					(end 30.914848 -372.183914)
				)
				(xy 30.912308 -372.184168) (xy 31.034736 -373.248428) (xy 31.03499 -373.248682)
				(arc
					(start 31.037276 -373.248428)
					(mid 31.599049 -373.722299)
					(end 32.1056 -373.189754)
				)
				(arc
					(start 31.86176 -373.189754)
					(mid 31.56966 -373.479325)
					(end 31.27756 -373.189754)
				)
				(arc
					(start 31.27756 -373.187214)
					(mid 31.56966 -372.895114)
					(end 31.86176 -373.187214)
				)
				(arc
					(start 32.1056 -373.187214)
					(mid 32.104693 -373.156557)
					(end 32.102044 -373.126)
				)
				(xy 32.104584 -373.125746) (xy 31.989522 -372.12524)
				(arc
					(start 31.739332 -372.12524)
					(mid 31.447232 -372.414811)
					(end 31.155132 -372.12524)
				)
				(arc
					(start 31.155132 -372.1227)
					(mid 31.447232 -371.8306)
					(end 31.739332 -372.1227)
				)
				(xy 31.989268 -372.1227) (xy 31.982156 -372.061232)
			)
		)
	)
	(zone
		(layers "In2.Cu" "In5.Cu")
		(hatch none 0.5)
		(connect_pads
			(clearance 0)
		)
		(min_thickness 0.25)
		(keepout
			(tracks not_allowed)
			(vias allowed)
			(pads allowed)
			(copperpour not_allowed)
			(footprints allowed)
		)
		(placement
			(enabled no)
			(sheetname "")
		)
		(fill yes
			(thermal_gap 0.5)
			(thermal_bridge_width 0.5)
			(island_removal_mode 0)
		)
		(polygon
			(pts
				(arc
					(start 28.297886 -235.7755)
					(mid 27.733001 -235.189167)
					(end 27.12593 -235.731812)
				)
				(arc
					(start 27.061414 -236.59719)
					(mid 27.602942 -237.226094)
					(end 28.231846 -236.684566)
				)
				(xy 28.234894 -236.643418)
				(arc
					(start 27.93873 -236.643418)
					(mid 27.64663 -236.932989)
					(end 27.35453 -236.643418)
				)
				(arc
					(start 27.35453 -236.640878)
					(mid 27.64663 -236.348778)
					(end 27.93873 -236.640878)
				)
				(xy 28.235148 -236.640878) (xy 28.296362 -235.819442) (xy 28.297886 -235.77804)
				(arc
					(start 28.003246 -235.77804)
					(mid 27.711146 -236.067611)
					(end 27.419046 -235.77804)
				)
				(arc
					(start 27.419046 -235.7755)
					(mid 27.711146 -235.4834)
					(end 28.003246 -235.7755)
				)
			)
		)
	)
	(zone
		(layers "In2.Cu" "In5.Cu")
		(hatch none 0.5)
		(connect_pads
			(clearance 0)
		)
		(min_thickness 0.25)
		(keepout
			(tracks not_allowed)
			(vias allowed)
			(pads allowed)
			(copperpour not_allowed)
			(footprints allowed)
		)
		(placement
			(enabled no)
			(sheetname "")
		)
		(fill yes
			(thermal_gap 0.5)
			(thermal_bridge_width 0.5)
			(island_removal_mode 0)
		)
		(polygon
			(pts
				(arc
					(start 9.857486 -131.51485)
					(mid 9.270746 -130.92811)
					(end 8.684006 -131.51485)
				)
				(arc
					(start 8.684006 -132.4737)
					(mid 9.269476 -133.060439)
					(end 9.857486 -132.47624)
				)
				(arc
					(start 9.562846 -132.47624)
					(mid 9.270746 -132.765811)
					(end 8.978646 -132.47624)
				)
				(arc
					(start 8.978646 -132.4737)
					(mid 9.270746 -132.1816)
					(end 9.562846 -132.4737)
				)
				(xy 9.857486 -132.4737) (xy 9.857486 -131.51739)
				(arc
					(start 9.562846 -131.51739)
					(mid 9.270746 -131.806961)
					(end 8.978646 -131.51739)
				)
				(arc
					(start 8.978646 -131.51485)
					(mid 9.270746 -131.22275)
					(end 9.562846 -131.51485)
				)
			)
		)
	)
	(zone
		(layers "In2.Cu" "In5.Cu")
		(hatch none 0.5)
		(connect_pads
			(clearance 0)
		)
		(min_thickness 0.25)
		(keepout
			(tracks not_allowed)
			(vias allowed)
			(pads allowed)
			(copperpour not_allowed)
			(footprints allowed)
		)
		(placement
			(enabled no)
			(sheetname "")
		)
		(fill yes
			(thermal_gap 0.5)
			(thermal_bridge_width 0.5)
			(island_removal_mode 0)
		)
		(polygon
			(pts
				(arc
					(start 223.612456 -369.9383)
					(mid 223.042235 -369.351793)
					(end 222.439992 -369.90528)
				)
				(xy 222.437452 -369.905026) (xy 222.386398 -370.80444)
				(arc
					(start 222.388938 -370.804694)
					(mid 222.941642 -371.423438)
					(end 223.560386 -370.870734)
				)
				(xy 223.562926 -370.870988) (xy 223.564704 -370.840254)
				(arc
					(start 223.266762 -370.840254)
					(mid 222.974662 -371.129825)
					(end 222.682562 -370.840254)
				)
				(arc
					(start 222.682562 -370.837714)
					(mid 222.974662 -370.545614)
					(end 223.266762 -370.837714)
				)
				(xy 223.564704 -370.837714) (xy 223.61398 -369.971828) (xy 223.613726 -369.971574) (xy 223.61144 -369.971574)
				(xy 223.612456 -369.94084)
				(arc
					(start 223.317816 -369.94084)
					(mid 223.025716 -370.230411)
					(end 222.733616 -369.94084)
				)
				(arc
					(start 222.733616 -369.9383)
					(mid 223.025716 -369.6462)
					(end 223.317816 -369.9383)
				)
			)
		)
	)
	(zone
		(layers "In2.Cu" "In5.Cu")
		(hatch none 0.5)
		(connect_pads
			(clearance 0)
		)
		(min_thickness 0.25)
		(keepout
			(tracks not_allowed)
			(vias allowed)
			(pads allowed)
			(copperpour not_allowed)
			(footprints allowed)
		)
		(placement
			(enabled no)
			(sheetname "")
		)
		(fill yes
			(thermal_gap 0.5)
			(thermal_bridge_width 0.5)
			(island_removal_mode 0)
		)
		(polygon
			(pts
				(arc
					(start 9.29005 -376.347482)
					(mid 9.112584 -375.949075)
					(end 8.697722 -375.81459)
				)
				(xy 8.697468 -375.81205) (xy 7.817104 -375.905268)
				(arc
					(start 7.817358 -375.907808)
					(mid 7.340854 -376.497088)
					(end 7.930134 -376.973592)
				)
				(xy 7.930388 -376.976132) (xy 8.810498 -376.882914) (xy 8.810752 -376.88266)
				(arc
					(start 8.810498 -376.880374)
					(mid 9.151612 -376.70685)
					(end 9.29005 -376.350022)
				)
				(arc
					(start 9.04621 -376.350022)
					(mid 8.801432 -376.635734)
					(end 8.478266 -376.44324)
				)
				(arc
					(start 8.165846 -376.44324)
					(mid 7.873746 -376.732811)
					(end 7.581646 -376.44324)
				)
				(arc
					(start 7.581646 -376.4407)
					(mid 7.873746 -376.1486)
					(end 8.165846 -376.4407)
				)
				(arc
					(start 8.47725 -376.4407)
					(mid 8.466029 -376.395965)
					(end 8.46201 -376.350022)
				)
				(arc
					(start 8.46201 -376.347482)
					(mid 8.75411 -376.055382)
					(end 9.04621 -376.347482)
				)
			)
		)
	)
	(zone
		(layers "In2.Cu" "In5.Cu")
		(hatch none 0.5)
		(connect_pads
			(clearance 0)
		)
		(min_thickness 0.25)
		(keepout
			(tracks not_allowed)
			(vias allowed)
			(pads allowed)
			(copperpour not_allowed)
			(footprints allowed)
		)
		(placement
			(enabled no)
			(sheetname "")
		)
		(fill yes
			(thermal_gap 0.5)
			(thermal_bridge_width 0.5)
			(island_removal_mode 0)
		)
		(polygon
			(pts
				(arc
					(start 217.375486 -475.243144)
					(mid 217.202375 -474.827001)
					(end 216.78519 -474.656404)
				)
				(arc
					(start 215.92159 -474.661484)
					(mid 215.338406 -475.25178)
					(end 215.928702 -475.834964)
				)
				(arc
					(start 216.792048 -475.829884)
					(mid 217.20391 -475.657769)
					(end 217.375486 -475.245684)
				)
				(arc
					(start 217.080846 -475.245684)
					(mid 216.791285 -475.535244)
					(end 216.496646 -475.250764)
				)
				(arc
					(start 216.217246 -475.250764)
					(mid 215.925146 -475.540335)
					(end 215.633046 -475.250764)
				)
				(arc
					(start 215.633046 -475.248224)
					(mid 215.925146 -474.956124)
					(end 216.217246 -475.248224)
				)
				(xy 216.496646 -475.248224) (xy 216.496646 -475.245684)
				(arc
					(start 216.496646 -475.243144)
					(mid 216.788746 -474.951044)
					(end 217.080846 -475.243144)
				)
			)
		)
	)
	(zone
		(layers "In2.Cu" "In5.Cu")
		(hatch none 0.5)
		(connect_pads
			(clearance 0)
		)
		(min_thickness 0.25)
		(keepout
			(tracks not_allowed)
			(vias allowed)
			(pads allowed)
			(copperpour not_allowed)
			(footprints allowed)
		)
		(placement
			(enabled no)
			(sheetname "")
		)
		(fill yes
			(thermal_gap 0.5)
			(thermal_bridge_width 0.5)
			(island_removal_mode 0)
		)
		(polygon
			(pts
				(arc
					(start 7.266686 -101.498654)
					(mid 6.679946 -100.911914)
					(end 6.093206 -101.498654)
				)
				(arc
					(start 6.093206 -102.457504)
					(mid 6.678676 -103.044243)
					(end 7.266686 -102.460044)
				)
				(arc
					(start 6.972046 -102.460044)
					(mid 6.679946 -102.749615)
					(end 6.387846 -102.460044)
				)
				(arc
					(start 6.387846 -102.457504)
					(mid 6.679946 -102.165404)
					(end 6.972046 -102.457504)
				)
				(xy 7.266686 -102.457504) (xy 7.266686 -101.501194)
				(arc
					(start 6.972046 -101.501194)
					(mid 6.679946 -101.790765)
					(end 6.387846 -101.501194)
				)
				(arc
					(start 6.387846 -101.498654)
					(mid 6.679946 -101.206554)
					(end 6.972046 -101.498654)
				)
			)
		)
	)
	(zone
		(layers "In2.Cu" "In5.Cu")
		(hatch none 0.5)
		(connect_pads
			(clearance 0)
		)
		(min_thickness 0.25)
		(keepout
			(tracks not_allowed)
			(vias allowed)
			(pads allowed)
			(copperpour not_allowed)
			(footprints allowed)
		)
		(placement
			(enabled no)
			(sheetname "")
		)
		(fill yes
			(thermal_gap 0.5)
			(thermal_bridge_width 0.5)
			(island_removal_mode 0)
		)
		(polygon
			(pts
				(arc
					(start 29.138626 -344.885518)
					(mid 28.463364 -344.403151)
					(end 27.980894 -345.078304)
				)
				(arc
					(start 28.12288 -345.93022)
					(mid 28.748904 -346.418872)
					(end 29.288486 -345.83624)
				)
				(arc
					(start 28.993846 -345.83624)
					(mid 28.701746 -346.125811)
					(end 28.409646 -345.83624)
				)
				(arc
					(start 28.409646 -345.8337)
					(mid 28.701746 -345.5416)
					(end 28.993846 -345.8337)
				)
				(arc
					(start 29.288486 -345.8337)
					(mid 29.286548 -345.785277)
					(end 29.280612 -345.73718)
				)
				(xy 29.155136 -344.984324)
				(arc
					(start 28.85186 -344.984324)
					(mid 28.55976 -345.273895)
					(end 28.26766 -344.984324)
				)
				(arc
					(start 28.26766 -344.981784)
					(mid 28.55976 -344.689684)
					(end 28.85186 -344.981784)
				)
				(xy 29.154628 -344.981784)
			)
		)
	)
	(zone
		(layers "In2.Cu" "In5.Cu")
		(hatch none 0.5)
		(connect_pads
			(clearance 0)
		)
		(min_thickness 0.25)
		(keepout
			(tracks not_allowed)
			(vias allowed)
			(pads allowed)
			(copperpour not_allowed)
			(footprints allowed)
		)
		(placement
			(enabled no)
			(sheetname "")
		)
		(fill yes
			(thermal_gap 0.5)
			(thermal_bridge_width 0.5)
			(island_removal_mode 0)
		)
		(polygon
			(pts
				(arc
					(start 7.266686 -97.498916)
					(mid 6.679946 -96.912176)
					(end 6.093206 -97.498916)
				)
				(arc
					(start 6.093206 -98.457766)
					(mid 6.678676 -99.044505)
					(end 7.266686 -98.460306)
				)
				(arc
					(start 6.972046 -98.460306)
					(mid 6.679946 -98.749877)
					(end 6.387846 -98.460306)
				)
				(arc
					(start 6.387846 -98.457766)
					(mid 6.679946 -98.165666)
					(end 6.972046 -98.457766)
				)
				(xy 7.266686 -98.457766) (xy 7.266686 -97.501456)
				(arc
					(start 6.972046 -97.501456)
					(mid 6.679946 -97.791027)
					(end 6.387846 -97.501456)
				)
				(arc
					(start 6.387846 -97.498916)
					(mid 6.679946 -97.206816)
					(end 6.972046 -97.498916)
				)
			)
		)
	)
	(zone
		(layers "In2.Cu" "In5.Cu")
		(hatch none 0.5)
		(connect_pads
			(clearance 0)
		)
		(min_thickness 0.25)
		(keepout
			(tracks not_allowed)
			(vias allowed)
			(pads allowed)
			(copperpour not_allowed)
			(footprints allowed)
		)
		(placement
			(enabled no)
			(sheetname "")
		)
		(fill yes
			(thermal_gap 0.5)
			(thermal_bridge_width 0.5)
			(island_removal_mode 0)
		)
		(polygon
			(pts
				(arc
					(start 7.746746 -379.79096)
					(mid 7.160006 -380.3777)
					(end 7.746746 -380.96444)
				)
				(xy 8.660892 -380.96444)
				(arc
					(start 8.661146 -380.96444)
					(mid 9.075135 -380.793485)
					(end 9.247886 -380.38024)
				)
				(arc
					(start 8.953246 -380.38024)
					(mid 8.661146 -380.669811)
					(end 8.369046 -380.38024)
				)
				(arc
					(start 8.038846 -380.38024)
					(mid 7.746746 -380.669811)
					(end 7.454646 -380.38024)
				)
				(arc
					(start 7.454646 -380.3777)
					(mid 7.746746 -380.0856)
					(end 8.038846 -380.3777)
				)
				(arc
					(start 8.369046 -380.3777)
					(mid 8.661146 -380.0856)
					(end 8.953246 -380.3777)
				)
				(arc
					(start 9.247886 -380.3777)
					(mid 9.076034 -379.962812)
					(end 8.661146 -379.79096)
				)
			)
		)
	)
	(zone
		(layers "In2.Cu" "In5.Cu")
		(hatch none 0.5)
		(connect_pads
			(clearance 0)
		)
		(min_thickness 0.25)
		(keepout
			(tracks not_allowed)
			(vias allowed)
			(pads allowed)
			(copperpour not_allowed)
			(footprints allowed)
		)
		(placement
			(enabled no)
			(sheetname "")
		)
		(fill yes
			(thermal_gap 0.5)
			(thermal_bridge_width 0.5)
			(island_removal_mode 0)
		)
		(polygon
			(pts
				(arc
					(start 36.908486 -369.918742)
					(mid 36.329748 -369.332057)
					(end 35.73526 -369.90274)
				)
				(xy 35.73272 -369.90274) (xy 35.707574 -370.823998)
				(arc
					(start 35.710114 -370.823998)
					(mid 36.280598 -371.426486)
					(end 36.883086 -370.856002)
				)
				(xy 36.885626 -370.856002) (xy 36.88588 -370.84254)
				(arc
					(start 36.5887 -370.84254)
					(mid 36.2966 -371.132111)
					(end 36.0045 -370.84254)
				)
				(arc
					(start 36.0045 -370.84)
					(mid 36.2966 -370.5479)
					(end 36.5887 -370.84)
				)
				(xy 36.886134 -370.84) (xy 36.910772 -369.934998) (xy 36.910518 -369.934744) (xy 36.908232 -369.934744)
				(xy 36.908486 -369.921282)
				(arc
					(start 36.613846 -369.921282)
					(mid 36.321746 -370.210853)
					(end 36.029646 -369.921282)
				)
				(arc
					(start 36.029646 -369.918742)
					(mid 36.321746 -369.626642)
					(end 36.613846 -369.918742)
				)
			)
		)
	)
	(zone
		(layers "In2.Cu" "In5.Cu")
		(hatch none 0.5)
		(connect_pads
			(clearance 0)
		)
		(min_thickness 0.25)
		(keepout
			(tracks not_allowed)
			(vias allowed)
			(pads allowed)
			(copperpour not_allowed)
			(footprints allowed)
		)
		(placement
			(enabled no)
			(sheetname "")
		)
		(fill yes
			(thermal_gap 0.5)
			(thermal_bridge_width 0.5)
			(island_removal_mode 0)
		)
		(polygon
			(pts
				(arc
					(start 8.33628 -399.300446)
					(mid 8.155542 -398.877944)
					(end 7.725156 -398.716754)
				)
				(arc
					(start 6.862318 -398.756378)
					(mid 6.30555 -399.366994)
					(end 6.916166 -399.923762)
				)
				(arc
					(start 7.77875 -399.884138)
					(mid 8.173689 -399.704987)
					(end 8.33628 -399.302986)
				)
				(arc
					(start 8.04418 -399.302986)
					(mid 7.771951 -399.59188)
					(end 7.463028 -399.34261)
				)
				(arc
					(start 7.181342 -399.34261)
					(mid 6.889242 -399.632181)
					(end 6.597142 -399.34261)
				)
				(arc
					(start 6.597142 -399.34007)
					(mid 6.889242 -399.04797)
					(end 7.181342 -399.34007)
				)
				(arc
					(start 7.462774 -399.34007)
					(mid 7.46079 -399.321572)
					(end 7.45998 -399.302986)
				)
				(arc
					(start 7.45998 -399.300446)
					(mid 7.75208 -399.008346)
					(end 8.04418 -399.300446)
				)
			)
		)
	)
	(zone
		(layers "In2.Cu" "In5.Cu")
		(hatch none 0.5)
		(connect_pads
			(clearance 0)
		)
		(min_thickness 0.25)
		(keepout
			(tracks not_allowed)
			(vias allowed)
			(pads allowed)
			(copperpour not_allowed)
			(footprints allowed)
		)
		(placement
			(enabled no)
			(sheetname "")
		)
		(fill yes
			(thermal_gap 0.5)
			(thermal_bridge_width 0.5)
			(island_removal_mode 0)
		)
		(polygon
			(pts
				(arc
					(start 30.4038 -362.255054)
					(mid 29.81706 -361.668314)
					(end 29.23032 -362.255054)
				)
				(arc
					(start 29.23032 -363.213904)
					(mid 29.81579 -363.800643)
					(end 30.4038 -363.216444)
				)
				(arc
					(start 30.10916 -363.216444)
					(mid 29.81706 -363.506015)
					(end 29.52496 -363.216444)
				)
				(arc
					(start 29.52496 -363.213904)
					(mid 29.81706 -362.921804)
					(end 30.10916 -363.213904)
				)
				(xy 30.4038 -363.213904) (xy 30.4038 -362.257594)
				(arc
					(start 30.10916 -362.257594)
					(mid 29.81706 -362.547165)
					(end 29.52496 -362.257594)
				)
				(arc
					(start 29.52496 -362.255054)
					(mid 29.81706 -361.962954)
					(end 30.10916 -362.255054)
				)
			)
		)
	)
	(zone
		(layers "In2.Cu" "In5.Cu")
		(hatch none 0.5)
		(connect_pads
			(clearance 0)
		)
		(min_thickness 0.25)
		(keepout
			(tracks not_allowed)
			(vias allowed)
			(pads allowed)
			(copperpour not_allowed)
			(footprints allowed)
		)
		(placement
			(enabled no)
			(sheetname "")
		)
		(fill yes
			(thermal_gap 0.5)
			(thermal_bridge_width 0.5)
			(island_removal_mode 0)
		)
		(polygon
			(pts
				(arc
					(start 7.312914 -367.331752)
					(mid 6.753606 -367.843308)
					(end 7.265162 -368.402616)
				)
				(arc
					(start 8.127746 -368.441224)
					(mid 8.535074 -368.280531)
					(end 8.686546 -367.869724)
				)
				(arc
					(start 8.44169 -367.869724)
					(mid 8.151876 -368.197842)
					(end 7.862062 -367.869724)
				)
				(arc
					(start 7.581138 -367.869724)
					(mid 7.289038 -368.159295)
					(end 6.996938 -367.869724)
				)
				(arc
					(start 6.996938 -367.867184)
					(mid 7.289038 -367.575084)
					(end 7.581138 -367.867184)
				)
				(arc
					(start 7.862316 -367.867184)
					(mid 8.151876 -367.613669)
					(end 8.441436 -367.867184)
				)
				(arc
					(start 8.686546 -367.867184)
					(mid 8.525677 -367.521559)
					(end 8.175752 -367.37036)
				)
			)
		)
	)
	(zone
		(layers "In2.Cu" "In5.Cu")
		(hatch none 0.5)
		(connect_pads
			(clearance 0)
		)
		(min_thickness 0.25)
		(keepout
			(tracks not_allowed)
			(vias allowed)
			(pads allowed)
			(copperpour not_allowed)
			(footprints allowed)
		)
		(placement
			(enabled no)
			(sheetname "")
		)
		(fill yes
			(thermal_gap 0.5)
			(thermal_bridge_width 0.5)
			(island_removal_mode 0)
		)
		(polygon
			(pts
				(xy 7.278878 -421.34028)
				(arc
					(start 7.278878 -421.34282)
					(mid 6.703314 -421.889428)
					(end 7.249922 -422.464992)
				)
				(xy 7.249922 -422.467532) (xy 8.113014 -422.489884) (xy 8.113268 -422.48963)
				(arc
					(start 8.113268 -422.487344)
					(mid 8.526506 -422.321249)
					(end 8.688832 -421.906446)
				)
				(arc
					(start 8.419084 -421.906446)
					(mid 8.127746 -422.218269)
					(end 7.836408 -421.906446)
				)
				(arc
					(start 7.5565 -421.906446)
					(mid 7.2644 -422.196017)
					(end 6.9723 -421.906446)
				)
				(arc
					(start 6.9723 -421.903906)
					(mid 7.2644 -421.611806)
					(end 7.5565 -421.903906)
				)
				(arc
					(start 7.836408 -421.903906)
					(mid 8.127746 -421.634064)
					(end 8.419084 -421.903906)
				)
				(arc
					(start 8.688578 -421.903906)
					(mid 8.521834 -421.526599)
					(end 8.142224 -421.365172)
				)
				(xy 8.142224 -421.362632)
			)
		)
	)
	(zone
		(layers "In2.Cu" "In5.Cu")
		(hatch none 0.5)
		(connect_pads
			(clearance 0)
		)
		(min_thickness 0.25)
		(keepout
			(tracks not_allowed)
			(vias allowed)
			(pads allowed)
			(copperpour not_allowed)
			(footprints allowed)
		)
		(placement
			(enabled no)
			(sheetname "")
		)
		(fill yes
			(thermal_gap 0.5)
			(thermal_bridge_width 0.5)
			(island_removal_mode 0)
		)
		(polygon
			(pts
				(arc
					(start 22.581108 -32.148526)
					(mid 21.950172 -31.609538)
					(end 21.411184 -32.240474)
				)
				(arc
					(start 21.487384 -33.209738)
					(mid 22.093954 -33.750366)
					(end 22.659086 -33.166558)
				)
				(arc
					(start 22.364446 -33.166558)
					(mid 22.072346 -33.456129)
					(end 21.780246 -33.166558)
				)
				(arc
					(start 21.780246 -33.164018)
					(mid 22.072346 -32.871918)
					(end 22.364446 -33.164018)
				)
				(xy 22.659086 -33.164018) (xy 22.657308 -33.118044) (xy 22.584918 -32.19704)
				(arc
					(start 22.288246 -32.19704)
					(mid 21.996146 -32.486611)
					(end 21.704046 -32.19704)
				)
				(arc
					(start 21.704046 -32.1945)
					(mid 21.996146 -31.9024)
					(end 22.288246 -32.1945)
				)
				(xy 22.584664 -32.1945)
			)
		)
	)
	(zone
		(layers "In2.Cu" "In5.Cu")
		(hatch none 0.5)
		(connect_pads
			(clearance 0)
		)
		(min_thickness 0.25)
		(keepout
			(tracks not_allowed)
			(vias allowed)
			(pads allowed)
			(copperpour not_allowed)
			(footprints allowed)
		)
		(placement
			(enabled no)
			(sheetname "")
		)
		(fill yes
			(thermal_gap 0.5)
			(thermal_bridge_width 0.5)
			(island_removal_mode 0)
		)
		(polygon
			(pts
				(arc
					(start 22.532086 -238.0107)
					(mid 21.979949 -237.424981)
					(end 21.36267 -237.941612)
				)
				(arc
					(start 21.26107 -238.799624)
					(mid 21.774529 -239.451657)
					(end 22.426422 -238.938054)
				)
				(xy 22.434296 -238.871506)
				(arc
					(start 22.135846 -238.871506)
					(mid 21.843746 -239.161077)
					(end 21.551646 -238.871506)
				)
				(arc
					(start 21.551646 -238.868966)
					(mid 21.843746 -238.576866)
					(end 22.135846 -238.868966)
				)
				(xy 22.43455 -238.868966)
				(arc
					(start 22.528022 -238.079788)
					(mid 22.531006 -238.046572)
					(end 22.532086 -238.01324)
				)
				(arc
					(start 22.237446 -238.01324)
					(mid 21.945346 -238.302811)
					(end 21.653246 -238.01324)
				)
				(arc
					(start 21.653246 -238.0107)
					(mid 21.945346 -237.7186)
					(end 22.237446 -238.0107)
				)
			)
		)
	)
	(zone
		(layers "In2.Cu" "In5.Cu")
		(hatch none 0.5)
		(connect_pads
			(clearance 0)
		)
		(min_thickness 0.25)
		(keepout
			(tracks not_allowed)
			(vias allowed)
			(pads allowed)
			(copperpour not_allowed)
			(footprints allowed)
		)
		(placement
			(enabled no)
			(sheetname "")
		)
		(fill yes
			(thermal_gap 0.5)
			(thermal_bridge_width 0.5)
			(island_removal_mode 0)
		)
		(polygon
			(pts
				(arc
					(start 28.330652 -338.66201)
					(mid 27.743912 -338.07527)
					(end 27.157172 -338.66201)
				)
				(arc
					(start 27.157172 -339.620606)
					(mid 27.742515 -340.207598)
					(end 28.330652 -339.6234)
				)
				(arc
					(start 28.036012 -339.6234)
					(mid 27.743912 -339.912971)
					(end 27.451812 -339.6234)
				)
				(arc
					(start 27.451812 -339.62086)
					(mid 27.743912 -339.32876)
					(end 28.036012 -339.62086)
				)
				(xy 28.330652 -339.62086) (xy 28.330652 -338.66455)
				(arc
					(start 28.036012 -338.66455)
					(mid 27.743912 -338.954121)
					(end 27.451812 -338.66455)
				)
				(arc
					(start 27.451812 -338.66201)
					(mid 27.743912 -338.36991)
					(end 28.036012 -338.66201)
				)
			)
		)
	)
	(zone
		(layers "In2.Cu" "In5.Cu")
		(hatch none 0.5)
		(connect_pads
			(clearance 0)
		)
		(min_thickness 0.25)
		(keepout
			(tracks not_allowed)
			(vias allowed)
			(pads allowed)
			(copperpour not_allowed)
			(footprints allowed)
		)
		(placement
			(enabled no)
			(sheetname "")
		)
		(fill yes
			(thermal_gap 0.5)
			(thermal_bridge_width 0.5)
			(island_removal_mode 0)
		)
		(polygon
			(pts
				(arc
					(start 7.374382 -165.563804)
					(mid 6.757924 -165.013894)
					(end 6.208014 -165.630352)
				)
				(xy 6.205474 -165.630606) (xy 6.272022 -166.797228)
				(arc
					(start 6.274562 -166.796974)
					(mid 6.873121 -167.347391)
					(end 7.441946 -166.76624)
				)
				(arc
					(start 7.149846 -166.76624)
					(mid 6.857746 -167.055811)
					(end 6.565646 -166.76624)
				)
				(arc
					(start 6.565646 -166.7637)
					(mid 6.857746 -166.4716)
					(end 7.149846 -166.7637)
				)
				(xy 7.441946 -166.7637) (xy 7.44093 -166.730426) (xy 7.44347 -166.730172) (xy 7.378954 -165.599618)
				(arc
					(start 7.083298 -165.599618)
					(mid 6.791198 -165.889189)
					(end 6.499098 -165.599618)
				)
				(arc
					(start 6.499098 -165.597078)
					(mid 6.791198 -165.304978)
					(end 7.083298 -165.597078)
				)
				(xy 7.3787 -165.597078) (xy 7.376922 -165.563804) (xy 7.376668 -165.563804)
			)
		)
	)
	(zone
		(layers "In2.Cu" "In5.Cu")
		(hatch none 0.5)
		(connect_pads
			(clearance 0)
		)
		(min_thickness 0.25)
		(keepout
			(tracks not_allowed)
			(vias allowed)
			(pads allowed)
			(copperpour not_allowed)
			(footprints allowed)
		)
		(placement
			(enabled no)
			(sheetname "")
		)
		(fill yes
			(thermal_gap 0.5)
			(thermal_bridge_width 0.5)
			(island_removal_mode 0)
		)
		(polygon
			(pts
				(arc
					(start 22.225508 -444.181992)
					(mid 21.613876 -443.62116)
					(end 21.053044 -444.232792)
				)
				(arc
					(start 21.090382 -445.095376)
					(mid 21.68792 -445.657135)
					(end 22.263354 -445.07277)
				)
				(arc
					(start 21.968714 -445.07277)
					(mid 21.676614 -445.362341)
					(end 21.384514 -445.07277)
				)
				(arc
					(start 21.384514 -445.07023)
					(mid 21.676614 -444.77813)
					(end 21.968714 -445.07023)
				)
				(xy 22.263354 -445.07023) (xy 22.262846 -445.04483) (xy 22.226778 -444.209932)
				(arc
					(start 21.931376 -444.209932)
					(mid 21.639276 -444.499503)
					(end 21.347176 -444.209932)
				)
				(arc
					(start 21.347176 -444.207392)
					(mid 21.639276 -443.915292)
					(end 21.931376 -444.207392)
				)
				(xy 22.226524 -444.207392)
			)
		)
	)
	(zone
		(layers "In2.Cu" "In5.Cu")
		(hatch none 0.5)
		(connect_pads
			(clearance 0)
		)
		(min_thickness 0.25)
		(keepout
			(tracks not_allowed)
			(vias allowed)
			(pads allowed)
			(copperpour not_allowed)
			(footprints allowed)
		)
		(placement
			(enabled no)
			(sheetname "")
		)
		(fill yes
			(thermal_gap 0.5)
			(thermal_bridge_width 0.5)
			(island_removal_mode 0)
		)
		(polygon
			(pts
				(arc
					(start 7.075932 -347.585538)
					(mid 6.495923 -347.001353)
					(end 5.907532 -347.577156)
				)
				(arc
					(start 5.894578 -348.491048)
					(mid 6.470396 -349.08363)
					(end 7.062978 -348.507812)
				)
				(xy 7.062978 -348.50197)
				(arc
					(start 6.770878 -348.50197)
					(mid 6.478778 -348.791541)
					(end 6.186678 -348.50197)
				)
				(arc
					(start 6.186678 -348.49943)
					(mid 6.478778 -348.20733)
					(end 6.770878 -348.49943)
				)
				(xy 7.062978 -348.49943) (xy 7.075932 -347.594174) (xy 7.075932 -347.588078)
				(arc
					(start 6.783832 -347.588078)
					(mid 6.491732 -347.877649)
					(end 6.199632 -347.588078)
				)
				(arc
					(start 6.199632 -347.585538)
					(mid 6.491732 -347.293438)
					(end 6.783832 -347.585538)
				)
			)
		)
	)
	(zone
		(layers "In2.Cu" "In5.Cu")
		(hatch none 0.5)
		(connect_pads
			(clearance 0)
		)
		(min_thickness 0.25)
		(keepout
			(tracks not_allowed)
			(vias allowed)
			(pads allowed)
			(copperpour not_allowed)
			(footprints allowed)
		)
		(placement
			(enabled no)
			(sheetname "")
		)
		(fill yes
			(thermal_gap 0.5)
			(thermal_bridge_width 0.5)
			(island_removal_mode 0)
		)
		(polygon
			(pts
				(arc
					(start 216.811352 -63.493396)
					(mid 216.63544 -63.074487)
					(end 216.213182 -62.906656)
				)
				(arc
					(start 215.349836 -62.92342)
					(mid 214.774524 -63.521463)
					(end 215.372442 -64.0969)
				)
				(arc
					(start 216.236042 -64.080136)
					(mid 216.64271 -63.905207)
					(end 216.811352 -63.495936)
				)
				(arc
					(start 216.516712 -63.495936)
					(mid 216.233004 -63.785386)
					(end 215.933274 -63.5127)
				)
				(arc
					(start 215.653112 -63.5127)
					(mid 215.361012 -63.802271)
					(end 215.068912 -63.5127)
				)
				(arc
					(start 215.068912 -63.51016)
					(mid 215.361012 -63.21806)
					(end 215.653112 -63.51016)
				)
				(xy 215.93302 -63.51016) (xy 215.932512 -63.495936)
				(arc
					(start 215.932512 -63.493396)
					(mid 216.224612 -63.201296)
					(end 216.516712 -63.493396)
				)
			)
		)
	)
	(zone
		(layers "In2.Cu" "In5.Cu")
		(hatch none 0.5)
		(connect_pads
			(clearance 0)
		)
		(min_thickness 0.25)
		(keepout
			(tracks not_allowed)
			(vias allowed)
			(pads allowed)
			(copperpour not_allowed)
			(footprints allowed)
		)
		(placement
			(enabled no)
			(sheetname "")
		)
		(fill yes
			(thermal_gap 0.5)
			(thermal_bridge_width 0.5)
			(island_removal_mode 0)
		)
		(polygon
			(pts
				(arc
					(start 38.686486 -60.891166)
					(mid 38.099746 -60.304426)
					(end 37.513006 -60.891166)
				)
				(arc
					(start 37.513006 -61.850016)
					(mid 38.098476 -62.436755)
					(end 38.686486 -61.852556)
				)
				(arc
					(start 38.391846 -61.852556)
					(mid 38.099746 -62.142127)
					(end 37.807646 -61.852556)
				)
				(arc
					(start 37.807646 -61.850016)
					(mid 38.099746 -61.557916)
					(end 38.391846 -61.850016)
				)
				(xy 38.686486 -61.850016) (xy 38.686486 -60.893706)
				(arc
					(start 38.391846 -60.893706)
					(mid 38.099746 -61.183277)
					(end 37.807646 -60.893706)
				)
				(arc
					(start 37.807646 -60.891166)
					(mid 38.099746 -60.599066)
					(end 38.391846 -60.891166)
				)
			)
		)
	)
	(zone
		(layers "In2.Cu" "In5.Cu")
		(hatch none 0.5)
		(connect_pads
			(clearance 0)
		)
		(min_thickness 0.25)
		(keepout
			(tracks not_allowed)
			(vias allowed)
			(pads allowed)
			(copperpour not_allowed)
			(footprints allowed)
		)
		(placement
			(enabled no)
			(sheetname "")
		)
		(fill yes
			(thermal_gap 0.5)
			(thermal_bridge_width 0.5)
			(island_removal_mode 0)
		)
		(polygon
			(pts
				(arc
					(start 8.857742 -413.557974)
					(mid 8.574659 -413.070454)
					(end 8.010906 -413.074612)
				)
				(arc
					(start 7.215886 -413.544512)
					(mid 7.007016 -414.313851)
					(end 7.778242 -414.516062)
				)
				(xy 8.581898 -414.041336) (xy 8.591804 -414.03524)
				(arc
					(start 7.784846 -414.03524)
					(mid 7.492746 -414.324811)
					(end 7.200646 -414.03524)
				)
				(arc
					(start 7.200646 -414.0327)
					(mid 7.492746 -413.7406)
					(end 7.784846 -414.0327)
				)
				(arc
					(start 8.595868 -414.0327)
					(mid 8.787281 -413.830155)
					(end 8.857742 -413.560514)
				)
				(arc
					(start 8.588502 -413.560514)
					(mid 8.296402 -413.850085)
					(end 8.004302 -413.560514)
				)
				(arc
					(start 8.004302 -413.557974)
					(mid 8.296402 -413.265874)
					(end 8.588502 -413.557974)
				)
			)
		)
	)
	(zone
		(layers "In2.Cu" "In5.Cu")
		(hatch none 0.5)
		(connect_pads
			(clearance 0)
		)
		(min_thickness 0.25)
		(keepout
			(tracks not_allowed)
			(vias allowed)
			(pads allowed)
			(copperpour not_allowed)
			(footprints allowed)
		)
		(placement
			(enabled no)
			(sheetname "")
		)
		(fill yes
			(thermal_gap 0.5)
			(thermal_bridge_width 0.5)
			(island_removal_mode 0)
		)
		(polygon
			(pts
				(arc
					(start 26.58364 -341.503)
					(mid 25.9969 -340.91626)
					(end 25.41016 -341.503)
				)
				(arc
					(start 25.41016 -342.431116)
					(mid 25.99563 -343.017855)
					(end 26.58364 -342.433656)
				)
				(arc
					(start 26.289 -342.433656)
					(mid 25.9969 -342.723227)
					(end 25.7048 -342.433656)
				)
				(arc
					(start 25.7048 -342.431116)
					(mid 25.9969 -342.139016)
					(end 26.289 -342.431116)
				)
				(xy 26.58364 -342.431116) (xy 26.58364 -341.50554)
				(arc
					(start 26.289 -341.50554)
					(mid 25.9969 -341.795111)
					(end 25.7048 -341.50554)
				)
				(arc
					(start 25.7048 -341.503)
					(mid 25.9969 -341.2109)
					(end 26.289 -341.503)
				)
			)
		)
	)
	(zone
		(layers "In2.Cu" "In5.Cu")
		(hatch none 0.5)
		(connect_pads
			(clearance 0)
		)
		(min_thickness 0.25)
		(keepout
			(tracks not_allowed)
			(vias allowed)
			(pads allowed)
			(copperpour not_allowed)
			(footprints allowed)
		)
		(placement
			(enabled no)
			(sheetname "")
		)
		(fill yes
			(thermal_gap 0.5)
			(thermal_bridge_width 0.5)
			(island_removal_mode 0)
		)
		(polygon
			(pts
				(arc
					(start 220.782896 -472.90736)
					(mid 220.196156 -472.32062)
					(end 219.609416 -472.90736)
				)
				(arc
					(start 219.609416 -473.86621)
					(mid 220.194886 -474.452949)
					(end 220.782896 -473.86875)
				)
				(arc
					(start 220.488256 -473.86875)
					(mid 220.196156 -474.158321)
					(end 219.904056 -473.86875)
				)
				(arc
					(start 219.904056 -473.86621)
					(mid 220.196156 -473.57411)
					(end 220.488256 -473.86621)
				)
				(xy 220.782896 -473.86621) (xy 220.782896 -472.9099)
				(arc
					(start 220.488256 -472.9099)
					(mid 220.196156 -473.199471)
					(end 219.904056 -472.9099)
				)
				(arc
					(start 219.904056 -472.90736)
					(mid 220.196156 -472.61526)
					(end 220.488256 -472.90736)
				)
			)
		)
	)
	(zone
		(layers "In2.Cu" "In5.Cu")
		(hatch none 0.5)
		(connect_pads
			(clearance 0)
		)
		(min_thickness 0.25)
		(keepout
			(tracks not_allowed)
			(vias allowed)
			(pads allowed)
			(copperpour not_allowed)
			(footprints allowed)
		)
		(placement
			(enabled no)
			(sheetname "")
		)
		(fill yes
			(thermal_gap 0.5)
			(thermal_bridge_width 0.5)
			(island_removal_mode 0)
		)
		(polygon
			(pts
				(arc
					(start 7.53364 -417.243768)
					(mid 6.93852 -417.821999)
					(end 7.516622 -418.417248)
				)
				(arc
					(start 8.380222 -418.429694)
					(mid 8.804073 -418.257345)
					(end 8.975344 -417.833048)
				)
				(arc
					(start 8.68045 -417.833048)
					(mid 8.388604 -418.134968)
					(end 8.096758 -417.833048)
				)
				(arc
					(start 7.817104 -417.833048)
					(mid 7.525004 -418.122619)
					(end 7.232904 -417.833048)
				)
				(arc
					(start 7.232904 -417.830508)
					(mid 7.525004 -417.538408)
					(end 7.817104 -417.830508)
				)
				(arc
					(start 8.096758 -417.830508)
					(mid 8.388604 -417.550843)
					(end 8.68045 -417.830508)
				)
				(arc
					(start 8.97509 -417.830508)
					(mid 8.801965 -417.426717)
					(end 8.396986 -417.256214)
				)
			)
		)
	)
	(zone
		(layers "In2.Cu" "In5.Cu")
		(hatch none 0.5)
		(connect_pads
			(clearance 0)
		)
		(min_thickness 0.25)
		(keepout
			(tracks not_allowed)
			(vias allowed)
			(pads allowed)
			(copperpour not_allowed)
			(footprints allowed)
		)
		(placement
			(enabled no)
			(sheetname "")
		)
		(fill yes
			(thermal_gap 0.5)
			(thermal_bridge_width 0.5)
			(island_removal_mode 0)
		)
		(polygon
			(pts
				(arc
					(start 7.315454 -111.576612)
					(mid 6.710553 -111.008664)
					(end 6.142482 -111.613442)
				)
				(arc
					(start 6.16966 -112.476788)
					(mid 6.764148 -113.04497)
					(end 7.342886 -112.460786)
				)
				(arc
					(start 7.048246 -112.460786)
					(mid 6.756146 -112.750357)
					(end 6.464046 -112.460786)
				)
				(arc
					(start 6.464046 -112.458246)
					(mid 6.756146 -112.166146)
					(end 7.048246 -112.458246)
				)
				(xy 7.342886 -112.458246) (xy 7.342632 -112.439704) (xy 7.316216 -111.59744)
				(arc
					(start 7.021068 -111.59744)
					(mid 6.728968 -111.887011)
					(end 6.436868 -111.59744)
				)
				(arc
					(start 6.436868 -111.5949)
					(mid 6.728968 -111.3028)
					(end 7.021068 -111.5949)
				)
				(xy 7.315962 -111.5949)
			)
		)
	)
	(zone
		(layers "In2.Cu" "In5.Cu")
		(hatch none 0.5)
		(connect_pads
			(clearance 0)
		)
		(min_thickness 0.25)
		(keepout
			(tracks not_allowed)
			(vias allowed)
			(pads allowed)
			(copperpour not_allowed)
			(footprints allowed)
		)
		(placement
			(enabled no)
			(sheetname "")
		)
		(fill yes
			(thermal_gap 0.5)
			(thermal_bridge_width 0.5)
			(island_removal_mode 0)
		)
		(polygon
			(pts
				(arc
					(start 7.291578 -107.502198)
					(mid 6.683756 -106.937556)
					(end 6.119114 -107.545378)
				)
				(xy 6.116574 -107.545378) (xy 6.148324 -108.408216) (xy 6.148578 -108.40847)
				(arc
					(start 6.150864 -108.40847)
					(mid 6.746623 -108.973432)
					(end 7.323836 -108.38942)
				)
				(arc
					(start 7.029196 -108.38942)
					(mid 6.737096 -108.678991)
					(end 6.444996 -108.38942)
				)
				(arc
					(start 6.444996 -108.38688)
					(mid 6.737096 -108.09478)
					(end 7.029196 -108.38688)
				)
				(xy 7.323836 -108.38688) (xy 7.323328 -108.36529) (xy 7.325868 -108.36529) (xy 7.29488 -107.526328)
				(arc
					(start 6.997446 -107.526328)
					(mid 6.705346 -107.815899)
					(end 6.413246 -107.526328)
				)
				(arc
					(start 6.413246 -107.523788)
					(mid 6.705346 -107.231688)
					(end 6.997446 -107.523788)
				)
				(xy 7.29488 -107.523788) (xy 7.294118 -107.502198)
			)
		)
	)
	(zone
		(layers "In2.Cu" "In5.Cu")
		(hatch none 0.5)
		(connect_pads
			(clearance 0)
		)
		(min_thickness 0.25)
		(keepout
			(tracks not_allowed)
			(vias allowed)
			(pads allowed)
			(copperpour not_allowed)
			(footprints allowed)
		)
		(placement
			(enabled no)
			(sheetname "")
		)
		(fill yes
			(thermal_gap 0.5)
			(thermal_bridge_width 0.5)
			(island_removal_mode 0)
		)
		(polygon
			(pts
				(arc
					(start 223.657922 -266.97813)
					(mid 223.094439 -266.391851)
					(end 222.48622 -266.931648)
				)
				(arc
					(start 222.417894 -267.792708)
					(mid 222.956374 -268.424152)
					(end 223.587818 -267.885672)
				)
				(xy 223.591374 -267.84173)
				(arc
					(start 223.294956 -267.84173)
					(mid 223.002856 -268.131301)
					(end 222.710756 -267.84173)
				)
				(arc
					(start 222.710756 -267.83919)
					(mid 223.002856 -267.54709)
					(end 223.294956 -267.83919)
				)
				(xy 223.591628 -267.83919) (xy 223.656144 -267.024866) (xy 223.657922 -266.98067)
				(arc
					(start 223.363282 -266.98067)
					(mid 223.071182 -267.270241)
					(end 222.779082 -266.98067)
				)
				(arc
					(start 222.779082 -266.97813)
					(mid 223.071182 -266.68603)
					(end 223.363282 -266.97813)
				)
			)
		)
	)
	(zone
		(layers "In2.Cu" "In5.Cu")
		(hatch none 0.5)
		(connect_pads
			(clearance 0)
		)
		(min_thickness 0.25)
		(keepout
			(tracks not_allowed)
			(vias allowed)
			(pads allowed)
			(copperpour not_allowed)
			(footprints allowed)
		)
		(placement
			(enabled no)
			(sheetname "")
		)
		(fill yes
			(thermal_gap 0.5)
			(thermal_bridge_width 0.5)
			(island_removal_mode 0)
		)
		(polygon
			(pts
				(arc
					(start 223.750124 -163.975542)
					(mid 223.163384 -163.388802)
					(end 222.576644 -163.975542)
				)
				(arc
					(start 222.576644 -164.934392)
					(mid 223.162114 -165.521131)
					(end 223.750124 -164.936932)
				)
				(arc
					(start 223.455484 -164.936932)
					(mid 223.163384 -165.226503)
					(end 222.871284 -164.936932)
				)
				(arc
					(start 222.871284 -164.934392)
					(mid 223.163384 -164.642292)
					(end 223.455484 -164.934392)
				)
				(xy 223.750124 -164.934392) (xy 223.750124 -163.978082)
				(arc
					(start 223.455484 -163.978082)
					(mid 223.163384 -164.267653)
					(end 222.871284 -163.978082)
				)
				(arc
					(start 222.871284 -163.975542)
					(mid 223.163384 -163.683442)
					(end 223.455484 -163.975542)
				)
			)
		)
	)
	(zone
		(layers "In2.Cu" "In5.Cu")
		(hatch none 0.5)
		(connect_pads
			(clearance 0)
		)
		(min_thickness 0.25)
		(keepout
			(tracks not_allowed)
			(vias allowed)
			(pads allowed)
			(copperpour not_allowed)
			(footprints allowed)
		)
		(placement
			(enabled no)
			(sheetname "")
		)
		(fill yes
			(thermal_gap 0.5)
			(thermal_bridge_width 0.5)
			(island_removal_mode 0)
		)
		(polygon
			(pts
				(arc
					(start 7.74319 -370.89334)
					(mid 7.13004 -371.452521)
					(end 7.689088 -372.065804)
				)
				(arc
					(start 8.587486 -372.107206)
					(mid 9.033584 -371.931689)
					(end 9.19988 -371.482112)
				)
				(arc
					(start 8.90397 -371.482112)
					(mid 8.61441 -371.81313)
					(end 8.32485 -371.482112)
				)
				(arc
					(start 8.008112 -371.482112)
					(mid 7.716012 -371.771683)
					(end 7.423912 -371.482112)
				)
				(arc
					(start 7.423912 -371.479572)
					(mid 7.716012 -371.187472)
					(end 8.008112 -371.479572)
				)
				(arc
					(start 8.325358 -371.479572)
					(mid 8.61441 -371.228972)
					(end 8.903462 -371.479572)
				)
				(arc
					(start 9.199626 -371.479572)
					(mid 9.024093 -371.101031)
					(end 8.641334 -370.934742)
				)
			)
		)
	)
	(zone
		(layers "In2.Cu" "In5.Cu")
		(hatch none 0.5)
		(connect_pads
			(clearance 0)
		)
		(min_thickness 0.25)
		(keepout
			(tracks not_allowed)
			(vias allowed)
			(pads allowed)
			(copperpour not_allowed)
			(footprints allowed)
		)
		(placement
			(enabled no)
			(sheetname "")
		)
		(fill yes
			(thermal_gap 0.5)
			(thermal_bridge_width 0.5)
			(island_removal_mode 0)
		)
		(polygon
			(pts
				(xy 7.423912 -423.515536)
				(arc
					(start 7.423658 -423.518076)
					(mid 6.856476 -424.020742)
					(end 7.359142 -424.587924)
				)
				(xy 7.358888 -424.590464) (xy 8.22071 -424.642788) (xy 8.220964 -424.642534)
				(arc
					(start 8.221218 -424.640248)
					(mid 8.638573 -424.477996)
					(end 8.78713 -424.05554)
				)
				(arc
					(start 8.541258 -424.05554)
					(mid 8.253476 -424.39738)
					(end 7.965694 -424.05554)
				)
				(arc
					(start 7.6835 -424.05554)
					(mid 7.3914 -424.345111)
					(end 7.0993 -424.05554)
				)
				(arc
					(start 7.0993 -424.053)
					(mid 7.3914 -423.7609)
					(end 7.6835 -424.053)
				)
				(arc
					(start 7.966202 -424.053)
					(mid 8.253476 -423.813324)
					(end 8.54075 -424.053)
				)
				(arc
					(start 8.786876 -424.053)
					(mid 8.625275 -423.719294)
					(end 8.285734 -423.5704)
				)
				(xy 8.285988 -423.56786)
			)
		)
	)
	(zone
		(layers "In2.Cu" "In5.Cu")
		(hatch none 0.5)
		(connect_pads
			(clearance 0)
		)
		(min_thickness 0.25)
		(keepout
			(tracks not_allowed)
			(vias allowed)
			(pads allowed)
			(copperpour not_allowed)
			(footprints allowed)
		)
		(placement
			(enabled no)
			(sheetname "")
		)
		(fill yes
			(thermal_gap 0.5)
			(thermal_bridge_width 0.5)
			(island_removal_mode 0)
		)
		(polygon
			(pts
				(arc
					(start 7.568946 -157.531562)
					(mid 6.984746 -156.947362)
					(end 6.400546 -157.531562)
				)
				(arc
					(start 6.400546 -158.459678)
					(mid 6.983476 -159.043877)
					(end 7.568946 -158.462218)
				)
				(arc
					(start 7.276846 -158.462218)
					(mid 6.984746 -158.751789)
					(end 6.692646 -158.462218)
				)
				(arc
					(start 6.692646 -158.459678)
					(mid 6.984746 -158.167578)
					(end 7.276846 -158.459678)
				)
				(xy 7.568946 -158.459678) (xy 7.568946 -157.534102)
				(arc
					(start 7.276846 -157.534102)
					(mid 6.984746 -157.823673)
					(end 6.692646 -157.534102)
				)
				(arc
					(start 6.692646 -157.531562)
					(mid 6.984746 -157.239462)
					(end 7.276846 -157.531562)
				)
			)
		)
	)
	(zone
		(layers "In2.Cu" "In5.Cu")
		(hatch none 0.5)
		(connect_pads
			(clearance 0)
		)
		(min_thickness 0.25)
		(keepout
			(tracks not_allowed)
			(vias allowed)
			(pads allowed)
			(copperpour not_allowed)
			(footprints allowed)
		)
		(placement
			(enabled no)
			(sheetname "")
		)
		(fill yes
			(thermal_gap 0.5)
			(thermal_bridge_width 0.5)
			(island_removal_mode 0)
		)
		(polygon
			(pts
				(xy 8.228584 -357.926386) (xy 7.351776 -357.947214)
				(arc
					(start 7.351776 -357.949754)
					(mid 6.7818 -358.54767)
					(end 7.379716 -359.117646)
				)
				(xy 7.379716 -359.120186) (xy 8.25627 -359.099358) (xy 8.256524 -359.099104)
				(arc
					(start 8.256524 -359.096818)
					(mid 8.659606 -358.921841)
					(end 8.826754 -358.515412)
				)
				(arc
					(start 8.534654 -358.515412)
					(mid 8.252982 -358.804545)
					(end 7.95147 -358.53624)
				)
				(arc
					(start 7.657846 -358.53624)
					(mid 7.365746 -358.825811)
					(end 7.073646 -358.53624)
				)
				(arc
					(start 7.073646 -358.5337)
					(mid 7.365746 -358.2416)
					(end 7.657846 -358.5337)
				)
				(xy 7.951216 -358.5337) (xy 7.950454 -358.515412)
				(arc
					(start 7.950454 -358.512872)
					(mid 8.242554 -358.220772)
					(end 8.534654 -358.512872)
				)
				(arc
					(start 8.826754 -358.512872)
					(mid 8.650676 -358.09487)
					(end 8.228584 -357.928926)
				)
			)
		)
	)
	(zone
		(layers "In2.Cu" "In5.Cu")
		(hatch none 0.5)
		(connect_pads
			(clearance 0)
		)
		(min_thickness 0.25)
		(keepout
			(tracks not_allowed)
			(vias allowed)
			(pads allowed)
			(copperpour not_allowed)
			(footprints allowed)
		)
		(placement
			(enabled no)
			(sheetname "")
		)
		(fill yes
			(thermal_gap 0.5)
			(thermal_bridge_width 0.5)
			(island_removal_mode 0)
		)
		(polygon
			(pts
				(arc
					(start 35.638486 -472.820238)
					(mid 35.051746 -472.233498)
					(end 34.465006 -472.820238)
				)
				(arc
					(start 34.465006 -473.748354)
					(mid 35.050476 -474.335093)
					(end 35.638486 -473.750894)
				)
				(arc
					(start 35.343846 -473.750894)
					(mid 35.051746 -474.040465)
					(end 34.759646 -473.750894)
				)
				(arc
					(start 34.759646 -473.748354)
					(mid 35.051746 -473.456254)
					(end 35.343846 -473.748354)
				)
				(xy 35.638486 -473.748354) (xy 35.638486 -472.822778)
				(arc
					(start 35.343846 -472.822778)
					(mid 35.051746 -473.112349)
					(end 34.759646 -472.822778)
				)
				(arc
					(start 34.759646 -472.820238)
					(mid 35.051746 -472.528138)
					(end 35.343846 -472.820238)
				)
			)
		)
	)
	(zone
		(layers "In2.Cu" "In5.Cu")
		(hatch none 0.5)
		(connect_pads
			(clearance 0)
		)
		(min_thickness 0.25)
		(keepout
			(tracks not_allowed)
			(vias allowed)
			(pads allowed)
			(copperpour not_allowed)
			(footprints allowed)
		)
		(placement
			(enabled no)
			(sheetname "")
		)
		(fill yes
			(thermal_gap 0.5)
			(thermal_bridge_width 0.5)
			(island_removal_mode 0)
		)
		(polygon
			(pts
				(arc
					(start 7.332472 -161.5313)
					(mid 6.748272 -160.9471)
					(end 6.164072 -161.5313)
				)
				(arc
					(start 6.164072 -162.459416)
					(mid 6.747002 -163.043615)
					(end 7.332472 -162.461956)
				)
				(arc
					(start 7.040372 -162.461956)
					(mid 6.748272 -162.751527)
					(end 6.456172 -162.461956)
				)
				(arc
					(start 6.456172 -162.459416)
					(mid 6.748272 -162.167316)
					(end 7.040372 -162.459416)
				)
				(xy 7.332472 -162.459416) (xy 7.332472 -161.53384)
				(arc
					(start 7.040372 -161.53384)
					(mid 6.748272 -161.823411)
					(end 6.456172 -161.53384)
				)
				(arc
					(start 6.456172 -161.5313)
					(mid 6.748272 -161.2392)
					(end 7.040372 -161.5313)
				)
			)
		)
	)
	(zone
		(layers "In2.Cu" "In5.Cu")
		(hatch none 0.5)
		(connect_pads
			(clearance 0)
		)
		(min_thickness 0.25)
		(keepout
			(tracks not_allowed)
			(vias allowed)
			(pads allowed)
			(copperpour not_allowed)
			(footprints allowed)
		)
		(placement
			(enabled no)
			(sheetname "")
		)
		(fill yes
			(thermal_gap 0.5)
			(thermal_bridge_width 0.5)
			(island_removal_mode 0)
		)
		(polygon
			(pts
				(arc
					(start 8.689086 -385.532884)
					(mid 8.127746 -384.971544)
					(end 7.566406 -385.532884)
				)
				(arc
					(start 7.566406 -386.461)
					(mid 8.126476 -387.022339)
					(end 8.689086 -386.46354)
				)
				(arc
					(start 8.419846 -386.46354)
					(mid 8.127746 -386.753111)
					(end 7.835646 -386.46354)
				)
				(arc
					(start 7.835646 -386.461)
					(mid 8.127746 -386.1689)
					(end 8.419846 -386.461)
				)
				(xy 8.689086 -386.461) (xy 8.689086 -385.535424)
				(arc
					(start 8.419846 -385.535424)
					(mid 8.127746 -385.824995)
					(end 7.835646 -385.535424)
				)
				(arc
					(start 7.835646 -385.532884)
					(mid 8.127746 -385.240784)
					(end 8.419846 -385.532884)
				)
			)
		)
	)
	(zone
		(layers "In2.Cu" "In5.Cu")
		(hatch none 0.5)
		(connect_pads
			(clearance 0)
		)
		(min_thickness 0.25)
		(keepout
			(tracks not_allowed)
			(vias allowed)
			(pads allowed)
			(copperpour not_allowed)
			(footprints allowed)
		)
		(placement
			(enabled no)
			(sheetname "")
		)
		(fill yes
			(thermal_gap 0.5)
			(thermal_bridge_width 0.5)
			(island_removal_mode 0)
		)
		(polygon
			(pts
				(arc
					(start 9.021064 -363.817408)
					(mid 8.686561 -363.287653)
					(end 8.0645 -363.361986)
				)
				(xy 8.062976 -363.359954) (xy 7.375398 -363.918246)
				(arc
					(start 7.376922 -363.920278)
					(mid 7.291324 -364.745524)
					(end 8.11657 -364.831122)
				)
				(xy 8.118094 -364.833154) (xy 8.678672 -364.37824)
				(arc
					(start 8.038846 -364.37824)
					(mid 7.746746 -364.667811)
					(end 7.454646 -364.37824)
				)
				(arc
					(start 7.454646 -364.3757)
					(mid 7.746746 -364.0836)
					(end 8.038846 -364.3757)
				)
				(xy 8.68172 -364.3757) (xy 8.805672 -364.275116) (xy 8.805672 -364.274608)
				(arc
					(start 8.804148 -364.27283)
					(mid 8.963467 -364.070759)
					(end 9.021064 -363.819948)
				)
				(arc
					(start 8.726424 -363.819948)
					(mid 8.434324 -364.109519)
					(end 8.142224 -363.819948)
				)
				(arc
					(start 8.142224 -363.817408)
					(mid 8.434324 -363.525308)
					(end 8.726424 -363.817408)
				)
			)
		)
	)
	(zone
		(layers "In2.Cu" "In5.Cu")
		(hatch none 0.5)
		(connect_pads
			(clearance 0)
		)
		(min_thickness 0.25)
		(keepout
			(tracks not_allowed)
			(vias allowed)
			(pads allowed)
			(copperpour not_allowed)
			(footprints allowed)
		)
		(placement
			(enabled no)
			(sheetname "")
		)
		(fill yes
			(thermal_gap 0.5)
			(thermal_bridge_width 0.5)
			(island_removal_mode 0)
		)
		(polygon
			(pts
				(arc
					(start 31.927546 -475.163896)
					(mid 31.307532 -474.612462)
					(end 30.756098 -475.232476)
				)
				(xy 30.753558 -475.23273) (xy 30.804104 -476.09506)
				(arc
					(start 30.806644 -476.094806)
					(mid 31.408251 -476.647028)
					(end 31.979108 -476.063056)
				)
				(arc
					(start 31.684468 -476.063056)
					(mid 31.392368 -476.352627)
					(end 31.100268 -476.063056)
				)
				(arc
					(start 31.100268 -476.060516)
					(mid 31.392368 -475.768416)
					(end 31.684468 -476.060516)
				)
				(xy 31.979108 -476.060516) (xy 31.978092 -476.026226) (xy 31.980632 -476.025972) (xy 31.932372 -475.200726)
				(arc
					(start 31.633922 -475.200726)
					(mid 31.341822 -475.490297)
					(end 31.049722 -475.200726)
				)
				(arc
					(start 31.049722 -475.198186)
					(mid 31.341822 -474.906086)
					(end 31.633922 -475.198186)
				)
				(xy 31.932118 -475.198186) (xy 31.930086 -475.163896) (xy 31.929832 -475.163642)
			)
		)
	)
	(zone
		(layers "In2.Cu" "In5.Cu")
		(hatch none 0.5)
		(connect_pads
			(clearance 0)
		)
		(min_thickness 0.25)
		(keepout
			(tracks not_allowed)
			(vias allowed)
			(pads allowed)
			(copperpour not_allowed)
			(footprints allowed)
		)
		(placement
			(enabled no)
			(sheetname "")
		)
		(fill yes
			(thermal_gap 0.5)
			(thermal_bridge_width 0.5)
			(island_removal_mode 0)
		)
		(polygon
			(pts
				(arc
					(start 7.675626 -383.436368)
					(mid 7.063238 -383.996311)
					(end 7.623048 -384.608832)
				)
				(arc
					(start 8.485886 -384.647186)
					(mid 8.930392 -384.472464)
					(end 9.097772 -384.02514)
				)
				(arc
					(start 8.801862 -384.02514)
					(mid 8.512048 -384.352972)
					(end 8.222234 -384.02514)
				)
				(arc
					(start 7.94131 -384.02514)
					(mid 7.64921 -384.314711)
					(end 7.35711 -384.02514)
				)
				(arc
					(start 7.35711 -384.0226)
					(mid 7.64921 -383.7305)
					(end 7.94131 -384.0226)
				)
				(arc
					(start 8.222488 -384.0226)
					(mid 8.512048 -383.768865)
					(end 8.801608 -384.0226)
				)
				(arc
					(start 9.097518 -384.0226)
					(mid 8.922584 -383.641781)
					(end 8.53821 -383.474722)
				)
			)
		)
	)
	(zone
		(layers "In2.Cu" "In5.Cu")
		(hatch none 0.5)
		(connect_pads
			(clearance 0)
		)
		(min_thickness 0.25)
		(keepout
			(tracks not_allowed)
			(vias allowed)
			(pads allowed)
			(copperpour not_allowed)
			(footprints allowed)
		)
		(placement
			(enabled no)
			(sheetname "")
		)
		(fill yes
			(thermal_gap 0.5)
			(thermal_bridge_width 0.5)
			(island_removal_mode 0)
		)
		(polygon
			(pts
				(arc
					(start 28.373832 -441.830968)
					(mid 27.772614 -441.259214)
					(end 27.20086 -441.860432)
				)
				(xy 27.19832 -441.860432) (xy 27.22372 -442.876178) (xy 27.223974 -442.876432)
				(arc
					(start 27.22626 -442.876432)
					(mid 27.818843 -443.448339)
					(end 28.399486 -442.86424)
				)
				(arc
					(start 28.104846 -442.86424)
					(mid 27.812746 -443.153811)
					(end 27.520646 -442.86424)
				)
				(arc
					(start 27.520646 -442.8617)
					(mid 27.812746 -442.5696)
					(end 28.104846 -442.8617)
				)
				(xy 28.399486 -442.8617) (xy 28.399232 -442.846968) (xy 28.401772 -442.846968) (xy 28.37688 -441.84824)
				(arc
					(start 28.079446 -441.84824)
					(mid 27.787346 -442.137811)
					(end 27.495246 -441.84824)
				)
				(arc
					(start 27.495246 -441.8457)
					(mid 27.787346 -441.5536)
					(end 28.079446 -441.8457)
				)
				(xy 28.376626 -441.8457) (xy 28.376372 -441.830968)
			)
		)
	)
	(zone
		(layers "In2.Cu" "In5.Cu")
		(hatch none 0.5)
		(connect_pads
			(clearance 0)
		)
		(min_thickness 0.25)
		(keepout
			(tracks not_allowed)
			(vias allowed)
			(pads allowed)
			(copperpour not_allowed)
			(footprints allowed)
		)
		(placement
			(enabled no)
			(sheetname "")
		)
		(fill yes
			(thermal_gap 0.5)
			(thermal_bridge_width 0.5)
			(island_removal_mode 0)
		)
		(polygon
			(pts
				(arc
					(start 216.698322 -269.606014)
					(mid 216.523496 -269.188173)
					(end 216.1032 -269.019274)
				)
				(arc
					(start 215.1888 -269.032228)
					(mid 214.610442 -269.62735)
					(end 215.205564 -270.205708)
				)
				(arc
					(start 216.11971 -270.192754)
					(mid 216.528481 -270.018961)
					(end 216.698322 -269.608554)
				)
				(arc
					(start 216.403682 -269.608554)
					(mid 216.118065 -269.898053)
					(end 215.81999 -269.621508)
				)
				(arc
					(start 215.489282 -269.621508)
					(mid 215.197182 -269.911079)
					(end 214.905082 -269.621508)
				)
				(arc
					(start 214.905082 -269.618968)
					(mid 215.197182 -269.326868)
					(end 215.489282 -269.618968)
				)
				(xy 215.819736 -269.618968) (xy 215.819482 -269.608554)
				(arc
					(start 215.819482 -269.606014)
					(mid 216.111582 -269.313914)
					(end 216.403682 -269.606014)
				)
			)
		)
	)
	(zone
		(layers "In2.Cu" "In5.Cu")
		(hatch none 0.5)
		(connect_pads
			(clearance 0)
		)
		(min_thickness 0.25)
		(keepout
			(tracks not_allowed)
			(vias allowed)
			(pads allowed)
			(copperpour not_allowed)
			(footprints allowed)
		)
		(placement
			(enabled no)
			(sheetname "")
		)
		(fill yes
			(thermal_gap 0.5)
			(thermal_bridge_width 0.5)
			(island_removal_mode 0)
		)
		(polygon
			(pts
				(arc
					(start 25.282906 -348.827598)
					(mid 24.711917 -348.241069)
					(end 24.110188 -348.796102)
				)
				(arc
					(start 24.052022 -349.878904)
					(mid 24.606504 -350.496378)
					(end 25.223978 -349.941896)
				)
				(xy 25.225502 -349.91294)
				(arc
					(start 24.9301 -349.91294)
					(mid 24.638 -350.202511)
					(end 24.3459 -349.91294)
				)
				(arc
					(start 24.3459 -349.9104)
					(mid 24.638 -349.6183)
					(end 24.9301 -349.9104)
				)
				(xy 25.225756 -349.9104) (xy 25.282144 -348.859348) (xy 25.282906 -348.830138)
				(arc
					(start 24.988266 -348.830138)
					(mid 24.696166 -349.119709)
					(end 24.404066 -348.830138)
				)
				(arc
					(start 24.404066 -348.827598)
					(mid 24.696166 -348.535498)
					(end 24.988266 -348.827598)
				)
			)
		)
	)
	(zone
		(layers "In2.Cu" "In5.Cu")
		(hatch none 0.5)
		(connect_pads
			(clearance 0)
		)
		(min_thickness 0.25)
		(keepout
			(tracks not_allowed)
			(vias allowed)
			(pads allowed)
			(copperpour not_allowed)
			(footprints allowed)
		)
		(placement
			(enabled no)
			(sheetname "")
		)
		(fill yes
			(thermal_gap 0.5)
			(thermal_bridge_width 0.5)
			(island_removal_mode 0)
		)
		(polygon
			(pts
				(arc
					(start 7.619238 -169.531538)
					(mid 7.032498 -168.944798)
					(end 6.445758 -169.531538)
				)
				(arc
					(start 6.445758 -170.459654)
					(mid 7.031228 -171.046393)
					(end 7.619238 -170.462194)
				)
				(arc
					(start 7.324598 -170.462194)
					(mid 7.032498 -170.751765)
					(end 6.740398 -170.462194)
				)
				(arc
					(start 6.740398 -170.459654)
					(mid 7.032498 -170.167554)
					(end 7.324598 -170.459654)
				)
				(xy 7.619238 -170.459654) (xy 7.619238 -169.534078)
				(arc
					(start 7.324598 -169.534078)
					(mid 7.032498 -169.823649)
					(end 6.740398 -169.534078)
				)
				(arc
					(start 6.740398 -169.531538)
					(mid 7.032498 -169.239438)
					(end 7.324598 -169.531538)
				)
			)
		)
	)
	(zone
		(net "P5VC")
		(layer "In3.Cu")
		(hatch none 0.5)
		(connect_pads
			(clearance 0.5)
		)
		(min_thickness 0.25)
		(fill yes
			(thermal_gap 0.5)
			(thermal_bridge_width 0.5)
			(island_removal_mode 0)
		)
		(polygon
			(pts
				(xy 37.03574 -43.3832) (xy 30.289246 -50.129694) (xy 30.289246 -98.866706) (xy 39.433246 -108.010706)
				(xy 39.433246 -152.968706) (xy 41.211246 -154.746706) (xy 41.211246 -164.175694) (xy 31.305246 -174.081694)
				(xy 31.305246 -197.037706) (xy 39.687246 -205.419706) (xy 39.687246 -212.816694) (xy 38.671246 -213.832694)
				(xy 38.671246 -234.375706) (xy 39.687246 -235.391706) (xy 39.687246 -273.014694) (xy 27.749246 -284.952694)
				(xy 27.749246 -311.972706) (xy 39.560246 -323.783706) (xy 39.560246 -361.914694) (xy 25.717246 -375.757694)
				(xy 25.717246 -403.031706) (xy 39.560246 -416.874706) (xy 39.560246 -453.227694) (xy 29.16174 -463.6262)
				(xy 21.41474 -463.6262) (xy 19.113246 -465.927694) (xy 19.113246 -493.074706) (xy 21.03374 -494.9952)
				(xy 48.815752 -494.9952) (xy 67.738752 -476.0722) (xy 82.089752 -476.0722) (xy 84.264246 -473.897706)
				(xy 84.264246 -404.967694) (xy 82.089752 -402.7932) (xy 70.405752 -402.7932) (xy 65.214246 -397.601694)
				(xy 65.214246 -381.695706) (xy 67.738752 -379.1712) (xy 81.454752 -379.1712) (xy 83.629246 -376.996706)
				(xy 83.629246 -308.066694) (xy 79.930752 -304.3682) (xy 68.373752 -304.3682) (xy 65.087246 -301.081694)
				(xy 65.087246 -288.731706) (xy 66.722752 -287.0962) (xy 80.946752 -287.0962) (xy 84.645246 -283.397706)
				(xy 84.645246 -200.624694) (xy 82.343752 -198.3232) (xy 72.183752 -198.3232) (xy 67.119246 -193.258694)
				(xy 67.119246 -178.241706) (xy 68.500752 -176.8602) (xy 79.930752 -176.8602) (xy 84.645246 -172.145706)
				(xy 84.645246 -97.881694) (xy 79.930752 -93.1672) (xy 73.707752 -93.1672) (xy 70.151752 -89.6112)
				(xy 66.341752 -89.6112) (xy 64.960246 -88.229694) (xy 64.960246 -74.355706) (xy 67.230752 -72.0852)
				(xy 77.136752 -72.0852) (xy 80.835246 -68.386706) (xy 80.835246 -50.002694) (xy 74.215752 -43.3832)
			)
		)
		(polygon
			(pts
				(arc
					(start 31.927546 -475.163896)
					(mid 31.307532 -474.612462)
					(end 30.756098 -475.232476)
				)
				(xy 30.753558 -475.23273) (xy 30.804104 -476.09506)
				(arc
					(start 30.806644 -476.094806)
					(mid 31.426658 -476.64624)
					(end 31.978092 -476.026226)
				)
				(xy 31.980632 -476.025972) (xy 31.930086 -475.163896) (xy 31.929832 -475.163642)
			)
		)
		(polygon
			(pts
				(arc
					(start 35.638486 -472.819984)
					(mid 35.051619 -472.233498)
					(end 34.465006 -472.820238)
				)
				(arc
					(start 34.465006 -473.748354)
					(mid 35.051746 -474.335094)
					(end 35.638486 -473.748354)
				)
			)
		)
		(polygon
			(pts
				(arc
					(start 31.979616 -372.061486)
					(mid 31.386018 -371.590316)
					(end 30.914848 -372.183914)
				)
				(xy 30.912308 -372.184168) (xy 31.034736 -373.248428) (xy 31.03499 -373.248682)
				(arc
					(start 31.037276 -373.248428)
					(mid 31.630874 -373.719598)
					(end 32.102044 -373.126)
				)
				(xy 32.104584 -373.125746) (xy 31.982156 -372.061232)
			)
		)
		(polygon
			(pts
				(arc
					(start 36.908232 -369.934744)
					(mid 36.337748 -369.332256)
					(end 35.73526 -369.90274)
				)
				(xy 35.73272 -369.90274) (xy 35.707574 -370.823998)
				(arc
					(start 35.710114 -370.823998)
					(mid 36.280598 -371.426486)
					(end 36.883086 -370.856002)
				)
				(xy 36.885626 -370.856002) (xy 36.910772 -369.934998) (xy 36.910518 -369.934744)
			)
		)
		(polygon
			(pts
				(arc
					(start 31.773876 -63.350394)
					(mid 31.25724 -62.70117)
					(end 30.608016 -63.217806)
				)
				(xy 30.605476 -63.217552) (xy 30.503368 -64.11595) (xy 30.503622 -64.116204)
				(arc
					(start 30.505908 -64.116458)
					(mid 31.022544 -64.765682)
					(end 31.671768 -64.249046)
				)
				(xy 31.674308 -64.2493) (xy 31.776416 -63.350648)
			)
		)
		(polygon
			(pts
				(arc
					(start 38.686486 -60.890912)
					(mid 38.099619 -60.304426)
					(end 37.513006 -60.891166)
				)
				(arc
					(start 37.513006 -61.850016)
					(mid 38.099746 -62.436756)
					(end 38.686486 -61.850016)
				)
			)
		)
	)
	(zone
		(net "P5VB")
		(layer "In3.Cu")
		(hatch none 0.5)
		(connect_pads
			(clearance 0.5)
		)
		(min_thickness 0.25)
		(fill yes
			(thermal_gap 0.5)
			(thermal_bridge_width 0.5)
			(island_removal_mode 0)
		)
		(polygon
			(pts
				(xy 35.63874 -9.4742) (xy 31.940246 -13.172694) (xy 31.940246 -37.906706) (xy 37.03574 -43.0022)
				(xy 74.37374 -43.0022) (xy 81.216246 -49.844706) (xy 81.216246 -68.544694) (xy 77.29474 -72.4662)
				(xy 67.38874 -72.4662) (xy 65.341246 -74.513694) (xy 65.341246 -88.071706) (xy 66.49974 -89.2302)
				(xy 70.30974 -89.2302) (xy 73.86574 -92.7862) (xy 80.08874 -92.7862) (xy 85.026246 -97.723706) (xy 85.026246 -172.303694)
				(xy 80.08874 -177.2412) (xy 68.65874 -177.2412) (xy 67.500246 -178.399694) (xy 67.500246 -193.100706)
				(xy 72.34174 -197.9422) (xy 82.50174 -197.9422) (xy 85.026246 -200.466706) (xy 85.026246 -283.555694)
				(xy 81.10474 -287.4772) (xy 66.88074 -287.4772) (xy 65.468246 -288.889694) (xy 65.468246 -300.923706)
				(xy 68.53174 -303.9872) (xy 80.08874 -303.9872) (xy 84.010246 -307.908706) (xy 84.010246 -377.154694)
				(xy 81.61274 -379.5522) (xy 67.89674 -379.5522) (xy 65.595246 -381.853694) (xy 65.595246 -397.443706)
				(xy 70.56374 -402.4122) (xy 82.24774 -402.4122) (xy 84.645246 -404.809706) (xy 84.645246 -474.055694)
				(xy 82.24774 -476.4532) (xy 67.89674 -476.4532) (xy 60.642246 -483.707694) (xy 60.642246 -492.058706)
				(xy 61.92774 -493.3442) (xy 70.405752 -493.3442) (xy 73.580752 -490.1692) (xy 132.254752 -490.1692)
				(xy 139.636246 -482.787706) (xy 139.636246 -24.729694) (xy 137.080752 -22.1742) (xy 98.472752 -22.1742)
				(xy 85.772752 -9.4742)
			)
		)
	)
	(zone
		(net "P3V3")
		(layer "In3.Cu")
		(hatch none 0.5)
		(connect_pads
			(clearance 0.5)
		)
		(min_thickness 0.25)
		(fill yes
			(thermal_gap 0.5)
			(thermal_bridge_width 0.5)
			(island_removal_mode 0)
		)
		(polygon
			(pts
				(arc
					(start 0.999998 -0.763016)
					(mid 0.832426 -0.832426)
					(end 0.763016 -0.999998)
				)
				(xy 0.763016 -53.433726) (xy 0.816356 -53.487066)
				(arc
					(start 5.050028 -53.487066)
					(mid 6.763004 -55.200042)
					(end 5.050028 -56.913018)
				)
				(xy 0.816102 -56.913018) (xy 0.763016 -56.966104) (xy 0.763016 -104.233726) (xy 0.816356 -104.287066)
				(arc
					(start 5.050028 -104.287066)
					(mid 6.574439 -105.218724)
					(end 6.440678 -107.000294)
				)
				(arc
					(start 6.440678 -107.000294)
					(mid 7.003377 -107.018543)
					(end 7.291578 -107.502198)
				)
				(xy 7.294118 -107.502198) (xy 7.325868 -108.36529)
				(arc
					(start 7.323328 -108.36529)
					(mid 6.758686 -108.973112)
					(end 6.150864 -108.40847)
				)
				(xy 6.148578 -108.40847) (xy 6.148324 -108.408216) (xy 6.116574 -107.545378)
				(arc
					(start 6.119114 -107.545378)
					(mid 6.127653 -107.422093)
					(end 6.161786 -107.303316)
				)
				(arc
					(start 6.161786 -107.303316)
					(mid 5.642464 -107.607384)
					(end 5.050028 -107.713018)
				)
				(xy 0.816102 -107.713018) (xy 0.763016 -107.766104) (xy 0.763016 -208.233772) (xy 0.816102 -208.286858)
				(arc
					(start 5.050028 -208.286858)
					(mid 6.763258 -210.000088)
					(end 5.050028 -211.713064)
				)
				(xy 0.816102 -211.713064) (xy 0.763016 -211.76615) (xy 0.763016 -303.433734) (xy 0.816356 -303.487074)
				(arc
					(start 5.050028 -303.487074)
					(mid 6.763004 -305.20005)
					(end 5.050028 -306.913026)
				)
				(xy 0.816102 -306.913026) (xy 0.763016 -306.966112) (xy 0.763016 -354.233734) (xy 0.816356 -354.287074)
				(arc
					(start 5.050028 -354.287074)
					(mid 6.763004 -356.00005)
					(end 5.050028 -357.713026)
				)
				(xy 0.816102 -357.713026) (xy 0.763016 -357.766112) (xy 0.763016 -458.23378) (xy 0.816102 -458.286866)
				(arc
					(start 5.050028 -458.286866)
					(mid 6.763258 -460.000096)
					(end 5.050028 -461.713072)
				)
				(xy 0.816102 -461.713072) (xy 0.763016 -461.766158)
				(arc
					(start 0.763016 -505.000006)
					(mid 0.832426 -505.167578)
					(end 0.999998 -505.236988)
				)
				(arc
					(start 261.500112 -505.236988)
					(mid 261.667684 -505.167578)
					(end 261.737094 -505.000006)
				)
				(xy 261.737094 -428.396146) (xy 261.183882 -427.842934)
				(arc
					(start 260.149594 -427.842934)
					(mid 258.726388 -427.253265)
					(end 258.136898 -425.829984)
				)
				(xy 258.136898 -411.80131) (xy 257.583686 -411.248098)
				(arc
					(start 251.394976 -411.248098)
					(mid 250.097036 -409.950158)
					(end 251.394976 -408.651964)
				)
				(xy 257.583686 -408.651964) (xy 258.136898 -408.098752)
				(arc
					(start 258.136898 -364.16996)
					(mid 258.726388 -362.746679)
					(end 260.149594 -362.15701)
				)
				(xy 261.183882 -362.15701) (xy 261.737094 -361.603798)
				(arc
					(start 261.737094 -0.999998)
					(mid 261.667684 -0.832426)
					(end 261.500112 -0.763016)
				)
			)
		)
		(polygon
			(pts
				(arc
					(start 22.225508 -444.181992)
					(mid 21.613876 -443.62116)
					(end 21.053044 -444.232792)
				)
				(arc
					(start 21.090382 -445.095376)
					(mid 21.701887 -445.656457)
					(end 22.262846 -445.04483)
				)
			)
		)
		(polygon
			(pts
				(arc
					(start 28.373832 -441.830968)
					(mid 27.772614 -441.259214)
					(end 27.20086 -441.860432)
				)
				(xy 27.19832 -441.860432) (xy 27.22372 -442.876178) (xy 27.223974 -442.876432)
				(arc
					(start 27.22626 -442.876432)
					(mid 27.827478 -443.448186)
					(end 28.399232 -442.846968)
				)
				(xy 28.401772 -442.846968) (xy 28.376372 -441.830968)
			)
		)
		(polygon
			(pts
				(arc
					(start 11.938 -441.81014)
					(mid 12.52474 -441.2234)
					(end 11.938 -440.63666)
				)
				(arc
					(start 11.0744 -440.63666)
					(mid 10.48766 -441.2234)
					(end 11.0744 -441.81014)
				)
			)
		)
		(polygon
			(pts
				(arc
					(start 12.239498 -438.105042)
					(mid 11.652758 -437.518302)
					(end 11.066018 -438.105042)
				)
				(arc
					(start 11.066018 -439.033412)
					(mid 11.652885 -439.619898)
					(end 12.239498 -439.033158)
				)
			)
		)
		(polygon
			(pts
				(xy 7.423912 -423.515536)
				(arc
					(start 7.423658 -423.518076)
					(mid 6.856476 -424.020742)
					(end 7.359142 -424.587924)
				)
				(xy 7.358888 -424.590464) (xy 8.22071 -424.642788) (xy 8.220964 -424.642534)
				(arc
					(start 8.221218 -424.640248)
					(mid 8.7884 -424.137582)
					(end 8.285734 -423.5704)
				)
				(xy 8.285988 -423.56786)
			)
		)
		(polygon
			(pts
				(xy 8.142224 -421.362632) (xy 7.278878 -421.34028)
				(arc
					(start 7.278878 -421.34282)
					(mid 6.703314 -421.889428)
					(end 7.249922 -422.464992)
				)
				(xy 7.249922 -422.467532) (xy 8.113014 -422.489884) (xy 8.113268 -422.48963)
				(arc
					(start 8.113268 -422.487344)
					(mid 8.688832 -421.940736)
					(end 8.142224 -421.365172)
				)
			)
		)
		(polygon
			(pts
				(arc
					(start 7.53364 -417.243768)
					(mid 6.93852 -417.821999)
					(end 7.516622 -418.417248)
				)
				(arc
					(start 8.380222 -418.429694)
					(mid 8.975344 -417.851336)
					(end 8.396986 -417.256214)
				)
			)
		)
		(polygon
			(pts
				(arc
					(start 8.581898 -414.041336)
					(mid 8.779764 -413.272478)
					(end 8.010906 -413.074612)
				)
				(arc
					(start 7.215886 -413.544512)
					(mid 7.007016 -414.313851)
					(end 7.778242 -414.516062)
				)
			)
		)
		(polygon
			(pts
				(arc
					(start 8.203946 -410.396436)
					(mid 8.765286 -409.835096)
					(end 8.203946 -409.273756)
				)
				(arc
					(start 7.340346 -409.273756)
					(mid 6.779006 -409.835096)
					(end 7.340346 -410.396436)
				)
			)
		)
		(polygon
			(pts
				(arc
					(start 7.77875 -399.884138)
					(mid 8.335766 -399.273649)
					(end 7.725156 -398.716754)
				)
				(arc
					(start 6.862318 -398.756378)
					(mid 6.30555 -399.366994)
					(end 6.916166 -399.923762)
				)
			)
		)
		(polygon
			(pts
				(arc
					(start 8.689086 -385.53263)
					(mid 8.127619 -384.971544)
					(end 7.566406 -385.532884)
				)
				(arc
					(start 7.566406 -386.461)
					(mid 8.127746 -387.02234)
					(end 8.689086 -386.461)
				)
			)
		)
		(polygon
			(pts
				(arc
					(start 7.675626 -383.436368)
					(mid 7.063238 -383.996311)
					(end 7.623048 -384.608832)
				)
				(arc
					(start 8.485886 -384.647186)
					(mid 9.09828 -384.087116)
					(end 8.53821 -383.474722)
				)
			)
		)
		(polygon
			(pts
				(arc
					(start 8.661146 -380.96444)
					(mid 9.247886 -380.3777)
					(end 8.661146 -379.79096)
				)
				(arc
					(start 7.746746 -379.79096)
					(mid 7.160006 -380.3777)
					(end 7.746746 -380.96444)
				)
			)
		)
		(polygon
			(pts
				(arc
					(start 8.810498 -376.880374)
					(mid 9.287002 -376.291094)
					(end 8.697722 -375.81459)
				)
				(xy 8.697468 -375.81205) (xy 7.817104 -375.905268)
				(arc
					(start 7.817358 -375.907808)
					(mid 7.340854 -376.497088)
					(end 7.930134 -376.973592)
				)
				(xy 7.930388 -376.976132) (xy 8.810498 -376.882914) (xy 8.810752 -376.88266)
			)
		)
		(polygon
			(pts
				(arc
					(start 7.74319 -370.89334)
					(mid 7.13004 -371.452521)
					(end 7.689088 -372.065804)
				)
				(arc
					(start 8.587486 -372.107206)
					(mid 9.200642 -371.547898)
					(end 8.641334 -370.934742)
				)
			)
		)
		(polygon
			(pts
				(arc
					(start 7.312914 -367.331752)
					(mid 6.753606 -367.843308)
					(end 7.265162 -368.402616)
				)
				(arc
					(start 8.127746 -368.441224)
					(mid 8.687314 -367.929795)
					(end 8.175752 -367.37036)
				)
			)
		)
		(polygon
			(pts
				(arc
					(start 27.24023 -365.912654)
					(mid 26.644981 -365.334548)
					(end 26.06675 -365.929672)
				)
				(arc
					(start 26.083006 -367.02365)
					(mid 26.678382 -367.601754)
					(end 27.256486 -367.006378)
				)
			)
		)
		(polygon
			(pts
				(arc
					(start 8.804148 -364.27283)
					(mid 8.889746 -363.447584)
					(end 8.0645 -363.361986)
				)
				(xy 8.062976 -363.359954) (xy 7.375398 -363.918246)
				(arc
					(start 7.376922 -363.920278)
					(mid 7.291324 -364.745524)
					(end 8.11657 -364.831122)
				)
				(xy 8.118094 -364.833154) (xy 8.805672 -364.275116) (xy 8.805672 -364.274608)
			)
		)
		(polygon
			(pts
				(arc
					(start 30.4038 -362.2548)
					(mid 29.816933 -361.668314)
					(end 29.23032 -362.255054)
				)
				(arc
					(start 29.23032 -363.213904)
					(mid 29.81706 -363.800644)
					(end 30.4038 -363.213904)
				)
			)
		)
		(polygon
			(pts
				(arc
					(start 8.256524 -359.096818)
					(mid 8.8265 -358.498902)
					(end 8.228584 -357.928926)
				)
				(xy 8.228584 -357.926386) (xy 7.351776 -357.947214)
				(arc
					(start 7.351776 -357.949754)
					(mid 6.7818 -358.54767)
					(end 7.379716 -359.117646)
				)
				(xy 7.379716 -359.120186) (xy 8.25627 -359.099358) (xy 8.256524 -359.099104)
			)
		)
		(polygon
			(pts
				(arc
					(start 8.446516 -353.441508)
					(mid 8.750808 -352.669348)
					(end 7.978648 -352.365056)
				)
				(xy 7.977632 -352.36277) (xy 7.00405 -352.786188) (xy 7.003796 -352.786442)
				(arc
					(start 7.004812 -352.788728)
					(mid 6.70054 -353.560934)
					(end 7.47268 -353.864926)
				)
				(xy 7.473696 -353.867212) (xy 8.447532 -353.443794)
			)
		)
		(polygon
			(pts
				(arc
					(start 25.282144 -348.859348)
					(mid 24.727789 -348.241881)
					(end 24.110188 -348.796102)
				)
				(arc
					(start 24.052022 -349.878904)
					(mid 24.606504 -350.496378)
					(end 25.223978 -349.941896)
				)
			)
		)
		(polygon
			(pts
				(arc
					(start 7.075932 -347.594174)
					(mid 6.500241 -347.001594)
					(end 5.907532 -347.577156)
				)
				(arc
					(start 5.894578 -348.491048)
					(mid 6.470396 -349.08363)
					(end 7.062978 -348.507812)
				)
			)
		)
		(polygon
			(pts
				(arc
					(start 29.138626 -344.885518)
					(mid 28.463364 -344.403151)
					(end 27.980894 -345.078304)
				)
				(arc
					(start 28.12288 -345.93022)
					(mid 28.798266 -346.412566)
					(end 29.280612 -345.73718)
				)
			)
		)
		(polygon
			(pts
				(arc
					(start 29.41574 -341.502746)
					(mid 28.828873 -340.91626)
					(end 28.24226 -341.503)
				)
				(arc
					(start 28.24226 -342.431116)
					(mid 28.829 -343.017856)
					(end 29.41574 -342.431116)
				)
			)
		)
		(polygon
			(pts
				(arc
					(start 26.58364 -341.502746)
					(mid 25.996773 -340.91626)
					(end 25.41016 -341.503)
				)
				(arc
					(start 25.41016 -342.431116)
					(mid 25.9969 -343.017856)
					(end 26.58364 -342.431116)
				)
			)
		)
		(polygon
			(pts
				(arc
					(start 22.65426 -341.08644)
					(mid 22.07006 -340.50224)
					(end 21.48586 -341.08644)
				)
				(arc
					(start 21.48586 -342.045544)
					(mid 22.070187 -342.62949)
					(end 22.65426 -342.04529)
				)
			)
		)
		(polygon
			(pts
				(arc
					(start 28.330652 -338.66201)
					(mid 27.743912 -338.07527)
					(end 27.157172 -338.66201)
				)
				(arc
					(start 27.157172 -339.621114)
					(mid 27.744039 -340.2076)
					(end 28.330652 -339.62086)
				)
			)
		)
		(polygon
			(pts
				(arc
					(start 35.506914 -273.700494)
					(mid 34.921063 -273.112992)
					(end 34.333434 -273.698716)
				)
				(arc
					(start 34.332418 -274.618196)
					(mid 34.918396 -275.205698)
					(end 35.505898 -274.61972)
				)
				(xy 35.505898 -274.618196)
			)
		)
		(polygon
			(pts
				(arc
					(start 32.190182 -273.690588)
					(mid 31.603315 -273.104102)
					(end 31.016702 -273.690842)
				)
				(arc
					(start 31.016702 -274.618958)
					(mid 31.603442 -275.205698)
					(end 32.190182 -274.618958)
				)
			)
		)
		(polygon
			(pts
				(arc
					(start 32.082486 -266.8651)
					(mid 31.495746 -266.27836)
					(end 30.909006 -266.8651)
				)
				(arc
					(start 30.909006 -267.728954)
					(mid 31.495873 -268.31544)
					(end 32.082486 -267.7287)
				)
			)
		)
		(polygon
			(pts
				(arc
					(start 22.528022 -238.079788)
					(mid 22.014434 -237.428024)
					(end 21.36267 -237.941612)
				)
				(arc
					(start 21.26107 -238.799624)
					(mid 21.774529 -239.451657)
					(end 22.426422 -238.938054)
				)
			)
		)
		(polygon
			(pts
				(arc
					(start 28.296362 -235.819442)
					(mid 27.75496 -235.190547)
					(end 27.12593 -235.731812)
				)
				(arc
					(start 27.061414 -236.59719)
					(mid 27.602942 -237.226094)
					(end 28.231846 -236.684566)
				)
			)
		)
		(polygon
			(pts
				(arc
					(start 13.388086 -176.752504)
					(mid 12.823063 -176.149766)
					(end 12.220194 -176.714658)
				)
				(arc
					(start 12.192254 -177.578004)
					(mid 12.757404 -178.180746)
					(end 13.360146 -177.615596)
				)
			)
		)
		(polygon
			(pts
				(arc
					(start 7.619238 -169.531284)
					(mid 7.032371 -168.944798)
					(end 6.445758 -169.531538)
				)
				(arc
					(start 6.445758 -170.459654)
					(mid 7.032498 -171.046394)
					(end 7.619238 -170.459654)
				)
			)
		)
		(polygon
			(pts
				(arc
					(start 7.374382 -165.563804)
					(mid 6.757924 -165.013894)
					(end 6.208014 -165.630352)
				)
				(xy 6.205474 -165.630606) (xy 6.272022 -166.797228)
				(arc
					(start 6.274562 -166.796974)
					(mid 6.89102 -167.346884)
					(end 7.44093 -166.730426)
				)
				(xy 7.44347 -166.730172) (xy 7.376922 -165.563804)
			)
		)
		(polygon
			(pts
				(arc
					(start 37.223192 -163.92017)
					(mid 36.636325 -163.333684)
					(end 36.049712 -163.920424)
				)
				(arc
					(start 36.049712 -164.879274)
					(mid 36.636452 -165.466014)
					(end 37.223192 -164.879274)
				)
			)
		)
		(polygon
			(pts
				(arc
					(start 33.533334 -164.29355)
					(mid 33.94075 -163.570666)
					(end 33.217866 -163.16325)
				)
				(arc
					(start 32.361886 -163.402518)
					(mid 31.945616 -164.123487)
					(end 32.66948 -164.53485)
				)
			)
		)
		(polygon
			(pts
				(arc
					(start 7.332472 -161.531046)
					(mid 6.748145 -160.9471)
					(end 6.164072 -161.5313)
				)
				(arc
					(start 6.164072 -162.459416)
					(mid 6.748272 -163.043616)
					(end 7.332472 -162.459416)
				)
			)
		)
		(polygon
			(pts
				(arc
					(start 32.463486 -161.429446)
					(mid 31.876619 -160.84296)
					(end 31.290006 -161.4297)
				)
				(arc
					(start 31.290006 -162.2933)
					(mid 31.876746 -162.88004)
					(end 32.463486 -162.2933)
				)
			)
		)
		(polygon
			(pts
				(arc
					(start 7.568946 -157.531308)
					(mid 6.984619 -156.947362)
					(end 6.400546 -157.531562)
				)
				(arc
					(start 6.400546 -158.459678)
					(mid 6.984746 -159.043878)
					(end 7.568946 -158.459678)
				)
			)
		)
		(polygon
			(pts
				(arc
					(start 15.827502 -135.675116)
					(mid 15.241651 -135.087614)
					(end 14.654022 -135.673338)
				)
				(arc
					(start 14.653006 -136.536938)
					(mid 15.238984 -137.12444)
					(end 15.826486 -136.538462)
				)
				(xy 15.826486 -136.5377) (xy 15.826486 -136.536938)
			)
		)
		(polygon
			(pts
				(arc
					(start 22.481286 -135.191246)
					(mid 21.894419 -134.60476)
					(end 21.307806 -135.1915)
				)
				(arc
					(start 21.307806 -136.15035)
					(mid 21.894546 -136.73709)
					(end 22.481286 -136.15035)
				)
			)
		)
		(polygon
			(pts
				(arc
					(start 7.342886 -133.514338)
					(mid 6.756019 -132.927852)
					(end 6.169406 -133.514592)
				)
				(arc
					(start 6.169406 -134.442708)
					(mid 6.756146 -135.029448)
					(end 7.342886 -134.442708)
				)
			)
		)
		(polygon
			(pts
				(arc
					(start 9.857486 -131.514596)
					(mid 9.270619 -130.92811)
					(end 8.684006 -131.51485)
				)
				(arc
					(start 8.684006 -132.4737)
					(mid 9.270746 -133.06044)
					(end 9.857486 -132.4737)
				)
			)
		)
		(polygon
			(pts
				(arc
					(start 25.1206 -130.99034)
					(mid 25.70734 -130.4036)
					(end 25.1206 -129.81686)
				)
				(arc
					(start 24.257 -129.81686)
					(mid 23.67026 -130.4036)
					(end 24.257 -130.99034)
				)
			)
		)
		(polygon
			(pts
				(arc
					(start 7.292086 -127.49911)
					(mid 6.705219 -126.912624)
					(end 6.118606 -127.499364)
				)
				(arc
					(start 6.118606 -128.458214)
					(mid 6.705346 -129.044954)
					(end 7.292086 -128.458214)
				)
			)
		)
		(polygon
			(pts
				(arc
					(start 7.265416 -121.477532)
					(mid 6.642862 -120.929146)
					(end 6.094476 -121.5517)
				)
				(xy 6.091936 -121.551954) (xy 6.1468 -122.41403)
				(arc
					(start 6.14934 -122.413776)
					(mid 6.771894 -122.962162)
					(end 7.32028 -122.339608)
				)
				(xy 7.32282 -122.339354) (xy 7.267956 -121.477532) (xy 7.267702 -121.477278)
			)
		)
		(polygon
			(pts
				(arc
					(start 16.945102 -119.646954)
					(mid 16.359505 -119.059198)
					(end 15.771622 -119.644668)
				)
				(arc
					(start 15.770098 -120.508268)
					(mid 16.355822 -121.096024)
					(end 16.943578 -120.5103)
				)
				(xy 16.943578 -120.509284) (xy 16.943578 -120.508268)
			)
		)
		(polygon
			(pts
				(arc
					(start 7.418832 -115.548156)
					(mid 6.848602 -114.945414)
					(end 6.24586 -115.515644)
				)
				(xy 6.24332 -115.515644) (xy 6.21792 -116.441982)
				(arc
					(start 6.22046 -116.441982)
					(mid 6.294807 -116.744497)
					(end 6.513576 -116.966238)
				)
				(arc
					(start 6.513576 -116.966238)
					(mid 6.242247 -117.182704)
					(end 6.140704 -117.514624)
				)
				(arc
					(start 6.144006 -118.429532)
					(mid 6.732778 -119.01424)
					(end 7.317486 -118.425468)
				)
				(arc
					(start 7.314184 -117.510814)
					(mid 7.235055 -117.218568)
					(end 7.020814 -117.004592)
				)
				(arc
					(start 7.020814 -117.004592)
					(mid 7.286943 -116.795648)
					(end 7.393432 -116.474494)
				)
				(xy 7.395972 -116.474494) (xy 7.421372 -115.54841) (xy 7.421118 -115.548156)
			)
		)
		(polygon
			(pts
				(arc
					(start 7.315454 -111.576612)
					(mid 6.710553 -111.008664)
					(end 6.142482 -111.613442)
				)
				(arc
					(start 6.16966 -112.476788)
					(mid 6.774688 -113.044732)
					(end 7.342632 -112.439704)
				)
			)
		)
		(polygon
			(pts
				(arc
					(start 7.266686 -101.4984)
					(mid 6.679819 -100.911914)
					(end 6.093206 -101.498654)
				)
				(arc
					(start 6.093206 -102.457504)
					(mid 6.679946 -103.044244)
					(end 7.266686 -102.457504)
				)
			)
		)
		(polygon
			(pts
				(arc
					(start 7.266686 -97.498662)
					(mid 6.679819 -96.912176)
					(end 6.093206 -97.498916)
				)
				(arc
					(start 6.093206 -98.457766)
					(mid 6.679946 -99.044506)
					(end 7.266686 -98.457766)
				)
			)
		)
		(polygon
			(pts
				(arc
					(start 22.581108 -32.148526)
					(mid 21.950172 -31.609538)
					(end 21.411184 -32.240474)
				)
				(arc
					(start 21.487384 -33.209738)
					(mid 22.118192 -33.74897)
					(end 22.657308 -33.118044)
				)
			)
		)
		(polygon
			(pts
				(arc
					(start 29.968444 -31.996888)
					(mid 29.432377 -31.461202)
					(end 28.896564 -31.997142)
				)
				(arc
					(start 28.896564 -33.0327)
					(mid 29.432504 -33.56864)
					(end 29.968444 -33.0327)
				)
			)
		)
		(polygon
			(pts
				(xy 230.45674 -19.6342) (xy 198.294752 -19.6342) (xy 193.230246 -24.698706) (xy 193.230246 -484.850694)
				(xy 197.659752 -489.2802) (xy 240.61674 -489.2802) (xy 244.919246 -484.977694) (xy 244.919246 -34.096706)
			)
		)
		(polygon
			(pts
				(xy 85.93074 -9.0932) (xy 35.480752 -9.0932) (xy 31.559246 -13.014706) (xy 31.559246 -38.064694)
				(xy 36.687252 -43.1927) (xy 29.908246 -49.971706) (xy 29.908246 -99.024694) (xy 39.052246 -108.168694)
				(xy 39.052246 -153.126694) (xy 40.830246 -154.904694) (xy 40.830246 -164.017706) (xy 30.924246 -173.923706)
				(xy 30.924246 -197.195694) (xy 39.306246 -205.577694) (xy 39.306246 -212.658706) (xy 38.290246 -213.674706)
				(xy 38.290246 -234.533694) (xy 39.306246 -235.549694) (xy 39.306246 -272.856706) (xy 27.368246 -284.794706)
				(xy 27.368246 -312.130694) (xy 39.179246 -323.941694) (xy 39.179246 -361.756706) (xy 25.336246 -375.599706)
				(xy 25.336246 -403.189694) (xy 39.179246 -417.032694) (xy 39.179246 -453.069706) (xy 29.003752 -463.2452)
				(xy 21.256752 -463.2452) (xy 18.732246 -465.769706) (xy 18.732246 -493.232694) (xy 20.875752 -495.3762)
				(xy 48.97374 -495.3762) (xy 60.261246 -484.088694) (xy 60.261246 -492.216694) (xy 61.769752 -493.7252)
				(xy 70.56374 -493.7252) (xy 73.73874 -490.5502) (xy 132.41274 -490.5502) (xy 140.017246 -482.945694)
				(xy 140.017246 -24.571706) (xy 137.23874 -21.7932) (xy 98.63074 -21.7932)
			)
		)
	)
	(zone
		(net "P5VA")
		(layer "In3.Cu")
		(hatch none 0.5)
		(connect_pads
			(clearance 0.5)
		)
		(min_thickness 0.25)
		(fill yes
			(thermal_gap 0.5)
			(thermal_bridge_width 0.5)
			(island_removal_mode 0)
		)
		(polygon
			(pts
				(xy 198.45274 -20.0152) (xy 193.611246 -24.856694) (xy 193.611246 -484.692706) (xy 197.81774 -488.8992)
				(xy 240.458752 -488.8992) (xy 244.538246 -484.819706) (xy 244.538246 -34.254694) (xy 230.298752 -20.0152)
			)
		)
		(polygon
			(pts
				(arc
					(start 216.792048 -475.829884)
					(mid 217.375485 -475.239715)
					(end 216.78519 -474.656404)
				)
				(arc
					(start 215.92159 -474.661484)
					(mid 215.338406 -475.25178)
					(end 215.928702 -475.834964)
				)
			)
		)
		(polygon
			(pts
				(arc
					(start 220.782896 -472.907106)
					(mid 220.196029 -472.32062)
					(end 219.609416 -472.90736)
				)
				(arc
					(start 219.609416 -473.86621)
					(mid 220.196156 -474.45295)
					(end 220.782896 -473.86621)
				)
			)
		)
		(polygon
			(pts
				(arc
					(start 216.490804 -373.038624)
					(mid 217.067892 -372.442232)
					(end 216.4715 -371.865144)
				)
				(arc
					(start 215.608154 -371.879368)
					(mid 215.031064 -372.475633)
					(end 215.627204 -373.052848)
				)
			)
		)
		(polygon
			(pts
				(arc
					(start 223.61144 -369.971574)
					(mid 223.058863 -369.352569)
					(end 222.439992 -369.90528)
				)
				(xy 222.437452 -369.905026) (xy 222.386398 -370.80444)
				(arc
					(start 222.388938 -370.804694)
					(mid 222.941642 -371.423438)
					(end 223.560386 -370.870734)
				)
				(xy 223.562926 -370.870988) (xy 223.61398 -369.971828) (xy 223.613726 -369.971574)
			)
		)
		(polygon
			(pts
				(arc
					(start 216.11971 -270.192754)
					(mid 216.69832 -269.597759)
					(end 216.1032 -269.019274)
				)
				(arc
					(start 215.1888 -269.032228)
					(mid 214.610442 -269.62735)
					(end 215.205564 -270.205708)
				)
			)
		)
		(polygon
			(pts
				(arc
					(start 223.656144 -267.024866)
					(mid 223.11779 -266.393432)
					(end 222.48622 -266.931648)
				)
				(arc
					(start 222.417894 -267.792708)
					(mid 222.956374 -268.424152)
					(end 223.587818 -267.885672)
				)
			)
		)
		(polygon
			(pts
				(arc
					(start 215.344756 -165.87724)
					(mid 214.747348 -166.453312)
					(end 215.32342 -167.05072)
				)
				(arc
					(start 216.186766 -167.066468)
					(mid 216.78443 -166.490523)
					(end 216.208356 -165.892988)
				)
			)
		)
		(polygon
			(pts
				(arc
					(start 223.750124 -163.975288)
					(mid 223.163257 -163.388802)
					(end 222.576644 -163.975542)
				)
				(arc
					(start 222.576644 -164.934392)
					(mid 223.163384 -165.521132)
					(end 223.750124 -164.934392)
				)
			)
		)
		(polygon
			(pts
				(arc
					(start 216.236042 -64.080136)
					(mid 216.811352 -63.481966)
					(end 216.213182 -62.906656)
				)
				(arc
					(start 215.349836 -62.92342)
					(mid 214.774524 -63.521463)
					(end 215.372442 -64.0969)
				)
			)
		)
		(polygon
			(pts
				(arc
					(start 223.618552 -60.985908)
					(mid 223.031685 -60.399422)
					(end 222.445072 -60.986162)
				)
				(arc
					(start 222.445072 -61.945012)
					(mid 223.031812 -62.531752)
					(end 223.618552 -61.945012)
				)
			)
		)
	)
	(zone
		(net "P12V")
		(layer "In4.Cu")
		(hatch none 0.5)
		(connect_pads
			(clearance 0.5)
		)
		(min_thickness 0.25)
		(fill yes
			(thermal_gap 0.5)
			(thermal_bridge_width 0.5)
			(island_removal_mode 0)
		)
		(polygon
			(pts
				(arc
					(start 0.999998 -0.763016)
					(mid 0.832426 -0.832426)
					(end 0.763016 -0.999998)
				)
				(xy 0.763016 -53.433726) (xy 0.816356 -53.487066)
				(arc
					(start 5.050028 -53.487066)
					(mid 6.763004 -55.200042)
					(end 5.050028 -56.913018)
				)
				(xy 0.816102 -56.913018) (xy 0.763016 -56.966104) (xy 0.763016 -104.233726) (xy 0.816356 -104.287066)
				(arc
					(start 5.050028 -104.287066)
					(mid 6.574439 -105.218724)
					(end 6.440678 -107.000294)
				)
				(arc
					(start 6.440678 -107.000294)
					(mid 7.003377 -107.018543)
					(end 7.291578 -107.502198)
				)
				(xy 7.294118 -107.502198) (xy 7.325868 -108.36529)
				(arc
					(start 7.323328 -108.36529)
					(mid 6.758686 -108.973112)
					(end 6.150864 -108.40847)
				)
				(xy 6.148578 -108.40847) (xy 6.148324 -108.408216) (xy 6.116574 -107.545378)
				(arc
					(start 6.119114 -107.545378)
					(mid 6.127653 -107.422093)
					(end 6.161786 -107.303316)
				)
				(arc
					(start 6.161786 -107.303316)
					(mid 5.642464 -107.607384)
					(end 5.050028 -107.713018)
				)
				(xy 0.816102 -107.713018) (xy 0.763016 -107.766104) (xy 0.763016 -208.233772) (xy 0.816102 -208.286858)
				(arc
					(start 5.050028 -208.286858)
					(mid 6.763258 -210.000088)
					(end 5.050028 -211.713064)
				)
				(xy 0.816102 -211.713064) (xy 0.763016 -211.76615) (xy 0.763016 -303.433734) (xy 0.816356 -303.487074)
				(arc
					(start 5.050028 -303.487074)
					(mid 6.763004 -305.20005)
					(end 5.050028 -306.913026)
				)
				(xy 0.816102 -306.913026) (xy 0.763016 -306.966112) (xy 0.763016 -354.233734) (xy 0.816356 -354.287074)
				(arc
					(start 5.050028 -354.287074)
					(mid 6.763004 -356.00005)
					(end 5.050028 -357.713026)
				)
				(xy 0.816102 -357.713026) (xy 0.763016 -357.766112) (xy 0.763016 -458.23378) (xy 0.816102 -458.286866)
				(arc
					(start 5.050028 -458.286866)
					(mid 6.763258 -460.000096)
					(end 5.050028 -461.713072)
				)
				(xy 0.816102 -461.713072) (xy 0.763016 -461.766158)
				(arc
					(start 0.763016 -505.000006)
					(mid 0.832426 -505.167578)
					(end 0.999998 -505.236988)
				)
				(arc
					(start 261.500112 -505.236988)
					(mid 261.667684 -505.167578)
					(end 261.737094 -505.000006)
				)
				(xy 261.737094 -428.396146) (xy 261.183882 -427.842934)
				(arc
					(start 260.149594 -427.842934)
					(mid 258.726388 -427.253265)
					(end 258.136898 -425.829984)
				)
				(xy 258.136898 -411.80131) (xy 257.583686 -411.248098)
				(arc
					(start 251.394976 -411.248098)
					(mid 250.097036 -409.950158)
					(end 251.394976 -408.651964)
				)
				(xy 257.583686 -408.651964) (xy 258.136898 -408.098752)
				(arc
					(start 258.136898 -364.16996)
					(mid 258.726388 -362.746679)
					(end 260.149594 -362.15701)
				)
				(xy 261.183882 -362.15701) (xy 261.737094 -361.603798)
				(arc
					(start 261.737094 -0.999998)
					(mid 261.667684 -0.832426)
					(end 261.500112 -0.763016)
				)
			)
		)
		(polygon
			(pts
				(arc
					(start 216.792048 -475.829884)
					(mid 217.375485 -475.239715)
					(end 216.78519 -474.656404)
				)
				(arc
					(start 215.92159 -474.661484)
					(mid 215.338406 -475.25178)
					(end 215.928702 -475.834964)
				)
			)
		)
		(polygon
			(pts
				(arc
					(start 31.927546 -475.163896)
					(mid 31.307532 -474.612462)
					(end 30.756098 -475.232476)
				)
				(xy 30.753558 -475.23273) (xy 30.804104 -476.09506)
				(arc
					(start 30.806644 -476.094806)
					(mid 31.426658 -476.64624)
					(end 31.978092 -476.026226)
				)
				(xy 31.980632 -476.025972) (xy 31.930086 -475.163896) (xy 31.929832 -475.163642)
			)
		)
		(polygon
			(pts
				(arc
					(start 220.782896 -472.907106)
					(mid 220.196029 -472.32062)
					(end 219.609416 -472.90736)
				)
				(arc
					(start 219.609416 -473.86621)
					(mid 220.196156 -474.45295)
					(end 220.782896 -473.86621)
				)
			)
		)
		(polygon
			(pts
				(arc
					(start 35.638486 -472.819984)
					(mid 35.051619 -472.233498)
					(end 34.465006 -472.820238)
				)
				(arc
					(start 34.465006 -473.748354)
					(mid 35.051746 -474.335094)
					(end 35.638486 -473.748354)
				)
			)
		)
		(polygon
			(pts
				(arc
					(start 22.225508 -444.181992)
					(mid 21.613876 -443.62116)
					(end 21.053044 -444.232792)
				)
				(arc
					(start 21.090382 -445.095376)
					(mid 21.701887 -445.656457)
					(end 22.262846 -445.04483)
				)
			)
		)
		(polygon
			(pts
				(arc
					(start 28.373832 -441.830968)
					(mid 27.772614 -441.259214)
					(end 27.20086 -441.860432)
				)
				(xy 27.19832 -441.860432) (xy 27.22372 -442.876178) (xy 27.223974 -442.876432)
				(arc
					(start 27.22626 -442.876432)
					(mid 27.827478 -443.448186)
					(end 28.399232 -442.846968)
				)
				(xy 28.401772 -442.846968) (xy 28.376372 -441.830968)
			)
		)
		(polygon
			(pts
				(arc
					(start 11.938 -441.81014)
					(mid 12.52474 -441.2234)
					(end 11.938 -440.63666)
				)
				(arc
					(start 11.0744 -440.63666)
					(mid 10.48766 -441.2234)
					(end 11.0744 -441.81014)
				)
			)
		)
		(polygon
			(pts
				(arc
					(start 12.239498 -438.105042)
					(mid 11.652758 -437.518302)
					(end 11.066018 -438.105042)
				)
				(arc
					(start 11.066018 -439.033412)
					(mid 11.652885 -439.619898)
					(end 12.239498 -439.033158)
				)
			)
		)
		(polygon
			(pts
				(xy 7.423912 -423.515536)
				(arc
					(start 7.423658 -423.518076)
					(mid 6.856476 -424.020742)
					(end 7.359142 -424.587924)
				)
				(xy 7.358888 -424.590464) (xy 8.22071 -424.642788) (xy 8.220964 -424.642534)
				(arc
					(start 8.221218 -424.640248)
					(mid 8.7884 -424.137582)
					(end 8.285734 -423.5704)
				)
				(xy 8.285988 -423.56786)
			)
		)
		(polygon
			(pts
				(xy 8.142224 -421.362632) (xy 7.278878 -421.34028)
				(arc
					(start 7.278878 -421.34282)
					(mid 6.703314 -421.889428)
					(end 7.249922 -422.464992)
				)
				(xy 7.249922 -422.467532) (xy 8.113014 -422.489884) (xy 8.113268 -422.48963)
				(arc
					(start 8.113268 -422.487344)
					(mid 8.688832 -421.940736)
					(end 8.142224 -421.365172)
				)
			)
		)
		(polygon
			(pts
				(arc
					(start 7.53364 -417.243768)
					(mid 6.93852 -417.821999)
					(end 7.516622 -418.417248)
				)
				(arc
					(start 8.380222 -418.429694)
					(mid 8.975344 -417.851336)
					(end 8.396986 -417.256214)
				)
			)
		)
		(polygon
			(pts
				(arc
					(start 8.581898 -414.041336)
					(mid 8.779764 -413.272478)
					(end 8.010906 -413.074612)
				)
				(arc
					(start 7.215886 -413.544512)
					(mid 7.007016 -414.313851)
					(end 7.778242 -414.516062)
				)
			)
		)
		(polygon
			(pts
				(arc
					(start 8.203946 -410.396436)
					(mid 8.765286 -409.835096)
					(end 8.203946 -409.273756)
				)
				(arc
					(start 7.340346 -409.273756)
					(mid 6.779006 -409.835096)
					(end 7.340346 -410.396436)
				)
			)
		)
		(polygon
			(pts
				(arc
					(start 7.77875 -399.884138)
					(mid 8.335766 -399.273649)
					(end 7.725156 -398.716754)
				)
				(arc
					(start 6.862318 -398.756378)
					(mid 6.30555 -399.366994)
					(end 6.916166 -399.923762)
				)
			)
		)
		(polygon
			(pts
				(arc
					(start 8.689086 -385.53263)
					(mid 8.127619 -384.971544)
					(end 7.566406 -385.532884)
				)
				(arc
					(start 7.566406 -386.461)
					(mid 8.127746 -387.02234)
					(end 8.689086 -386.461)
				)
			)
		)
		(polygon
			(pts
				(arc
					(start 7.675626 -383.436368)
					(mid 7.063238 -383.996311)
					(end 7.623048 -384.608832)
				)
				(arc
					(start 8.485886 -384.647186)
					(mid 9.09828 -384.087116)
					(end 8.53821 -383.474722)
				)
			)
		)
		(polygon
			(pts
				(arc
					(start 8.661146 -380.96444)
					(mid 9.247886 -380.3777)
					(end 8.661146 -379.79096)
				)
				(arc
					(start 7.746746 -379.79096)
					(mid 7.160006 -380.3777)
					(end 7.746746 -380.96444)
				)
			)
		)
		(polygon
			(pts
				(arc
					(start 8.810498 -376.880374)
					(mid 9.287002 -376.291094)
					(end 8.697722 -375.81459)
				)
				(xy 8.697468 -375.81205) (xy 7.817104 -375.905268)
				(arc
					(start 7.817358 -375.907808)
					(mid 7.340854 -376.497088)
					(end 7.930134 -376.973592)
				)
				(xy 7.930388 -376.976132) (xy 8.810498 -376.882914) (xy 8.810752 -376.88266)
			)
		)
		(polygon
			(pts
				(arc
					(start 216.490804 -373.038624)
					(mid 217.067892 -372.442232)
					(end 216.4715 -371.865144)
				)
				(arc
					(start 215.608154 -371.879368)
					(mid 215.031064 -372.475633)
					(end 215.627204 -373.052848)
				)
			)
		)
		(polygon
			(pts
				(arc
					(start 31.979616 -372.061486)
					(mid 31.386018 -371.590316)
					(end 30.914848 -372.183914)
				)
				(xy 30.912308 -372.184168) (xy 31.034736 -373.248428) (xy 31.03499 -373.248682)
				(arc
					(start 31.037276 -373.248428)
					(mid 31.630874 -373.719598)
					(end 32.102044 -373.126)
				)
				(xy 32.104584 -373.125746) (xy 31.982156 -372.061232)
			)
		)
		(polygon
			(pts
				(arc
					(start 7.74319 -370.89334)
					(mid 7.13004 -371.452521)
					(end 7.689088 -372.065804)
				)
				(arc
					(start 8.587486 -372.107206)
					(mid 9.200642 -371.547898)
					(end 8.641334 -370.934742)
				)
			)
		)
		(polygon
			(pts
				(arc
					(start 223.61144 -369.971574)
					(mid 223.058863 -369.352569)
					(end 222.439992 -369.90528)
				)
				(xy 222.437452 -369.905026) (xy 222.386398 -370.80444)
				(arc
					(start 222.388938 -370.804694)
					(mid 222.941642 -371.423438)
					(end 223.560386 -370.870734)
				)
				(xy 223.562926 -370.870988) (xy 223.61398 -369.971828) (xy 223.613726 -369.971574)
			)
		)
		(polygon
			(pts
				(arc
					(start 36.908232 -369.934744)
					(mid 36.337748 -369.332256)
					(end 35.73526 -369.90274)
				)
				(xy 35.73272 -369.90274) (xy 35.707574 -370.823998)
				(arc
					(start 35.710114 -370.823998)
					(mid 36.280598 -371.426486)
					(end 36.883086 -370.856002)
				)
				(xy 36.885626 -370.856002) (xy 36.910772 -369.934998) (xy 36.910518 -369.934744)
			)
		)
		(polygon
			(pts
				(arc
					(start 7.312914 -367.331752)
					(mid 6.753606 -367.843308)
					(end 7.265162 -368.402616)
				)
				(arc
					(start 8.127746 -368.441224)
					(mid 8.687314 -367.929795)
					(end 8.175752 -367.37036)
				)
			)
		)
		(polygon
			(pts
				(arc
					(start 27.24023 -365.912654)
					(mid 26.644981 -365.334548)
					(end 26.06675 -365.929672)
				)
				(arc
					(start 26.083006 -367.02365)
					(mid 26.678382 -367.601754)
					(end 27.256486 -367.006378)
				)
			)
		)
		(polygon
			(pts
				(arc
					(start 8.804148 -364.27283)
					(mid 8.889746 -363.447584)
					(end 8.0645 -363.361986)
				)
				(xy 8.062976 -363.359954) (xy 7.375398 -363.918246)
				(arc
					(start 7.376922 -363.920278)
					(mid 7.291324 -364.745524)
					(end 8.11657 -364.831122)
				)
				(xy 8.118094 -364.833154) (xy 8.805672 -364.275116) (xy 8.805672 -364.274608)
			)
		)
		(polygon
			(pts
				(arc
					(start 30.4038 -362.2548)
					(mid 29.816933 -361.668314)
					(end 29.23032 -362.255054)
				)
				(arc
					(start 29.23032 -363.213904)
					(mid 29.81706 -363.800644)
					(end 30.4038 -363.213904)
				)
			)
		)
		(polygon
			(pts
				(arc
					(start 8.256524 -359.096818)
					(mid 8.8265 -358.498902)
					(end 8.228584 -357.928926)
				)
				(xy 8.228584 -357.926386) (xy 7.351776 -357.947214)
				(arc
					(start 7.351776 -357.949754)
					(mid 6.7818 -358.54767)
					(end 7.379716 -359.117646)
				)
				(xy 7.379716 -359.120186) (xy 8.25627 -359.099358) (xy 8.256524 -359.099104)
			)
		)
		(polygon
			(pts
				(arc
					(start 8.446516 -353.441508)
					(mid 8.750808 -352.669348)
					(end 7.978648 -352.365056)
				)
				(xy 7.977632 -352.36277) (xy 7.00405 -352.786188) (xy 7.003796 -352.786442)
				(arc
					(start 7.004812 -352.788728)
					(mid 6.70054 -353.560934)
					(end 7.47268 -353.864926)
				)
				(xy 7.473696 -353.867212) (xy 8.447532 -353.443794)
			)
		)
		(polygon
			(pts
				(arc
					(start 25.282144 -348.859348)
					(mid 24.727789 -348.241881)
					(end 24.110188 -348.796102)
				)
				(arc
					(start 24.052022 -349.878904)
					(mid 24.606504 -350.496378)
					(end 25.223978 -349.941896)
				)
			)
		)
		(polygon
			(pts
				(arc
					(start 7.075932 -347.594174)
					(mid 6.500241 -347.001594)
					(end 5.907532 -347.577156)
				)
				(arc
					(start 5.894578 -348.491048)
					(mid 6.470396 -349.08363)
					(end 7.062978 -348.507812)
				)
			)
		)
		(polygon
			(pts
				(arc
					(start 29.138626 -344.885518)
					(mid 28.463364 -344.403151)
					(end 27.980894 -345.078304)
				)
				(arc
					(start 28.12288 -345.93022)
					(mid 28.798266 -346.412566)
					(end 29.280612 -345.73718)
				)
			)
		)
		(polygon
			(pts
				(arc
					(start 29.41574 -341.502746)
					(mid 28.828873 -340.91626)
					(end 28.24226 -341.503)
				)
				(arc
					(start 28.24226 -342.431116)
					(mid 28.829 -343.017856)
					(end 29.41574 -342.431116)
				)
			)
		)
		(polygon
			(pts
				(arc
					(start 26.58364 -341.502746)
					(mid 25.996773 -340.91626)
					(end 25.41016 -341.503)
				)
				(arc
					(start 25.41016 -342.431116)
					(mid 25.9969 -343.017856)
					(end 26.58364 -342.431116)
				)
			)
		)
		(polygon
			(pts
				(arc
					(start 22.65426 -341.08644)
					(mid 22.07006 -340.50224)
					(end 21.48586 -341.08644)
				)
				(arc
					(start 21.48586 -342.045544)
					(mid 22.070187 -342.62949)
					(end 22.65426 -342.04529)
				)
			)
		)
		(polygon
			(pts
				(arc
					(start 28.330652 -338.66201)
					(mid 27.743912 -338.07527)
					(end 27.157172 -338.66201)
				)
				(arc
					(start 27.157172 -339.621114)
					(mid 27.744039 -340.2076)
					(end 28.330652 -339.62086)
				)
			)
		)
		(polygon
			(pts
				(arc
					(start 35.506914 -273.700494)
					(mid 34.921063 -273.112992)
					(end 34.333434 -273.698716)
				)
				(arc
					(start 34.332418 -274.618196)
					(mid 34.918396 -275.205698)
					(end 35.505898 -274.61972)
				)
				(xy 35.505898 -274.618196)
			)
		)
		(polygon
			(pts
				(arc
					(start 32.190182 -273.690588)
					(mid 31.603315 -273.104102)
					(end 31.016702 -273.690842)
				)
				(arc
					(start 31.016702 -274.618958)
					(mid 31.603442 -275.205698)
					(end 32.190182 -274.618958)
				)
			)
		)
		(polygon
			(pts
				(arc
					(start 216.11971 -270.192754)
					(mid 216.69832 -269.597759)
					(end 216.1032 -269.019274)
				)
				(arc
					(start 215.1888 -269.032228)
					(mid 214.610442 -269.62735)
					(end 215.205564 -270.205708)
				)
			)
		)
		(polygon
			(pts
				(arc
					(start 223.656144 -267.024866)
					(mid 223.11779 -266.393432)
					(end 222.48622 -266.931648)
				)
				(arc
					(start 222.417894 -267.792708)
					(mid 222.956374 -268.424152)
					(end 223.587818 -267.885672)
				)
			)
		)
		(polygon
			(pts
				(arc
					(start 32.082486 -266.8651)
					(mid 31.495746 -266.27836)
					(end 30.909006 -266.8651)
				)
				(arc
					(start 30.909006 -267.728954)
					(mid 31.495873 -268.31544)
					(end 32.082486 -267.7287)
				)
			)
		)
		(polygon
			(pts
				(arc
					(start 22.528022 -238.079788)
					(mid 22.014434 -237.428024)
					(end 21.36267 -237.941612)
				)
				(arc
					(start 21.26107 -238.799624)
					(mid 21.774529 -239.451657)
					(end 22.426422 -238.938054)
				)
			)
		)
		(polygon
			(pts
				(arc
					(start 28.296362 -235.819442)
					(mid 27.75496 -235.190547)
					(end 27.12593 -235.731812)
				)
				(arc
					(start 27.061414 -236.59719)
					(mid 27.602942 -237.226094)
					(end 28.231846 -236.684566)
				)
			)
		)
		(polygon
			(pts
				(arc
					(start 13.388086 -176.752504)
					(mid 12.823063 -176.149766)
					(end 12.220194 -176.714658)
				)
				(arc
					(start 12.192254 -177.578004)
					(mid 12.757404 -178.180746)
					(end 13.360146 -177.615596)
				)
			)
		)
		(polygon
			(pts
				(arc
					(start 7.619238 -169.531284)
					(mid 7.032371 -168.944798)
					(end 6.445758 -169.531538)
				)
				(arc
					(start 6.445758 -170.459654)
					(mid 7.032498 -171.046394)
					(end 7.619238 -170.459654)
				)
			)
		)
		(polygon
			(pts
				(arc
					(start 215.344756 -165.87724)
					(mid 214.747348 -166.453312)
					(end 215.32342 -167.05072)
				)
				(arc
					(start 216.186766 -167.066468)
					(mid 216.78443 -166.490523)
					(end 216.208356 -165.892988)
				)
			)
		)
		(polygon
			(pts
				(arc
					(start 7.374382 -165.563804)
					(mid 6.757924 -165.013894)
					(end 6.208014 -165.630352)
				)
				(xy 6.205474 -165.630606) (xy 6.272022 -166.797228)
				(arc
					(start 6.274562 -166.796974)
					(mid 6.89102 -167.346884)
					(end 7.44093 -166.730426)
				)
				(xy 7.44347 -166.730172) (xy 7.376922 -165.563804)
			)
		)
		(polygon
			(pts
				(arc
					(start 223.750124 -163.975288)
					(mid 223.163257 -163.388802)
					(end 222.576644 -163.975542)
				)
				(arc
					(start 222.576644 -164.934392)
					(mid 223.163384 -165.521132)
					(end 223.750124 -164.934392)
				)
			)
		)
		(polygon
			(pts
				(arc
					(start 37.223192 -163.92017)
					(mid 36.636325 -163.333684)
					(end 36.049712 -163.920424)
				)
				(arc
					(start 36.049712 -164.879274)
					(mid 36.636452 -165.466014)
					(end 37.223192 -164.879274)
				)
			)
		)
		(polygon
			(pts
				(arc
					(start 33.533334 -164.29355)
					(mid 33.94075 -163.570666)
					(end 33.217866 -163.16325)
				)
				(arc
					(start 32.361886 -163.402518)
					(mid 31.945616 -164.123487)
					(end 32.66948 -164.53485)
				)
			)
		)
		(polygon
			(pts
				(arc
					(start 7.332472 -161.531046)
					(mid 6.748145 -160.9471)
					(end 6.164072 -161.5313)
				)
				(arc
					(start 6.164072 -162.459416)
					(mid 6.748272 -163.043616)
					(end 7.332472 -162.459416)
				)
			)
		)
		(polygon
			(pts
				(arc
					(start 32.463486 -161.429446)
					(mid 31.876619 -160.84296)
					(end 31.290006 -161.4297)
				)
				(arc
					(start 31.290006 -162.2933)
					(mid 31.876746 -162.88004)
					(end 32.463486 -162.2933)
				)
			)
		)
		(polygon
			(pts
				(arc
					(start 7.568946 -157.531308)
					(mid 6.984619 -156.947362)
					(end 6.400546 -157.531562)
				)
				(arc
					(start 6.400546 -158.459678)
					(mid 6.984746 -159.043878)
					(end 7.568946 -158.459678)
				)
			)
		)
		(polygon
			(pts
				(arc
					(start 15.827502 -135.675116)
					(mid 15.241651 -135.087614)
					(end 14.654022 -135.673338)
				)
				(arc
					(start 14.653006 -136.536938)
					(mid 15.238984 -137.12444)
					(end 15.826486 -136.538462)
				)
				(xy 15.826486 -136.5377) (xy 15.826486 -136.536938)
			)
		)
		(polygon
			(pts
				(arc
					(start 22.481286 -135.191246)
					(mid 21.894419 -134.60476)
					(end 21.307806 -135.1915)
				)
				(arc
					(start 21.307806 -136.15035)
					(mid 21.894546 -136.73709)
					(end 22.481286 -136.15035)
				)
			)
		)
		(polygon
			(pts
				(arc
					(start 7.342886 -133.514338)
					(mid 6.756019 -132.927852)
					(end 6.169406 -133.514592)
				)
				(arc
					(start 6.169406 -134.442708)
					(mid 6.756146 -135.029448)
					(end 7.342886 -134.442708)
				)
			)
		)
		(polygon
			(pts
				(arc
					(start 9.857486 -131.514596)
					(mid 9.270619 -130.92811)
					(end 8.684006 -131.51485)
				)
				(arc
					(start 8.684006 -132.4737)
					(mid 9.270746 -133.06044)
					(end 9.857486 -132.4737)
				)
			)
		)
		(polygon
			(pts
				(arc
					(start 25.1206 -130.99034)
					(mid 25.70734 -130.4036)
					(end 25.1206 -129.81686)
				)
				(arc
					(start 24.257 -129.81686)
					(mid 23.67026 -130.4036)
					(end 24.257 -130.99034)
				)
			)
		)
		(polygon
			(pts
				(arc
					(start 7.292086 -127.49911)
					(mid 6.705219 -126.912624)
					(end 6.118606 -127.499364)
				)
				(arc
					(start 6.118606 -128.458214)
					(mid 6.705346 -129.044954)
					(end 7.292086 -128.458214)
				)
			)
		)
		(polygon
			(pts
				(arc
					(start 7.265416 -121.477532)
					(mid 6.642862 -120.929146)
					(end 6.094476 -121.5517)
				)
				(xy 6.091936 -121.551954) (xy 6.1468 -122.41403)
				(arc
					(start 6.14934 -122.413776)
					(mid 6.771894 -122.962162)
					(end 7.32028 -122.339608)
				)
				(xy 7.32282 -122.339354) (xy 7.267956 -121.477532) (xy 7.267702 -121.477278)
			)
		)
		(polygon
			(pts
				(arc
					(start 16.945102 -119.646954)
					(mid 16.359505 -119.059198)
					(end 15.771622 -119.644668)
				)
				(arc
					(start 15.770098 -120.508268)
					(mid 16.355822 -121.096024)
					(end 16.943578 -120.5103)
				)
				(xy 16.943578 -120.509284) (xy 16.943578 -120.508268)
			)
		)
		(polygon
			(pts
				(arc
					(start 7.418832 -115.548156)
					(mid 6.848602 -114.945414)
					(end 6.24586 -115.515644)
				)
				(xy 6.24332 -115.515644) (xy 6.21792 -116.441982)
				(arc
					(start 6.22046 -116.441982)
					(mid 6.294807 -116.744497)
					(end 6.513576 -116.966238)
				)
				(arc
					(start 6.513576 -116.966238)
					(mid 6.242247 -117.182704)
					(end 6.140704 -117.514624)
				)
				(arc
					(start 6.144006 -118.429532)
					(mid 6.732778 -119.01424)
					(end 7.317486 -118.425468)
				)
				(arc
					(start 7.314184 -117.510814)
					(mid 7.235055 -117.218568)
					(end 7.020814 -117.004592)
				)
				(arc
					(start 7.020814 -117.004592)
					(mid 7.286943 -116.795648)
					(end 7.393432 -116.474494)
				)
				(xy 7.395972 -116.474494) (xy 7.421372 -115.54841) (xy 7.421118 -115.548156)
			)
		)
		(polygon
			(pts
				(arc
					(start 7.315454 -111.576612)
					(mid 6.710553 -111.008664)
					(end 6.142482 -111.613442)
				)
				(arc
					(start 6.16966 -112.476788)
					(mid 6.774688 -113.044732)
					(end 7.342632 -112.439704)
				)
			)
		)
		(polygon
			(pts
				(arc
					(start 7.266686 -101.4984)
					(mid 6.679819 -100.911914)
					(end 6.093206 -101.498654)
				)
				(arc
					(start 6.093206 -102.457504)
					(mid 6.679946 -103.044244)
					(end 7.266686 -102.457504)
				)
			)
		)
		(polygon
			(pts
				(arc
					(start 7.266686 -97.498662)
					(mid 6.679819 -96.912176)
					(end 6.093206 -97.498916)
				)
				(arc
					(start 6.093206 -98.457766)
					(mid 6.679946 -99.044506)
					(end 7.266686 -98.457766)
				)
			)
		)
		(polygon
			(pts
				(arc
					(start 216.236042 -64.080136)
					(mid 216.811352 -63.481966)
					(end 216.213182 -62.906656)
				)
				(arc
					(start 215.349836 -62.92342)
					(mid 214.774524 -63.521463)
					(end 215.372442 -64.0969)
				)
			)
		)
		(polygon
			(pts
				(arc
					(start 31.773876 -63.350394)
					(mid 31.25724 -62.70117)
					(end 30.608016 -63.217806)
				)
				(xy 30.605476 -63.217552) (xy 30.503368 -64.11595) (xy 30.503622 -64.116204)
				(arc
					(start 30.505908 -64.116458)
					(mid 31.022544 -64.765682)
					(end 31.671768 -64.249046)
				)
				(xy 31.674308 -64.2493) (xy 31.776416 -63.350648)
			)
		)
		(polygon
			(pts
				(arc
					(start 223.618552 -60.985908)
					(mid 223.031685 -60.399422)
					(end 222.445072 -60.986162)
				)
				(arc
					(start 222.445072 -61.945012)
					(mid 223.031812 -62.531752)
					(end 223.618552 -61.945012)
				)
			)
		)
		(polygon
			(pts
				(arc
					(start 38.686486 -60.890912)
					(mid 38.099619 -60.304426)
					(end 37.513006 -60.891166)
				)
				(arc
					(start 37.513006 -61.850016)
					(mid 38.099746 -62.436756)
					(end 38.686486 -61.850016)
				)
			)
		)
		(polygon
			(pts
				(arc
					(start 22.581108 -32.148526)
					(mid 21.950172 -31.609538)
					(end 21.411184 -32.240474)
				)
				(arc
					(start 21.487384 -33.209738)
					(mid 22.118192 -33.74897)
					(end 22.657308 -33.118044)
				)
			)
		)
		(polygon
			(pts
				(arc
					(start 29.968444 -31.996888)
					(mid 29.432377 -31.461202)
					(end 28.896564 -31.997142)
				)
				(arc
					(start 28.896564 -33.0327)
					(mid 29.432504 -33.56864)
					(end 29.968444 -33.0327)
				)
			)
		)
	)
	(zone
		(layer "In5.Cu")
		(hatch none 0.5)
		(connect_pads
			(clearance 0)
		)
		(min_thickness 0.25)
		(keepout
			(tracks not_allowed)
			(vias allowed)
			(pads allowed)
			(copperpour not_allowed)
			(footprints allowed)
		)
		(placement
			(enabled no)
			(sheetname "")
		)
		(fill
			(thermal_gap 0.5)
			(thermal_bridge_width 0.5)
			(island_removal_mode 0)
		)
		(polygon
			(pts
				(arc
					(start 11.840718 -438.809384)
					(mid 12.033532 -438.720949)
					(end 12.239498 -438.670192)
				)
				(arc
					(start 12.239498 -438.468008)
					(mid 12.033532 -438.417252)
					(end 11.840718 -438.328816)
				)
				(arc
					(start 11.840718 -438.328816)
					(mid 11.41988 -437.929033)
					(end 11.918188 -438.226708)
				)
				(arc
					(start 11.918188 -438.226708)
					(mid 12.074012 -438.296858)
					(end 12.239498 -438.339484)
				)
				(arc
					(start 12.239498 -438.105042)
					(mid 11.652758 -437.518302)
					(end 11.066018 -438.105042)
				)
				(arc
					(start 11.066018 -439.032904)
					(mid 11.652631 -439.619898)
					(end 12.239498 -439.033158)
				)
				(arc
					(start 12.239498 -438.798716)
					(mid 12.074008 -438.841329)
					(end 11.918188 -438.911492)
				)
				(arc
					(start 11.918188 -438.911492)
					(mid 11.419887 -439.209162)
					(end 11.840718 -438.809384)
				)
			)
		)
	)
	(zone
		(layer "In5.Cu")
		(hatch none 0.5)
		(connect_pads
			(clearance 0)
		)
		(min_thickness 0.25)
		(keepout
			(tracks not_allowed)
			(vias allowed)
			(pads allowed)
			(copperpour not_allowed)
			(footprints allowed)
		)
		(placement
			(enabled no)
			(sheetname "")
		)
		(fill
			(thermal_gap 0.5)
			(thermal_bridge_width 0.5)
			(island_removal_mode 0)
		)
		(polygon
			(pts
				(arc
					(start 29.01696 -342.207342)
					(mid 29.209774 -342.118907)
					(end 29.41574 -342.06815)
				)
				(arc
					(start 29.41574 -341.865966)
					(mid 29.209774 -341.81521)
					(end 29.01696 -341.726774)
				)
				(arc
					(start 29.01696 -341.726774)
					(mid 28.596122 -341.326991)
					(end 29.09443 -341.624666)
				)
				(arc
					(start 29.09443 -341.624666)
					(mid 29.250254 -341.694816)
					(end 29.41574 -341.737442)
				)
				(arc
					(start 29.41574 -341.503254)
					(mid 28.829127 -340.91626)
					(end 28.24226 -341.503)
				)
				(arc
					(start 28.24226 -342.431116)
					(mid 28.829 -343.017856)
					(end 29.41574 -342.431116)
				)
				(arc
					(start 29.41574 -342.196674)
					(mid 29.25025 -342.239287)
					(end 29.09443 -342.30945)
				)
				(arc
					(start 29.09443 -342.30945)
					(mid 28.596129 -342.60712)
					(end 29.01696 -342.207342)
				)
			)
		)
	)
	(zone
		(net "P12V_HDD12")
		(layer "In5.Cu")
		(hatch none 0.5)
		(connect_pads
			(clearance 0.5)
		)
		(min_thickness 0.25)
		(fill yes
			(thermal_gap 0.5)
			(thermal_bridge_width 0.5)
			(island_removal_mode 0)
		)
		(polygon
			(pts
				(xy 36.194746 -218.0717) (xy 22.986746 -218.0717) (xy 22.478746 -217.5637) (xy 22.478746 -215.9127)
				(xy 22.732746 -215.6587) (xy 38.099746 -215.6587) (xy 40.385746 -217.9447) (xy 42.417746 -217.9447)
				(xy 43.052746 -218.5797) (xy 43.052746 -219.8497) (xy 42.798746 -220.1037) (xy 38.226746 -220.1037)
			)
		)
	)
	(zone
		(net "GND")
		(layer "In5.Cu")
		(hatch none 0.5)
		(connect_pads
			(clearance 0.5)
		)
		(min_thickness 0.25)
		(fill yes
			(thermal_gap 0.5)
			(thermal_bridge_width 0.5)
			(island_removal_mode 0)
		)
		(polygon
			(pts
				(xy 1.016 -0.762) (xy 0.762 -1.016) (xy 0.762 -52.8066) (xy 1.397 -53.4416) (xy 5.8928 -53.4416)
				(xy 6.8072 -54.356) (xy 6.8072 -56.2102) (xy 6.0452 -56.9722) (xy 1.397 -56.9722) (xy 0.762 -57.6072)
				(xy 0.762 -103.4542) (xy 1.397 -104.0892) (xy 6.4008 -104.0892) (xy 7.511796 -105.200196) (xy 7.365746 -105.3465)
				(xy 7.365746 -106.5276) (xy 5.422646 -108.4707) (xy 5.422646 -135.191246) (xy 6.1976 -135.9662)
				(xy 7.0866 -135.9662) (xy 8.255 -134.7978) (xy 8.255 -130.5052) (xy 14.478 -124.2822) (xy 14.5288 -124.2822)
				(xy 18.7452 -128.4986) (xy 18.3388 -128.905) (xy 17.272 -128.905) (xy 16.4846 -128.1176) (xy 15.4686 -128.1176)
				(xy 15.2654 -128.3208) (xy 15.2654 -134.493) (xy 14.0208 -135.7376) (xy 14.0208 -142.9766) (xy 12.3444 -144.653)
				(xy 11.684 -144.653) (xy 10.369804 -145.967196) (xy 5.936996 -145.967196) (xy 5.587746 -146.3167)
				(xy 5.587746 -198.0184) (xy 7.5946 -200.025254) (xy 7.5946 -200.152) (xy 8.3566 -200.914) (xy 11.684 -200.914)
				(xy 17.2466 -206.4766) (xy 17.2466 -207.7974) (xy 16.1544 -208.8896) (xy 14.8082 -208.8896) (xy 14.3002 -209.3976)
				(xy 14.3002 -216.1286) (xy 10.3124 -220.1164) (xy 9.525 -220.1164) (xy 8.382 -218.9734) (xy 7.9756 -218.9734)
				(xy 7.6454 -219.3036) (xy 6.6548 -219.3036) (xy 6.0579 -218.7067) (xy 1.142746 -218.7067) (xy 0.762 -219.087446)
				(xy 0.762 -302.895) (xy 1.3208 -303.4538) (xy 5.7658 -303.4538) (xy 6.7818 -304.4698) (xy 6.7818 -306.07)
				(xy 5.842 -307.0098) (xy 1.3208 -307.0098) (xy 0.762 -307.5686) (xy 0.762 -353.5426) (xy 1.3462 -354.1268)
				(xy 5.765546 -354.1268) (xy 6.858 -355.219254) (xy 6.858 -356.743) (xy 6.731 -356.87) (xy 6.730746 -356.87)
				(xy 5.587746 -358.013) (xy 5.587746 -388.467346) (xy 6.2484 -389.128) (xy 6.9088 -389.128) (xy 9.7282 -386.3086)
				(xy 9.7282 -378.968) (xy 9.779 -378.9172) (xy 10.8966 -378.9172) (xy 12.5476 -380.5682) (xy 12.5476 -389.5598)
				(xy 15.7988 -392.811) (xy 15.7988 -395.986) (xy 14.985746 -396.799054) (xy 14.985746 -437.7182)
				(xy 14.986 -437.7182) (xy 15.1638 -437.896) (xy 28.4226 -437.896) (xy 31.2928 -440.7662) (xy 31.2928 -442.3918)
				(xy 31.0642 -442.6204) (xy 29.7434 -442.6204) (xy 27.6987 -440.5757) (xy 15.3289 -440.5757) (xy 14.985746 -440.918854)
				(xy 14.985746 -460.4004) (xy 16.865346 -462.28) (xy 23.749 -462.28) (xy 24.0284 -462.5594) (xy 24.0284 -462.6356)
				(xy 25.8572 -464.4644) (xy 38.862 -464.4644) (xy 39.5986 -465.201) (xy 39.5986 -470.2556) (xy 39.116 -470.2556)
				(xy 38.1508 -471.2208) (xy 38.1508 -472.7956) (xy 38.0238 -472.9226) (xy 37.5666 -472.9226) (xy 37.2364 -473.2528)
				(xy 37.2364 -474.472) (xy 37.6936 -474.9292) (xy 37.6936 -475.4372) (xy 36.7284 -476.4024) (xy 34.1884 -476.4024)
				(xy 32.1945 -474.4085) (xy 13.055346 -474.4085) (xy 7.632446 -468.9856) (xy 0.9652 -468.9856) (xy 0.762 -469.1888)
				(xy 0.762 -493.903) (xy 1.016 -494.157) (xy 1.016 -494.919) (xy 0.762 -495.173) (xy 0.762 -504.952)
				(xy 1.016 -505.206) (xy 261.366 -505.206) (xy 261.619746 -504.952254) (xy 261.619746 -496.951) (xy 261.62 -496.950746)
				(xy 261.62 -495.427) (xy 261.619746 -495.427) (xy 261.619746 -430.911254) (xy 261.62 -430.911) (xy 258.0259 -427.3169)
				(xy 258.0259 -425.2087) (xy 258.0132 -425.196) (xy 258.0132 -412.6992) (xy 257.302 -411.988) (xy 251.206 -411.988)
				(xy 250.063 -410.845) (xy 250.063 -408.94) (xy 251.206 -407.797) (xy 256.794 -407.797) (xy 258.064 -406.527)
				(xy 258.064 -363.22) (xy 259.207 -362.077) (xy 261.112 -362.077) (xy 261.62 -361.569) (xy 261.62 -322.719954)
				(xy 261.619746 -322.7197) (xy 261.619746 -1.016) (xy 261.493 -0.889254) (xy 261.493 -0.889) (xy 261.366 -0.762)
			)
		)
		(polygon
			(pts
				(xy 87.376 -451.2564) (xy 51.6636 -451.2564) (xy 51.5366 -451.3834) (xy 51.5366 -452.3232) (xy 51.9684 -452.755)
				(xy 87.0966 -452.755) (xy 87.5538 -452.2978) (xy 87.5538 -451.4342)
			)
		)
		(polygon
			(pts
				(arc
					(start 27.5463 -446.600326)
					(mid 27.567173 -446.490043)
					(end 27.473656 -446.42786)
				)
				(xy 26.82621 -446.42786) (xy 25.77973 -447.47434) (xy 25.780746 -447.496692)
				(arc
					(start 25.781254 -447.522092)
					(mid 25.811012 -447.593934)
					(end 25.882854 -447.623692)
				)
				(arc
					(start 27.510232 -447.623692)
					(mid 27.605256 -447.558051)
					(end 27.577542 -447.445892)
				)
				(arc
					(start 27.577542 -447.445892)
					(mid 27.380935 -447.029808)
					(end 27.5463 -446.600326)
				)
			)
		)
		(polygon
			(pts
				(arc
					(start 195.897754 -287.52419)
					(mid 195.794047 -287.520311)
					(end 195.741036 -287.609534)
				)
				(arc
					(start 195.741036 -290.08451)
					(mid 195.761119 -290.144899)
					(end 195.813172 -290.181538)
				)
				(arc
					(start 195.813172 -290.181538)
					(mid 195.787642 -290.182231)
					(end 195.765674 -290.195254)
				)
				(xy 195.74129 -290.219892) (xy 195.74129 -294.47109) (xy 195.796408 -294.47109) (xy 195.80098 -294.470328)
				(xy 195.80987 -294.46855) (xy 195.852542 -294.461692)
				(arc
					(start 195.852542 -294.359076)
					(mid 195.880703 -294.429031)
					(end 195.949316 -294.460422)
				)
				(arc
					(start 195.984368 -294.462962)
					(mid 196.062684 -294.437219)
					(end 196.096128 -294.36187)
				)
				(xy 196.096128 -287.606486)
				(arc
					(start 196.05879 -287.596326)
					(mid 195.975529 -287.56638)
					(end 195.897754 -287.52419)
				)
			)
		)
		(polygon
			(pts
				(arc
					(start 14.476984 -213.054946)
					(mid 14.369964 -213.026796)
					(end 14.300708 -213.113112)
				)
				(xy 14.300708 -215.18753)
				(arc
					(start 14.865858 -215.752426)
					(mid 14.976403 -215.774262)
					(end 15.039086 -215.680544)
				)
				(arc
					(start 15.039086 -213.347046)
					(mid 15.007786 -213.273948)
					(end 14.933422 -213.2457)
				)
				(arc
					(start 14.933422 -213.2457)
					(mid 14.684049 -213.200954)
					(end 14.476984 -213.054946)
				)
			)
		)
		(polygon
			(pts
				(xy 14.88948 -208.890108) (xy 14.808454 -208.890108) (xy 14.300708 -209.397854)
				(arc
					(start 14.300708 -212.209888)
					(mid 14.369961 -212.296212)
					(end 14.476984 -212.268054)
				)
				(arc
					(start 14.476984 -212.268054)
					(mid 14.684032 -212.122007)
					(end 14.933422 -212.0773)
				)
				(arc
					(start 14.933422 -212.0773)
					(mid 15.008104 -212.049118)
					(end 15.03934 -211.9757)
				)
				(xy 15.03934 -209.039968)
			)
		)
		(polygon
			(pts
				(xy 81.345278 -201.781156) (xy 79.140304 -201.781156) (xy 79.140304 -202.202542)
				(arc
					(start 79.10322 -202.239626)
					(mid 79.092314 -202.294857)
					(end 79.139034 -202.32624)
				)
				(arc
					(start 80.960976 -202.32624)
					(mid 81.17392 -202.168392)
					(end 81.434686 -202.120754)
				)
				(arc
					(start 81.434686 -202.120754)
					(mid 81.532534 -202.060297)
					(end 81.511394 -201.947272)
				)
			)
		)
		(polygon
			(pts
				(arc
					(start 8.793734 -153.797508)
					(mid 8.728142 -153.702756)
					(end 8.616188 -153.730198)
				)
				(arc
					(start 8.616188 -153.730198)
					(mid 8.573263 -153.773832)
					(end 8.526018 -153.812748)
				)
				(arc
					(start 8.526018 -153.812748)
					(mid 8.506177 -153.844742)
					(end 8.513826 -153.881582)
				)
				(arc
					(start 8.513826 -153.881582)
					(mid 8.5285 -154.502837)
					(end 7.9756 -154.786584)
				)
				(arc
					(start 7.9756 -154.786584)
					(mid 7.874966 -154.844891)
					(end 7.895082 -154.959558)
				)
				(arc
					(start 8.620506 -155.684728)
					(mid 8.731051 -155.706564)
					(end 8.793734 -155.612846)
				)
			)
		)
		(polygon
			(pts
				(xy 18.080482 -454.621646)
				(arc
					(start 20.447254 -452.25462)
					(mid 20.426061 -452.36499)
					(end 20.519644 -452.42734)
				)
				(xy 50.595276 -452.42734)
				(arc
					(start 50.596038 -452.377556)
					(mid 50.608813 -452.265036)
					(end 50.643028 -452.157084)
				)
				(arc
					(start 50.643028 -452.157084)
					(mid 50.634202 -452.061405)
					(end 50.549556 -452.01586)
				)
				(arc
					(start 37.94125 -452.01586)
					(mid 37.87469 -452.040919)
					(end 37.84092 -452.10349)
				)
				(arc
					(start 37.84092 -452.10349)
					(mid 37.839635 -452.075481)
					(end 37.83076 -452.04888)
				)
				(arc
					(start 37.83076 -452.04888)
					(mid 37.771523 -451.734193)
					(end 37.886894 -451.43547)
				)
				(arc
					(start 37.886894 -451.43547)
					(mid 37.896726 -451.328956)
					(end 37.805868 -451.272656)
				)
				(xy 18.88236 -451.272656)
				(arc
					(start 16.499078 -448.889628)
					(mid 16.388533 -448.867792)
					(end 16.32585 -448.96151)
				)
				(xy 16.32585 -453.742806)
				(arc
					(start 17.349978 -454.766934)
					(mid 17.42177 -454.796708)
					(end 17.493488 -454.766934)
				)
				(arc
					(start 17.493488 -454.766934)
					(mid 17.752688 -454.61668)
					(end 18.052288 -454.614534)
				)
			)
		)
		(polygon
			(pts
				(arc
					(start 8.414004 -198.882508)
					(mid 8.476841 -198.976169)
					(end 8.587486 -198.954136)
				)
				(xy 8.876792 -198.665084)
				(arc
					(start 8.876792 -178.4858)
					(mid 8.813955 -178.392139)
					(end 8.70331 -178.414172)
				)
				(xy 8.414004 -178.703224)
			)
		)
		(polygon
			(pts
				(arc
					(start 18.619216 -110.271814)
					(mid 18.558916 -110.174201)
					(end 18.445988 -110.195106)
				)
				(arc
					(start 17.375632 -111.265462)
					(mid 17.353547 -111.376129)
					(end 17.44726 -111.438944)
				)
				(arc
					(start 18.975578 -111.438944)
					(mid 19.070762 -111.372878)
					(end 19.042126 -111.260636)
				)
				(arc
					(start 19.042126 -111.260636)
					(mid 18.717108 -110.814796)
					(end 18.619216 -110.271814)
				)
			)
		)
		(polygon
			(pts
				(xy 24.384 -253.9238) (xy 21.0058 -253.9238) (xy 20.955 -253.9746)
				(arc
					(start 20.955 -254.478536)
					(mid 20.92425 -254.51412)
					(end 20.890738 -254.547116)
				)
				(arc
					(start 20.890738 -254.547116)
					(mid 20.857471 -254.6223)
					(end 20.890738 -254.697484)
				)
				(arc
					(start 20.890738 -254.697484)
					(mid 20.924248 -254.730482)
					(end 20.955 -254.766064)
				)
				(arc
					(start 20.955 -255.494536)
					(mid 20.535845 -255.713794)
					(end 20.091654 -255.551178)
				)
				(arc
					(start 20.091654 -255.551178)
					(mid 20.020218 -255.52284)
					(end 19.949414 -255.552702)
				)
				(xy 19.216116 -256.286) (xy 15.9004 -256.286) (xy 15.875 -256.3114) (xy 15.0368 -256.3114) (xy 14.8336 -256.5146)
				(xy 9.2456 -256.5146) (xy 5.3848 -260.3754) (xy 5.3848 -262.9154) (xy 7.2136 -264.7442) (xy 7.2136 -264.8458)
				(xy 9.5758 -267.208) (xy 14.2494 -267.208) (xy 15.4178 -266.0396) (xy 16.4338 -266.0396) (xy 25.2984 -274.9042)
				(xy 25.4254 -274.9042) (xy 28.194 -277.6728) (xy 28.4226 -277.6728) (xy 28.575 -277.8252) (xy 30.5816 -277.8252)
				(xy 30.607 -277.7998) (xy 30.607 -277.0632) (xy 29.3624 -275.8186) (xy 29.3624 -272.8722) (xy 29.337 -272.8468)
				(xy 29.337 -272.3896) (xy 25.0952 -268.1478) (xy 25.0952 -254.635)
			)
		)
		(polygon
			(pts
				(arc
					(start 36.252912 -242.235736)
					(mid 36.274997 -242.125069)
					(end 36.181284 -242.062254)
				)
				(xy 36.096448 -242.062254) (xy 28.552648 -249.606308) (xy 26.739342 -249.606308)
				(arc
					(start 26.732484 -249.60834)
					(mid 26.702321 -249.616263)
					(end 26.671778 -249.622564)
				)
				(xy 26.630122 -249.62993) (xy 26.630122 -249.723148) (xy 28.7655 -249.723148)
			)
		)
		(polygon
			(pts
				(arc
					(start 82.18551 -197.954392)
					(mid 82.279171 -197.891555)
					(end 82.257138 -197.78091)
				)
				(xy 81.701386 -197.224904)
				(arc
					(start 81.584546 -197.224904)
					(mid 81.511186 -197.256479)
					(end 81.4832 -197.33133)
				)
				(arc
					(start 81.4832 -197.33133)
					(mid 81.442185 -197.574681)
					(end 81.304384 -197.779386)
				)
				(arc
					(start 81.304384 -197.779386)
					(mid 81.280395 -197.890705)
					(end 81.374742 -197.954392)
				)
			)
		)
		(polygon
			(pts
				(xy 9.365996 -176.70399) (xy 9.365996 -170.736514) (xy 8.6868 -170.057318) (xy 8.261604 -170.482514)
				(xy 8.261604 -175.45939) (xy 8.4455 -175.643286)
				(arc
					(start 8.4455 -177.378868)
					(mid 8.508219 -177.472734)
					(end 8.618982 -177.45075)
				)
			)
		)
		(polygon
			(pts
				(xy 14.986254 -436.982108) (xy 14.986254 -437.717692) (xy 15.164054 -437.895492)
				(arc
					(start 18.134076 -437.895492)
					(mid 18.219612 -437.828533)
					(end 18.195798 -437.722518)
				)
				(arc
					(start 17.75714 -437.28386)
					(mid 17.422798 -437.06046)
					(end 17.028414 -436.982108)
				)
			)
		)
		(polygon
			(pts
				(arc
					(start 26.702004 -151.815292)
					(mid 26.794442 -151.823785)
					(end 26.884376 -151.846788)
				)
				(arc
					(start 26.884376 -151.846788)
					(mid 26.976544 -151.833341)
					(end 27.018996 -151.750522)
				)
				(xy 27.018996 -150.492714)
				(arc
					(start 26.875486 -150.349458)
					(mid 26.764702 -150.327422)
					(end 26.702004 -150.42134)
				)
			)
		)
		(polygon
			(pts
				(xy 36.957 -270.9418) (xy 34.2646 -270.9418) (xy 33.4264 -271.78) (xy 33.4264 -274.7518) (xy 33.8328 -275.1582)
				(xy 36.5506 -275.1582) (xy 36.9824 -274.7264) (xy 36.9824 -271.5006) (xy 37.0586 -271.4244) (xy 37.0586 -271.3228)
				(xy 36.9824 -271.2466) (xy 36.9824 -270.9672)
			)
		)
		(polygon
			(pts
				(xy 46.8884 -199.517) (xy 22.3774 -199.517) (xy 21.4122 -200.4822) (xy 21.4122 -212.210904)
				(arc
					(start 20.716748 -212.210904)
					(mid 20.621411 -212.277383)
					(end 20.650708 -212.389974)
				)
				(arc
					(start 20.650708 -212.389974)
					(mid 20.908392 -213.957783)
					(end 19.40687 -214.476838)
				)
				(xy 19.376136 -214.465154) (xy 19.3167 -214.524336) (xy 19.45386 -214.661496) (xy 21.312632 -214.661496)
				(arc
					(start 21.600414 -214.373714)
					(mid 21.578378 -214.484498)
					(end 21.672296 -214.547196)
				)
				(arc
					(start 24.44496 -214.547196)
					(mid 24.542462 -214.474161)
					(end 24.499824 -214.359998)
				)
				(arc
					(start 24.499824 -214.359998)
					(mid 24.399667 -214.278663)
					(end 24.319738 -214.177372)
				)
				(xy 24.304752 -214.153496) (xy 36.933632 -214.153496) (xy 37.549074 -213.5378) (xy 42.418 -213.5378)
				(xy 47.3964 -208.5594) (xy 47.3964 -200.025)
			)
		)
		(polygon
			(pts
				(arc
					(start 65.961514 -485.820466)
					(mid 65.889796 -485.790871)
					(end 65.818004 -485.820466)
				)
				(xy 65.78473 -485.850946) (xy 65.76695 -485.866186) (xy 65.76695 -489.32211)
				(arc
					(start 67.155822 -490.710728)
					(mid 67.232652 -490.740382)
					(end 67.30619 -490.703362)
				)
				(arc
					(start 67.30619 -490.703362)
					(mid 67.341592 -490.663388)
					(end 67.380104 -490.6264)
				)
				(arc
					(start 67.380104 -490.6264)
					(mid 67.414551 -490.5502)
					(end 67.380104 -490.474)
				)
				(arc
					(start 67.380104 -490.474)
					(mid 67.156798 -489.9787)
					(end 67.380104 -489.4834)
				)
				(arc
					(start 67.380104 -489.4834)
					(mid 67.414551 -489.4072)
					(end 67.380104 -489.331)
				)
				(arc
					(start 67.380104 -489.331)
					(mid 67.156798 -488.8357)
					(end 67.380104 -488.3404)
				)
				(arc
					(start 67.380104 -488.3404)
					(mid 67.414551 -488.2642)
					(end 67.380104 -488.188)
				)
				(arc
					(start 67.380104 -488.188)
					(mid 67.162665 -487.780572)
					(end 67.265042 -487.330242)
				)
				(xy 67.287648 -487.295698) (xy 66.915538 -486.923588) (xy 66.915538 -486.77449)
			)
		)
		(polygon
			(pts
				(arc
					(start 55.521352 -476.326962)
					(mid 55.427486 -476.389681)
					(end 55.44947 -476.500444)
				)
				(xy 57.795922 -478.84715)
				(arc
					(start 57.81929 -478.845372)
					(mid 58.052673 -478.874622)
					(end 58.255662 -478.993454)
				)
				(arc
					(start 58.255662 -478.993454)
					(mid 58.33399 -479.018847)
					(end 58.405522 -478.97796)
				)
				(arc
					(start 58.405522 -478.97796)
					(mid 58.535207 -478.849078)
					(end 58.698384 -478.766632)
				)
				(arc
					(start 58.698384 -478.766632)
					(mid 58.766152 -478.69379)
					(end 58.739278 -478.597976)
				)
				(xy 56.468264 -476.326962)
			)
		)
		(polygon
			(pts
				(arc
					(start 22.695154 -461.442308)
					(mid 22.623402 -461.471976)
					(end 22.593554 -461.543654)
				)
				(xy 22.591776 -461.588866) (xy 22.589998 -461.612234) (xy 23.117556 -462.139792)
				(arc
					(start 24.487378 -462.139792)
					(mid 24.581244 -462.077073)
					(end 24.55926 -461.96631)
				)
				(xy 24.035258 -461.442308)
			)
		)
		(polygon
			(pts
				(arc
					(start 19.286474 -460.26832)
					(mid 19.17616 -460.24609)
					(end 19.112992 -460.339186)
				)
				(arc
					(start 19.112992 -460.339186)
					(mid 18.796185 -461.085863)
					(end 18.045938 -461.394048)
				)
				(arc
					(start 17.440656 -461.394048)
					(mid 17.346824 -461.456684)
					(end 17.368774 -461.567276)
				)
				(xy 17.814036 -462.012792)
				(arc
					(start 19.222466 -462.012792)
					(mid 19.317442 -461.947939)
					(end 19.291046 -461.836008)
				)
				(arc
					(start 19.291046 -461.836008)
					(mid 19.127111 -461.227822)
					(end 19.610324 -460.823818)
				)
				(arc
					(start 19.610324 -460.823818)
					(mid 19.69359 -460.755811)
					(end 19.669252 -460.651098)
				)
			)
		)
		(polygon
			(pts
				(arc
					(start 29.391102 -453.385936)
					(mid 29.413138 -453.275152)
					(end 29.31922 -453.212454)
				)
				(xy 26.338022 -453.212454) (xy 26.338022 -453.265286) (xy 26.338276 -453.267318) (xy 26.339038 -453.277986)
				(xy 26.340054 -453.29729) (xy 26.58491 -453.541892) (xy 29.235146 -453.541892)
			)
		)
		(polygon
			(pts
				(arc
					(start 222.70593 -452.577454)
					(mid 222.651774 -452.470952)
					(end 222.533718 -452.48957)
				)
				(arc
					(start 205.595728 -469.427814)
					(mid 205.573692 -469.538598)
					(end 205.66761 -469.601296)
				)
				(xy 206.616554 -469.601296)
				(arc
					(start 222.908114 -453.309736)
					(mid 222.937876 -453.236238)
					(end 222.905828 -453.163686)
				)
				(arc
					(start 222.905828 -453.163686)
					(mid 222.73293 -452.895439)
					(end 222.70593 -452.577454)
				)
			)
		)
		(polygon
			(pts
				(arc
					(start 15.561818 -449.58)
					(mid 15.506264 -449.568869)
					(end 15.47495 -449.616068)
				)
				(xy 15.487142 -453.934068) (xy 15.588742 -453.934068) (xy 15.588742 -449.606924)
			)
		)
		(polygon
			(pts
				(arc
					(start 35.483038 -448.195954)
					(mid 35.45319 -448.124276)
					(end 35.381438 -448.094608)
				)
				(xy 26.434034 -448.094608)
				(arc
					(start 26.153872 -448.37477)
					(mid 26.131836 -448.485554)
					(end 26.225754 -448.548252)
				)
				(arc
					(start 35.428936 -448.548252)
					(mid 35.512948 -448.503788)
					(end 35.523424 -448.409314)
				)
				(arc
					(start 35.523424 -448.409314)
					(mid 35.493225 -448.304527)
					(end 35.483038 -448.195954)
				)
			)
		)
		(polygon
			(pts
				(arc
					(start 18.98269 -450.68744)
					(mid 19.015394 -450.61492)
					(end 18.985738 -450.541136)
				)
				(xy 16.100298 -447.655696) (xy 16.061436 -447.694812) (xy 16.058896 -447.698368)
				(arc
					(start 16.04772 -447.711576)
					(mid 16.017946 -447.783368)
					(end 16.04772 -447.855086)
				)
				(xy 18.29435 -450.10197) (xy 18.29435 -450.17436)
				(arc
					(start 18.823178 -450.702934)
					(mid 18.89497 -450.732708)
					(end 18.966688 -450.702934)
				)
			)
		)
		(polygon
			(pts
				(arc
					(start 35.55111 -447.543936)
					(mid 35.572946 -447.433391)
					(end 35.479228 -447.370708)
				)
				(xy 28.424632 -447.370708)
				(arc
					(start 28.409392 -447.388234)
					(mid 28.382069 -447.418044)
					(end 28.35275 -447.445892)
				)
				(arc
					(start 28.35275 -447.445892)
					(mid 28.325307 -447.557982)
					(end 28.420314 -447.623438)
				)
				(xy 35.471608 -447.623438)
			)
		)
		(polygon
			(pts
				(arc
					(start 15.159228 -446.2145)
					(mid 15.053194 -446.190634)
					(end 14.986254 -446.276222)
				)
				(xy 14.986254 -446.793874)
				(arc
					(start 15.90421 -447.711576)
					(mid 16.014755 -447.733412)
					(end 16.077438 -447.639694)
				)
				(xy 16.077438 -447.132964)
			)
		)
		(polygon
			(pts
				(arc
					(start 15.770098 -407.467816)
					(mid 15.707379 -407.37395)
					(end 15.596616 -407.395934)
				)
				(xy 15.3162 -407.676096) (xy 15.3162 -429.789082)
				(arc
					(start 15.472156 -429.944784)
					(mid 15.582701 -429.96662)
					(end 15.645384 -429.872902)
				)
				(xy 15.645384 -408.758644) (xy 15.769844 -408.634184)
			)
		)
		(polygon
			(pts
				(arc
					(start 219.10802 -381.785114)
					(mid 219.012947 -381.794914)
					(end 218.968066 -381.879348)
				)
				(arc
					(start 218.967812 -383.580894)
					(mid 219.030531 -383.67476)
					(end 219.141294 -383.652776)
				)
				(xy 219.429838 -383.364232)
				(arc
					(start 219.429838 -381.930148)
					(mid 219.40017 -381.858396)
					(end 219.328492 -381.828548)
				)
				(arc
					(start 219.328492 -381.828548)
					(mid 219.216155 -381.817506)
					(end 219.10802 -381.785114)
				)
			)
		)
		(polygon
			(pts
				(arc
					(start 219.141294 -364.31982)
					(mid 219.03051 -364.297784)
					(end 218.967812 -364.391702)
				)
				(arc
					(start 218.967812 -380.705106)
					(mid 219.016239 -380.791681)
					(end 219.115386 -380.795784)
				)
				(arc
					(start 219.115386 -380.795784)
					(mid 219.243637 -380.748789)
					(end 219.379292 -380.732792)
				)
				(arc
					(start 219.379292 -380.732792)
					(mid 219.451134 -380.703034)
					(end 219.480892 -380.631192)
				)
				(xy 219.480892 -364.659164)
			)
		)
		(polygon
			(pts
				(arc
					(start 14.105382 -358.813354)
					(mid 13.994837 -358.791518)
					(end 13.932154 -358.885236)
				)
				(xy 13.9319 -368.550444)
				(arc
					(start 13.969492 -368.588036)
					(mid 14.025046 -368.599167)
					(end 14.05636 -368.551968)
				)
				(xy 14.05636 -368.234722) (xy 18.722848 -363.568234)
				(arc
					(start 18.72107 -363.544866)
					(mid 18.7193 -363.4994)
					(end 18.72107 -363.453934)
				)
				(xy 18.722848 -363.430566)
			)
		)
		(polygon
			(pts
				(arc
					(start 195.852796 -296.794174)
					(mid 195.774657 -296.82002)
					(end 195.74129 -296.895266)
				)
				(xy 195.74129 -340.505034)
				(arc
					(start 195.922646 -340.68639)
					(mid 196.033191 -340.708226)
					(end 196.095874 -340.614508)
				)
				(arc
					(start 196.095874 -296.895266)
					(mid 196.062523 -296.820002)
					(end 195.984368 -296.794174)
				)
				(arc
					(start 195.984368 -296.794174)
					(mid 195.918582 -296.797456)
					(end 195.852796 -296.794174)
				)
			)
		)
		(polygon
			(pts
				(arc
					(start 21.18614 -250.832112)
					(mid 21.060746 -250.817562)
					(end 21.017992 -250.936252)
				)
				(arc
					(start 21.017992 -250.936252)
					(mid 21.048289 -251.618595)
					(end 20.710652 -252.212348)
				)
				(arc
					(start 20.710652 -252.212348)
					(mid 20.68752 -252.323247)
					(end 20.781518 -252.386592)
				)
				(arc
					(start 22.174708 -252.386592)
					(mid 22.248414 -252.354921)
					(end 22.276054 -252.279658)
				)
				(arc
					(start 22.276054 -252.279658)
					(mid 22.28436 -252.144429)
					(end 22.323552 -252.014736)
				)
				(xy 22.337268 -251.982986)
			)
		)
		(polygon
			(pts
				(arc
					(start 18.627598 -213.167722)
					(mid 18.571664 -213.063555)
					(end 18.455132 -213.082886)
				)
				(xy 18.316194 -213.22157) (xy 18.316194 -213.470744) (xy 18.07972 -213.707218)
				(arc
					(start 18.108422 -213.742778)
					(mid 18.210084 -213.932231)
					(end 18.236438 -214.145622)
				)
				(arc
					(start 18.236438 -214.145622)
					(mid 18.26377 -214.221494)
					(end 18.337784 -214.253572)
				)
				(arc
					(start 18.801588 -214.253572)
					(mid 18.893023 -214.19627)
					(end 18.881344 -214.08898)
				)
				(arc
					(start 18.881344 -214.08898)
					(mid 18.661588 -213.65394)
					(end 18.627598 -213.167722)
				)
			)
		)
		(polygon
			(pts
				(arc
					(start 84.692236 -202.163934)
					(mid 84.593993 -202.137637)
					(end 84.52231 -202.209654)
				)
				(arc
					(start 84.52231 -202.209654)
					(mid 84.463854 -202.351116)
					(end 84.370672 -202.472544)
				)
				(arc
					(start 84.370672 -202.472544)
					(mid 84.340898 -202.544426)
					(end 84.370672 -202.616308)
				)
				(arc
					(start 84.360766 -202.604878)
					(mid 84.301552 -202.566315)
					(end 84.23148 -202.575668)
				)
				(arc
					(start 84.23148 -202.575668)
					(mid 84.170769 -202.603596)
					(end 84.107274 -202.624436)
				)
				(arc
					(start 84.107274 -202.624436)
					(mid 84.035433 -202.696166)
					(end 84.061554 -202.794362)
				)
				(arc
					(start 87.68461 -206.417418)
					(mid 87.795155 -206.439254)
					(end 87.857838 -206.345536)
				)
				(arc
					(start 87.857838 -206.06131)
					(mid 87.82808 -205.989468)
					(end 87.756238 -205.95971)
				)
				(arc
					(start 87.756238 -205.95971)
					(mid 87.717494 -205.951928)
					(end 87.68461 -205.929992)
				)
				(arc
					(start 87.68461 -205.929992)
					(mid 87.795155 -205.951828)
					(end 87.857838 -205.85811)
				)
				(xy 87.857838 -205.32979)
			)
		)
		(polygon
			(pts
				(arc
					(start 83.387946 -199.200008)
					(mid 83.358188 -199.128166)
					(end 83.286346 -199.098408)
				)
				(arc
					(start 83.002374 -199.098408)
					(mid 82.908542 -199.161044)
					(end 82.930492 -199.271636)
				)
				(arc
					(start 88.66886 -205.010004)
					(mid 88.779644 -205.03204)
					(end 88.842342 -204.938122)
				)
				(arc
					(start 88.842342 -204.65415)
					(mid 88.813565 -204.583302)
					(end 88.743536 -204.55255)
				)
				(arc
					(start 88.743536 -204.55255)
					(mid 88.813592 -204.521824)
					(end 88.842342 -204.45095)
				)
				(xy 88.842342 -203.731368) (xy 84.209128 -199.098408)
				(arc
					(start 83.489546 -199.098408)
					(mid 83.395714 -199.161044)
					(end 83.417664 -199.271636)
				)
				(arc
					(start 83.417664 -199.271636)
					(mid 83.395676 -199.238774)
					(end 83.387946 -199.200008)
				)
			)
		)
		(polygon
			(pts
				(arc
					(start 36.552886 -142.550642)
					(mid 36.436993 -142.530889)
					(end 36.379912 -142.6337)
				)
				(arc
					(start 36.379912 -142.6337)
					(mid 36.3755 -142.793228)
					(end 36.328096 -142.945612)
				)
				(arc
					(start 36.328096 -142.945612)
					(mid 36.326588 -143.028073)
					(end 36.38677 -143.08455)
				)
				(arc
					(start 36.38677 -143.08455)
					(mid 36.572571 -143.190439)
					(end 36.707826 -143.356076)
				)
				(xy 36.711382 -143.362426)
				(arc
					(start 37.03701 -143.688054)
					(mid 37.147794 -143.71009)
					(end 37.210492 -143.616172)
				)
				(xy 37.210492 -143.208248)
			)
		)
		(polygon
			(pts
				(xy 28.575254 -123.000008)
				(arc
					(start 28.545028 -123.000008)
					(mid 28.498334 -123.031402)
					(end 28.509214 -123.086622)
				)
				(xy 32.892238 -127.469392)
				(arc
					(start 32.922464 -127.469392)
					(mid 32.969158 -127.437998)
					(end 32.958278 -127.382778)
				)
			)
		)
		(polygon
			(pts
				(arc
					(start 15.930626 -115.619022)
					(mid 15.893633 -115.526474)
					(end 15.795244 -115.510056)
				)
				(arc
					(start 15.795244 -115.510056)
					(mid 15.714429 -115.53299)
					(end 15.63116 -115.544092)
				)
				(xy 15.611856 -115.545108) (xy 15.201392 -115.955572)
				(arc
					(start 15.201392 -116.527072)
					(mid 15.264111 -116.620938)
					(end 15.374874 -116.598954)
				)
				(xy 15.995904 -115.977924)
				(arc
					(start 15.980918 -115.945666)
					(mid 15.932205 -115.785972)
					(end 15.930626 -115.619022)
				)
			)
		)
		(polygon
			(pts
				(xy 32.004 -112.522) (xy 31.115 -112.522) (xy 30.734 -112.903) (xy 30.734 -114.173) (xy 32.766 -116.205)
				(xy 34.417 -116.205) (xy 35.052 -115.57)
			)
		)
		(polygon
			(pts
				(arc
					(start 101.064568 -49.90084)
					(mid 101.00922 -49.889983)
					(end 100.977954 -49.936908)
				)
				(xy 100.977954 -100.3808) (xy 96.5454 -100.3808) (xy 92.470224 -104.455976) (xy 89.161874 -101.147372)
				(xy 88.778334 -101.530912) (xy 92.086684 -104.839516) (xy 91.7448 -105.1814) (xy 91.7448 -242.2398)
				(xy 90.9828 -242.2398) (xy 90.9574 -242.2144) (xy 88.4936 -242.2144) (xy 87.6554 -243.0526) (xy 87.6554 -243.3066)
				(xy 87.122 -243.84) (xy 85.979 -243.84) (xy 85.6234 -244.1956) (xy 85.6234 -267.843) (xy 88.7476 -270.9672)
				(xy 88.7476 -277.0378) (xy 86.4108 -277.0378) (xy 85.1408 -278.3078) (xy 85.217 -278.3078) (xy 85.217 -330.4032)
				(xy 82.8802 -330.4032) (xy 82.8802 -409.263342) (xy 45.757084 -446.386204)
				(arc
					(start 28.412694 -446.386204)
					(mid 28.317419 -446.452516)
					(end 28.3464 -446.56502)
				)
				(arc
					(start 28.3464 -446.56502)
					(mid 28.379105 -446.595439)
					(end 28.409392 -446.628266)
				)
				(xy 28.424632 -446.645792) (xy 45.658278 -446.645792) (xy 82.8802 -409.424124) (xy 82.8802 -410.123132)
				(arc
					(start 47.515018 -445.488314)
					(mid 47.492982 -445.599098)
					(end 47.5869 -445.661796)
				)
				(xy 47.624238 -445.661796) (xy 82.8802 -410.405834) (xy 82.8802 -433.9844) (xy 87.153496 -438.257696)
				(arc
					(start 76.617322 -448.79387)
					(mid 76.595286 -448.904654)
					(end 76.689204 -448.967352)
				)
				(xy 78.196186 -448.967352) (xy 88.029796 -439.133996) (xy 88.7984 -439.9026) (xy 90.5002 -439.9026)
				(xy 91.7448 -438.658) (xy 91.7448 -440.2836) (xy 93.2942 -441.833) (xy 99.9998 -441.833) (xy 102.5398 -439.293)
				(xy 102.5398 -101.2444) (xy 101.6762 -100.3808) (xy 101.110542 -100.3808) (xy 101.110542 -49.946814)
			)
		)
		(polygon
			(pts
				(arc
					(start 72.309482 -15.306548)
					(mid 72.198937 -15.284712)
					(end 72.136254 -15.37843)
				)
				(xy 72.136254 -18.421096) (xy 72.34555 -18.630392) (xy 72.592438 -18.630392) (xy 72.592438 -18.174208)
				(xy 73.025254 -17.741646)
				(arc
					(start 73.312782 -17.741646)
					(mid 73.406648 -17.678927)
					(end 73.384664 -17.568164)
				)
				(xy 72.973438 -17.157192) (xy 72.973438 -15.970504)
			)
		)
		(polygon
			(pts
				(arc
					(start 26.013664 -7.984236)
					(mid 26.0355 -7.873691)
					(end 25.941782 -7.811008)
				)
				(xy 25.653238 -7.811008)
				(arc
					(start 24.566372 -8.89762)
					(mid 24.536636 -8.972288)
					(end 24.570436 -9.045194)
				)
				(arc
					(start 24.570436 -9.045194)
					(mid 24.62398 -9.098948)
					(end 24.67102 -9.158478)
				)
				(arc
					(start 24.67102 -9.158478)
					(mid 24.745335 -9.201227)
					(end 24.82596 -9.17194)
				)
			)
		)
	)
	(zone
		(net "P5V_HDD12")
		(layer "In5.Cu")
		(hatch none 0.5)
		(connect_pads
			(clearance 0.5)
		)
		(min_thickness 0.25)
		(fill yes
			(thermal_gap 0.5)
			(thermal_bridge_width 0.5)
			(island_removal_mode 0)
		)
		(polygon
			(pts
				(xy 23.113746 -225.6917) (xy 23.113746 -223.7867) (xy 23.494746 -223.4057) (xy 36.829746 -223.4057)
				(xy 39.496746 -226.0727) (xy 42.036746 -226.0727) (xy 42.798746 -226.8347) (xy 42.798746 -228.3587)
				(xy 42.671746 -228.4857) (xy 38.734746 -228.4857) (xy 36.067746 -225.8187) (xy 23.240746 -225.8187)
			)
		)
	)
	(zone
		(net "P5V_HDD13")
		(layer "In5.Cu")
		(hatch none 0.5)
		(connect_pads
			(clearance 0.5)
		)
		(min_thickness 0.25)
		(fill yes
			(thermal_gap 0.5)
			(thermal_bridge_width 0.5)
			(island_removal_mode 0)
		)
		(polygon
			(pts
				(xy 23.113746 -122.5677) (xy 23.113746 -120.7897) (xy 23.367746 -120.5357) (xy 29.209746 -120.5357)
				(xy 33.527746 -124.8537) (xy 39.877746 -124.8537) (xy 41.147746 -126.1237) (xy 41.147746 -127.3937)
				(xy 40.258746 -128.2827) (xy 37.845746 -128.2827) (xy 36.829746 -127.2667) (xy 33.273746 -127.2667)
				(xy 28.701746 -122.6947) (xy 23.240746 -122.6947)
			)
		)
	)
	(zone
		(layer "In5.Cu")
		(hatch none 0.5)
		(connect_pads
			(clearance 0)
		)
		(min_thickness 0.25)
		(keepout
			(tracks not_allowed)
			(vias allowed)
			(pads allowed)
			(copperpour not_allowed)
			(footprints allowed)
		)
		(placement
			(enabled no)
			(sheetname "")
		)
		(fill
			(thermal_gap 0.5)
			(thermal_bridge_width 0.5)
			(island_removal_mode 0)
		)
		(polygon
			(pts
				(arc
					(start 32.190182 -273.691096)
					(mid 31.603569 -273.104102)
					(end 31.016702 -273.690842)
				)
				(arc
					(start 31.016702 -273.946112)
					(mid 31.053047 -273.95026)
					(end 31.0896 -273.9517)
				)
				(arc
					(start 31.0896 -273.9517)
					(mid 31.232911 -273.924491)
					(end 31.356554 -273.847052)
				)
				(arc
					(start 31.356554 -273.847052)
					(mid 31.810351 -273.48458)
					(end 31.44647 -273.937222)
				)
				(xy 31.439104 -273.944588)
				(arc
					(start 31.438342 -273.944588)
					(mid 31.276412 -274.044008)
					(end 31.0896 -274.0787)
				)
				(arc
					(start 31.0896 -274.0787)
					(mid 31.053087 -274.077618)
					(end 31.016702 -274.074382)
				)
				(arc
					(start 31.016702 -274.253198)
					(mid 31.052986 -274.255682)
					(end 31.089346 -274.2565)
				)
				(xy 31.116016 -274.2565)
				(arc
					(start 31.116524 -274.257008)
					(mid 31.288335 -274.291429)
					(end 31.442152 -274.375372)
				)
				(arc
					(start 31.442152 -274.375372)
					(mid 31.814213 -274.821256)
					(end 31.353506 -274.467828)
				)
				(arc
					(start 31.353506 -274.467828)
					(mid 31.228124 -274.405102)
					(end 31.0896 -274.3835)
				)
				(xy 31.06293 -274.3835) (xy 31.062676 -274.382992) (xy 31.016702 -274.380706)
				(arc
					(start 31.016702 -274.618958)
					(mid 31.603442 -275.205698)
					(end 32.190182 -274.618958)
				)
			)
		)
	)
	(zone
		(layer "In5.Cu")
		(hatch none 0.5)
		(connect_pads
			(clearance 0)
		)
		(min_thickness 0.25)
		(keepout
			(tracks not_allowed)
			(vias allowed)
			(pads allowed)
			(copperpour not_allowed)
			(footprints allowed)
		)
		(placement
			(enabled no)
			(sheetname "")
		)
		(fill
			(thermal_gap 0.5)
			(thermal_bridge_width 0.5)
			(island_removal_mode 0)
		)
		(polygon
			(pts
				(arc
					(start 32.463486 -161.429954)
					(mid 31.876873 -160.84296)
					(end 31.290006 -161.4297)
				)
				(xy 31.290006 -161.5694)
				(arc
					(start 31.445454 -161.5694)
					(mid 31.527398 -161.562391)
					(end 31.606998 -161.541714)
				)
				(arc
					(start 31.606998 -161.541714)
					(mid 32.114472 -161.260002)
					(end 31.683198 -161.648394)
				)
				(arc
					(start 31.683198 -161.648394)
					(mid 31.579639 -161.681506)
					(end 31.47187 -161.695892)
				)
				(xy 31.471362 -161.6964) (xy 31.290006 -161.6964) (xy 31.290006 -161.8742) (xy 31.471362 -161.8742)
				(arc
					(start 31.472886 -161.875724)
					(mid 31.53969 -161.892997)
					(end 31.599124 -161.928048)
				)
				(xy 31.60141 -161.928048)
				(arc
					(start 31.720028 -162.046666)
					(mid 32.083372 -162.499926)
					(end 31.630112 -162.136582)
				)
				(arc
					(start 31.530036 -162.036506)
					(mid 31.491011 -162.010367)
					(end 31.444946 -162.0012)
				)
				(xy 31.290006 -162.0012)
				(arc
					(start 31.290006 -162.2933)
					(mid 31.876746 -162.88004)
					(end 32.463486 -162.2933)
				)
			)
		)
	)
	(zone
		(layer "In5.Cu")
		(hatch none 0.5)
		(connect_pads
			(clearance 0)
		)
		(min_thickness 0.25)
		(keepout
			(tracks not_allowed)
			(vias allowed)
			(pads allowed)
			(copperpour not_allowed)
			(footprints allowed)
		)
		(placement
			(enabled no)
			(sheetname "")
		)
		(fill
			(thermal_gap 0.5)
			(thermal_bridge_width 0.5)
			(island_removal_mode 0)
		)
		(polygon
			(pts
				(arc
					(start 11.0744 -440.63666)
					(mid 10.48766 -441.2234)
					(end 11.0744 -441.81014)
				)
				(xy 11.937746 -441.81014)
				(arc
					(start 11.938 -441.81014)
					(mid 12.52474 -441.2234)
					(end 11.938 -440.63666)
				)
				(arc
					(start 11.625072 -440.63666)
					(mid 11.676775 -440.818877)
					(end 11.78179 -440.976512)
				)
				(arc
					(start 11.78179 -440.976512)
					(mid 12.144386 -441.430185)
					(end 11.691366 -441.066682)
				)
				(xy 11.691112 -441.066428)
				(arc
					(start 11.691112 -441.065666)
					(mid 11.559097 -440.867028)
					(end 11.49731 -440.63666)
				)
				(xy 11.3157 -440.63666) (xy 11.3157 -440.830716)
				(arc
					(start 11.315192 -440.831224)
					(mid 11.304409 -440.924832)
					(end 11.28014 -441.015882)
				)
				(arc
					(start 11.28014 -441.015882)
					(mid 10.921521 -441.472173)
					(end 11.168634 -440.947048)
				)
				(arc
					(start 11.168634 -440.947048)
					(mid 11.183661 -440.876375)
					(end 11.1887 -440.8043)
				)
				(xy 11.1887 -440.63666)
			)
		)
	)
	(zone
		(layer "In5.Cu")
		(hatch none 0.5)
		(connect_pads
			(clearance 0)
		)
		(min_thickness 0.25)
		(keepout
			(tracks not_allowed)
			(vias allowed)
			(pads allowed)
			(copperpour not_allowed)
			(footprints allowed)
		)
		(placement
			(enabled no)
			(sheetname "")
		)
		(fill
			(thermal_gap 0.5)
			(thermal_bridge_width 0.5)
			(island_removal_mode 0)
		)
		(polygon
			(pts
				(arc
					(start 37.223192 -163.920678)
					(mid 36.636579 -163.333684)
					(end 36.049712 -163.920424)
				)
				(xy 36.049712 -164.1094)
				(arc
					(start 36.383976 -164.1094)
					(mid 36.397983 -164.108899)
					(end 36.411916 -164.107368)
				)
				(arc
					(start 36.411916 -164.107368)
					(mid 36.803463 -163.680691)
					(end 36.538916 -164.19576)
				)
				(arc
					(start 36.538916 -164.19576)
					(mid 36.477268 -164.222273)
					(end 36.411408 -164.23513)
				)
				(xy 36.410392 -164.2364) (xy 36.049712 -164.2364) (xy 36.049712 -164.4142) (xy 36.261294 -164.4142)
				(arc
					(start 36.262056 -164.414962)
					(mid 36.449088 -164.466432)
					(end 36.59886 -164.589714)
				)
				(arc
					(start 36.59886 -164.589714)
					(mid 36.739885 -165.152199)
					(end 36.47186 -164.637974)
				)
				(arc
					(start 36.47186 -164.637974)
					(mid 36.362879 -164.56631)
					(end 36.234878 -164.5412)
				)
				(xy 36.049712 -164.5412)
				(arc
					(start 36.049712 -164.879274)
					(mid 36.636452 -165.466014)
					(end 37.223192 -164.879274)
				)
			)
		)
	)
	(zone
		(net "12V_PRE_12")
		(layer "In5.Cu")
		(hatch none 0.5)
		(connect_pads
			(clearance 0.5)
		)
		(min_thickness 0.25)
		(fill yes
			(thermal_gap 0.5)
			(thermal_bridge_width 0.5)
			(island_removal_mode 0)
		)
		(polygon
			(pts
				(xy 23.113746 -218.3257) (xy 35.686746 -218.3257) (xy 37.845746 -220.4847) (xy 40.766746 -220.4847)
				(xy 41.147746 -220.8657) (xy 41.147746 -222.5167) (xy 40.385746 -223.2787) (xy 38.480746 -223.2787)
				(xy 34.670746 -219.4687) (xy 23.113746 -219.4687) (xy 22.859746 -219.2147) (xy 22.859746 -218.5797)
			)
		)
	)
	(zone
		(layer "In5.Cu")
		(hatch none 0.5)
		(connect_pads
			(clearance 0)
		)
		(min_thickness 0.25)
		(keepout
			(tracks not_allowed)
			(vias allowed)
			(pads allowed)
			(copperpour not_allowed)
			(footprints allowed)
		)
		(placement
			(enabled no)
			(sheetname "")
		)
		(fill
			(thermal_gap 0.5)
			(thermal_bridge_width 0.5)
			(island_removal_mode 0)
		)
		(polygon
			(pts
				(arc
					(start 13.388086 -176.752504)
					(mid 12.823063 -176.149766)
					(end 12.220194 -176.714658)
				)
				(arc
					(start 12.192254 -177.578004)
					(mid 12.757404 -178.180746)
					(end 13.360146 -177.615596)
				)
				(arc
					(start 13.367512 -177.384964)
					(mid 13.201074 -177.416732)
					(end 13.043662 -177.479452)
				)
				(arc
					(start 13.043662 -177.479452)
					(mid 12.541082 -177.77008)
					(end 12.967462 -177.376074)
				)
				(arc
					(start 12.967462 -177.376074)
					(mid 13.163418 -177.295456)
					(end 13.37183 -177.257202)
				)
				(arc
					(start 13.377672 -177.071274)
					(mid 13.180732 -177.031681)
					(end 12.995402 -176.95418)
				)
				(arc
					(start 12.995402 -176.95418)
					(mid 12.56903 -176.560179)
					(end 13.071602 -176.850802)
				)
				(arc
					(start 13.071602 -176.850802)
					(mid 13.222515 -176.911671)
					(end 13.38199 -176.94402)
				)
			)
		)
	)
	(zone
		(layer "In5.Cu")
		(hatch none 0.5)
		(connect_pads
			(clearance 0)
		)
		(min_thickness 0.25)
		(keepout
			(tracks not_allowed)
			(vias allowed)
			(pads allowed)
			(copperpour not_allowed)
			(footprints allowed)
		)
		(placement
			(enabled no)
			(sheetname "")
		)
		(fill
			(thermal_gap 0.5)
			(thermal_bridge_width 0.5)
			(island_removal_mode 0)
		)
		(polygon
			(pts
				(arc
					(start 22.085808 -135.871204)
					(mid 22.149477 -135.833517)
					(end 22.22119 -135.815324)
				)
				(xy 22.22246 -135.8138) (xy 22.481286 -135.8138) (xy 22.481286 -135.636) (xy 22.077426 -135.636)
				(arc
					(start 22.07641 -135.63473)
					(mid 21.980067 -135.611279)
					(end 21.895308 -135.5598)
				)
				(xy 21.89353 -135.5598) (xy 21.874988 -135.541258) (xy 21.831046 -135.497316) (xy 21.831046 -135.49503)
				(arc
					(start 21.81479 -135.472424)
					(mid 21.888841 -134.89953)
					(end 21.985224 -135.469122)
				)
				(arc
					(start 21.985224 -135.469122)
					(mid 22.041279 -135.498728)
					(end 22.103842 -135.509)
				)
				(xy 22.481286 -135.509)
				(arc
					(start 22.481286 -135.191754)
					(mid 21.894673 -134.60476)
					(end 21.307806 -135.1915)
				)
				(arc
					(start 21.307806 -136.15035)
					(mid 21.894546 -136.73709)
					(end 22.481286 -136.15035)
				)
				(xy 22.481286 -135.9408)
				(arc
					(start 22.248622 -135.9408)
					(mid 22.197922 -135.95096)
					(end 22.154896 -135.979662)
				)
				(arc
					(start 22.140926 -135.993378)
					(mid 21.688175 -136.357121)
					(end 22.05101 -135.903716)
				)
				(xy 22.06498 -135.889746) (xy 22.083522 -135.871204)
			)
		)
	)
	(zone
		(layer "In5.Cu")
		(hatch none 0.5)
		(connect_pads
			(clearance 0)
		)
		(min_thickness 0.25)
		(keepout
			(tracks not_allowed)
			(vias allowed)
			(pads allowed)
			(copperpour not_allowed)
			(footprints allowed)
		)
		(placement
			(enabled no)
			(sheetname "")
		)
		(fill
			(thermal_gap 0.5)
			(thermal_bridge_width 0.5)
			(island_removal_mode 0)
		)
		(polygon
			(pts
				(arc
					(start 16.945102 -119.646954)
					(mid 16.359505 -119.059198)
					(end 15.771622 -119.644668)
				)
				(arc
					(start 15.770098 -120.508268)
					(mid 16.355822 -121.096024)
					(end 16.943578 -120.5103)
				)
				(xy 16.943578 -120.509284) (xy 16.943578 -120.508268) (xy 16.944086 -120.226328)
				(arc
					(start 16.894556 -120.226328)
					(mid 16.750392 -120.254986)
					(end 16.62811 -120.336564)
				)
				(arc
					(start 16.606774 -120.358154)
					(mid 16.150309 -120.715813)
					(end 16.507968 -120.259348)
				)
				(xy 16.549878 -120.217438)
				(arc
					(start 16.551148 -120.217438)
					(mid 16.697011 -120.125937)
					(end 16.864838 -120.08739)
				)
				(xy 16.8656 -120.086628) (xy 16.94434 -120.086628) (xy 16.944594 -119.921528) (xy 16.826738 -119.921528)
				(arc
					(start 16.82623 -119.92102)
					(mid 16.688262 -119.903283)
					(end 16.55572 -119.861076)
				)
				(arc
					(start 16.55572 -119.861076)
					(mid 16.114388 -119.484996)
					(end 16.634206 -119.74195)
				)
				(arc
					(start 16.634206 -119.74195)
					(mid 16.743165 -119.771808)
					(end 16.855694 -119.781828)
				)
				(xy 16.944848 -119.781828)
			)
		)
	)
	(zone
		(layer "In5.Cu")
		(hatch none 0.5)
		(connect_pads
			(clearance 0)
		)
		(min_thickness 0.25)
		(keepout
			(tracks not_allowed)
			(vias allowed)
			(pads allowed)
			(copperpour not_allowed)
			(footprints allowed)
		)
		(placement
			(enabled no)
			(sheetname "")
		)
		(fill
			(thermal_gap 0.5)
			(thermal_bridge_width 0.5)
			(island_removal_mode 0)
		)
		(polygon
			(pts
				(arc
					(start 15.827502 -135.675116)
					(mid 15.241651 -135.087614)
					(end 14.654022 -135.673338)
				)
				(arc
					(start 14.653006 -136.536938)
					(mid 15.238984 -137.12444)
					(end 15.826486 -136.538462)
				)
				(xy 15.826486 -136.5377) (xy 15.826486 -136.536938) (xy 15.82674 -136.305036)
				(arc
					(start 15.772638 -136.305036)
					(mid 15.625931 -136.326778)
					(end 15.491714 -136.389872)
				)
				(arc
					(start 15.491714 -136.389872)
					(mid 15.027023 -136.737776)
					(end 15.40383 -136.296146)
				)
				(arc
					(start 15.40383 -136.296146)
					(mid 15.566489 -136.212495)
					(end 15.746222 -136.178544)
				)
				(xy 15.74673 -136.178036) (xy 15.826994 -136.178036) (xy 15.826994 -136.000236) (xy 15.82293 -136.000236)
				(arc
					(start 15.822676 -135.999728)
					(mid 15.620573 -135.97058)
					(end 15.430246 -135.896604)
				)
				(arc
					(start 15.430246 -135.896604)
					(mid 15.006384 -135.499478)
					(end 15.507462 -135.793226)
				)
				(arc
					(start 15.507462 -135.793226)
					(mid 15.663046 -135.850386)
					(end 15.827248 -135.872982)
				)
			)
		)
	)
	(zone
		(net "P5V_HDD14")
		(layer "In5.Cu")
		(hatch none 0.5)
		(connect_pads
			(clearance 0.5)
		)
		(min_thickness 0.25)
		(fill yes
			(thermal_gap 0.5)
			(thermal_bridge_width 0.5)
			(island_removal_mode 0)
		)
		(polygon
			(pts
				(xy 35.940746 -4.7117) (xy 34.924746 -5.7277) (xy 34.289746 -6.3627) (xy 24.129746 -6.3627) (xy 24.123396 -6.368796)
				(xy 22.612604 -6.368796) (xy 18.160746 -10.820654) (xy 18.160746 -12.3317) (xy 18.160746 -19.3167)
				(xy 18.414746 -19.5707) (xy 20.700746 -19.5707) (xy 21.462746 -18.8087) (xy 21.462746 -17.4117)
				(xy 21.208746 -17.1577) (xy 20.446746 -16.3957) (xy 20.446746 -12.5857) (xy 20.446746 -11.735054)
				(xy 22.7584 -9.4234) (xy 34.277046 -9.4234) (xy 34.296096 -9.404096) (xy 34.893504 -9.404096) (xy 37.4269 -6.8707)
				(xy 65.658746 -6.8707) (xy 72.770746 -13.9827) (xy 72.770746 -15.2527) (xy 72.770746 -16.5227) (xy 73.278746 -17.0307)
				(xy 73.786746 -17.5387) (xy 75.691746 -17.5387) (xy 76.580746 -18.4277) (xy 76.580746 -20.7137)
				(xy 76.961746 -21.0947) (xy 80.390746 -21.0947) (xy 80.517746 -20.9677) (xy 80.517746 -17.9197)
				(xy 80.517746 -16.7767) (xy 78.993746 -15.2527) (xy 77.596746 -15.2527) (xy 67.055746 -4.7117)
			)
		)
	)
	(zone
		(net "5V_PRE_13")
		(layer "In5.Cu")
		(hatch none 0.5)
		(connect_pads
			(clearance 0.5)
		)
		(min_thickness 0.25)
		(fill yes
			(thermal_gap 0.5)
			(thermal_bridge_width 0.5)
			(island_removal_mode 0)
		)
		(polygon
			(pts
				(xy 23.494746 -124.0917) (xy 23.494746 -123.4567) (xy 23.748746 -123.2027) (xy 28.193746 -123.2027)
				(xy 32.765746 -127.7747) (xy 36.702746 -127.7747) (xy 37.845746 -128.9177) (xy 37.845746 -130.4417)
				(xy 37.591746 -130.6957) (xy 34.289746 -130.6957) (xy 33.146746 -130.6957) (xy 31.622746 -129.1717)
				(xy 27.285696 -124.834904) (xy 23.819104 -124.834904) (xy 23.494746 -124.510546)
			)
		)
	)
	(zone
		(net "P12V_HDD13")
		(layer "In5.Cu")
		(hatch none 0.5)
		(connect_pads
			(clearance 0.5)
		)
		(min_thickness 0.25)
		(fill yes
			(thermal_gap 0.5)
			(thermal_bridge_width 0.5)
			(island_removal_mode 0)
		)
		(polygon
			(pts
				(xy 22.479 -115.062) (xy 22.479 -113.03) (xy 22.733 -112.776) (xy 30.734 -112.776) (xy 30.988 -112.776)
				(xy 30.988 -112.7887) (xy 34.417 -116.2177) (xy 40.004746 -116.2177) (xy 40.023796 -116.237004)
				(xy 41.586404 -116.237004) (xy 44.069 -118.7196) (xy 44.069 -121.3358) (xy 43.5991 -121.8057) (xy 40.258746 -121.8057)
				(xy 38.988746 -121.8057) (xy 36.067746 -118.8847) (xy 35.686746 -118.8847) (xy 32.892746 -118.8847)
				(xy 32.638746 -118.8847) (xy 29.590746 -115.8367) (xy 29.336746 -115.5827) (xy 29.209746 -115.4557)
				(xy 22.8727 -115.4557)
			)
		)
	)
	(zone
		(net "5V_PRE_14")
		(layer "In5.Cu")
		(hatch none 0.5)
		(connect_pads
			(clearance 0.5)
		)
		(min_thickness 0.25)
		(fill yes
			(thermal_gap 0.5)
			(thermal_bridge_width 0.5)
			(island_removal_mode 0)
		)
		(polygon
			(pts
				(xy 25.336246 -10.9982) (xy 25.336246 -16.0147) (xy 25.304496 -16.04645) (xy 21.272246 -20.0787)
				(xy 18.160746 -20.0787) (xy 18.033746 -20.2057) (xy 18.033746 -21.8567) (xy 18.160746 -21.9837)
				(xy 22.351746 -21.9837) (xy 26.542746 -17.7927) (xy 27.431746 -16.9037) (xy 27.431746 -13.6652)
				(xy 27.432 -13.6652) (xy 27.9654 -13.1318) (xy 36.7792 -13.1318) (xy 40.7543 -9.1567) (xy 64.134746 -9.1567)
				(xy 70.738746 -15.7607) (xy 70.738746 -18.8087) (xy 70.738746 -19.8247) (xy 70.802246 -19.8882)
				(xy 72.008746 -21.0947) (xy 73.278746 -21.0947) (xy 75.564746 -21.0947) (xy 75.691746 -20.9677)
				(xy 75.691746 -18.4277) (xy 75.310746 -18.0467) (xy 74.167746 -18.0467) (xy 74.040746 -17.9197)
				(xy 73.151746 -17.9197) (xy 72.389746 -17.1577) (xy 72.389746 -14.1097) (xy 65.404746 -7.1247) (xy 37.9476 -7.1247)
				(xy 35.1155 -9.9568) (xy 26.1366 -9.9568) (xy 25.336246 -10.757154)
			)
		)
	)
	(zone
		(net "12V_PRE_13")
		(layer "In5.Cu")
		(hatch none 0.5)
		(connect_pads
			(clearance 0.5)
		)
		(min_thickness 0.25)
		(fill yes
			(thermal_gap 0.5)
			(thermal_bridge_width 0.5)
			(island_removal_mode 0)
		)
		(polygon
			(pts
				(xy 23.621746 -117.6147) (xy 23.621746 -116.0907) (xy 23.748746 -115.9637) (xy 29.082746 -115.9637)
				(xy 32.384746 -119.2657) (xy 36.067746 -119.2657) (xy 36.194746 -119.3927) (xy 36.194746 -122.3137)
				(xy 36.067746 -122.4407) (xy 33.654746 -122.4407) (xy 32.5374 -122.4407) (xy 27.9654 -117.8687)
				(xy 23.875746 -117.8687)
			)
		)
	)
	(zone
		(net "5V_PRE_12")
		(layer "In5.Cu")
		(hatch none 0.5)
		(connect_pads
			(clearance 0.5)
		)
		(min_thickness 0.25)
		(fill yes
			(thermal_gap 0.5)
			(thermal_bridge_width 0.5)
			(island_removal_mode 0)
		)
		(polygon
			(pts
				(xy 23.240746 -226.9617) (xy 23.240746 -226.1997) (xy 23.367746 -226.0727) (xy 35.432746 -226.0727)
				(xy 38.480746 -229.1207) (xy 40.385746 -229.1207) (xy 41.147746 -229.8827) (xy 41.147746 -231.5337)
				(xy 40.893746 -231.7877) (xy 39.242746 -231.7877) (xy 34.670746 -227.2157) (xy 23.494746 -227.2157)
			)
		)
	)
	(zone
		(net "GND")
		(layer "In6.Cu")
		(hatch none 0.5)
		(connect_pads
			(clearance 0.5)
		)
		(min_thickness 0.25)
		(fill yes
			(thermal_gap 0.5)
			(thermal_bridge_width 0.5)
			(island_removal_mode 0)
		)
		(polygon
			(pts
				(arc
					(start 0.999998 -0.763016)
					(mid 0.832426 -0.832426)
					(end 0.763016 -0.999998)
				)
				(xy 0.763016 -53.433726) (xy 0.816356 -53.487066)
				(arc
					(start 5.050028 -53.487066)
					(mid 6.763004 -55.200042)
					(end 5.050028 -56.913018)
				)
				(xy 0.816102 -56.913018) (xy 0.763016 -56.966104) (xy 0.763016 -104.233726) (xy 0.816356 -104.287066)
				(xy 1.388872 -104.287066) (xy 1.388872 -104.144064) (xy 4.995672 -104.144064) (xy 4.995672 -104.287066)
				(arc
					(start 5.050028 -104.287066)
					(mid 6.574439 -105.218724)
					(end 6.440678 -107.000294)
				)
				(arc
					(start 6.440678 -107.000294)
					(mid 7.003377 -107.018543)
					(end 7.291578 -107.502198)
				)
				(xy 7.294118 -107.502198) (xy 7.325868 -108.36529)
				(arc
					(start 7.323328 -108.36529)
					(mid 6.758686 -108.973112)
					(end 6.150864 -108.40847)
				)
				(xy 6.148578 -108.40847) (xy 6.148324 -108.408216) (xy 6.116574 -107.545378)
				(arc
					(start 6.119114 -107.545378)
					(mid 6.127653 -107.422093)
					(end 6.161786 -107.303316)
				)
				(arc
					(start 6.161786 -107.303316)
					(mid 5.642464 -107.607384)
					(end 5.050028 -107.713018)
				)
				(xy 0.816102 -107.713018) (xy 0.763016 -107.766104) (xy 0.763016 -208.233772) (xy 0.816102 -208.286858)
				(arc
					(start 5.050028 -208.286858)
					(mid 6.763258 -210.000088)
					(end 5.050028 -211.713064)
				)
				(xy 0.816102 -211.713064) (xy 0.763016 -211.76615) (xy 0.763016 -303.433734) (xy 0.816356 -303.487074)
				(arc
					(start 5.050028 -303.487074)
					(mid 6.763004 -305.20005)
					(end 5.050028 -306.913026)
				)
				(xy 0.816102 -306.913026) (xy 0.763016 -306.966112) (xy 0.763016 -354.233734) (xy 0.816356 -354.287074)
				(xy 1.388872 -354.287074) (xy 1.388872 -354.144072) (xy 4.995672 -354.144072) (xy 4.995672 -354.287074)
				(arc
					(start 5.050028 -354.287074)
					(mid 6.763004 -356.00005)
					(end 5.050028 -357.713026)
				)
				(xy 0.816102 -357.713026) (xy 0.763016 -357.766112) (xy 0.763016 -458.23378) (xy 0.816102 -458.286866)
				(arc
					(start 5.050028 -458.286866)
					(mid 6.763258 -460.000096)
					(end 5.050028 -461.713072)
				)
				(xy 0.816102 -461.713072) (xy 0.763016 -461.766158)
				(arc
					(start 0.763016 -505.000006)
					(mid 0.832426 -505.167578)
					(end 0.999998 -505.236988)
				)
				(arc
					(start 261.500112 -505.236988)
					(mid 261.667684 -505.167578)
					(end 261.737094 -505.000006)
				)
				(xy 261.737094 -428.396146) (xy 261.183882 -427.842934)
				(arc
					(start 260.149594 -427.842934)
					(mid 258.726388 -427.253265)
					(end 258.136898 -425.829984)
				)
				(xy 258.136898 -411.80131) (xy 257.583686 -411.248098)
				(arc
					(start 251.394976 -411.248098)
					(mid 250.097036 -409.950158)
					(end 251.394976 -408.651964)
				)
				(xy 257.583686 -408.651964) (xy 258.136898 -408.098752)
				(arc
					(start 258.136898 -364.16996)
					(mid 258.726388 -362.746679)
					(end 260.149594 -362.15701)
				)
				(xy 261.183882 -362.15701) (xy 261.737094 -361.603798)
				(arc
					(start 261.737094 -0.999998)
					(mid 261.667684 -0.832426)
					(end 261.500112 -0.763016)
				)
			)
		)
		(polygon
			(pts
				(arc
					(start 216.792048 -475.829884)
					(mid 217.375485 -475.239715)
					(end 216.78519 -474.656404)
				)
				(arc
					(start 215.92159 -474.661484)
					(mid 215.338406 -475.25178)
					(end 215.928702 -475.834964)
				)
			)
		)
		(polygon
			(pts
				(arc
					(start 31.927546 -475.163896)
					(mid 31.307532 -474.612462)
					(end 30.756098 -475.232476)
				)
				(xy 30.753558 -475.23273) (xy 30.804104 -476.09506)
				(arc
					(start 30.806644 -476.094806)
					(mid 31.426658 -476.64624)
					(end 31.978092 -476.026226)
				)
				(xy 31.980632 -476.025972) (xy 31.930086 -475.163896) (xy 31.929832 -475.163642)
			)
		)
		(polygon
			(pts
				(arc
					(start 220.782896 -472.907106)
					(mid 220.196029 -472.32062)
					(end 219.609416 -472.90736)
				)
				(arc
					(start 219.609416 -473.86621)
					(mid 220.196156 -474.45295)
					(end 220.782896 -473.86621)
				)
			)
		)
		(polygon
			(pts
				(arc
					(start 35.638486 -472.819984)
					(mid 35.051619 -472.233498)
					(end 34.465006 -472.820238)
				)
				(arc
					(start 34.465006 -473.748354)
					(mid 35.051746 -474.335094)
					(end 35.638486 -473.748354)
				)
			)
		)
		(polygon
			(pts
				(arc
					(start 22.225508 -444.181992)
					(mid 21.613876 -443.62116)
					(end 21.053044 -444.232792)
				)
				(arc
					(start 21.090382 -445.095376)
					(mid 21.701887 -445.656457)
					(end 22.262846 -445.04483)
				)
			)
		)
		(polygon
			(pts
				(arc
					(start 28.373832 -441.830968)
					(mid 27.772614 -441.259214)
					(end 27.20086 -441.860432)
				)
				(xy 27.19832 -441.860432) (xy 27.22372 -442.876178) (xy 27.223974 -442.876432)
				(arc
					(start 27.22626 -442.876432)
					(mid 27.827478 -443.448186)
					(end 28.399232 -442.846968)
				)
				(xy 28.401772 -442.846968) (xy 28.376372 -441.830968)
			)
		)
		(polygon
			(pts
				(arc
					(start 11.938 -441.81014)
					(mid 12.52474 -441.2234)
					(end 11.938 -440.63666)
				)
				(arc
					(start 11.0744 -440.63666)
					(mid 10.48766 -441.2234)
					(end 11.0744 -441.81014)
				)
			)
		)
		(polygon
			(pts
				(arc
					(start 12.239498 -438.105042)
					(mid 11.652758 -437.518302)
					(end 11.066018 -438.105042)
				)
				(arc
					(start 11.066018 -439.033412)
					(mid 11.652885 -439.619898)
					(end 12.239498 -439.033158)
				)
			)
		)
		(polygon
			(pts
				(xy 7.423912 -423.515536)
				(arc
					(start 7.423658 -423.518076)
					(mid 6.856476 -424.020742)
					(end 7.359142 -424.587924)
				)
				(xy 7.358888 -424.590464) (xy 8.22071 -424.642788) (xy 8.220964 -424.642534)
				(arc
					(start 8.221218 -424.640248)
					(mid 8.7884 -424.137582)
					(end 8.285734 -423.5704)
				)
				(xy 8.285988 -423.56786)
			)
		)
		(polygon
			(pts
				(xy 4.995672 -422.144444) (xy 1.388872 -422.144444) (xy 1.388872 -422.855644) (xy 4.995672 -422.855644)
			)
		)
		(polygon
			(pts
				(xy 8.142224 -421.362632) (xy 7.278878 -421.34028)
				(arc
					(start 7.278878 -421.34282)
					(mid 6.703314 -421.889428)
					(end 7.249922 -422.464992)
				)
				(xy 7.249922 -422.467532) (xy 8.113014 -422.489884) (xy 8.113268 -422.48963)
				(arc
					(start 8.113268 -422.487344)
					(mid 8.688832 -421.940736)
					(end 8.142224 -421.365172)
				)
			)
		)
		(polygon
			(pts
				(xy 4.995672 -421.144446) (xy 1.388872 -421.144446) (xy 1.388872 -421.855646) (xy 4.995672 -421.855646)
			)
		)
		(polygon
			(pts
				(xy 4.995672 -418.144452) (xy 1.388872 -418.144452) (xy 1.388872 -418.855652) (xy 4.995672 -418.855652)
			)
		)
		(polygon
			(pts
				(arc
					(start 7.53364 -417.243768)
					(mid 6.93852 -417.821999)
					(end 7.516622 -418.417248)
				)
				(arc
					(start 8.380222 -418.429694)
					(mid 8.975344 -417.851336)
					(end 8.396986 -417.256214)
				)
			)
		)
		(polygon
			(pts
				(xy 4.995672 -417.144454) (xy 1.388872 -417.144454) (xy 1.388872 -417.855654) (xy 4.995672 -417.855654)
			)
		)
		(polygon
			(pts
				(xy 4.995672 -414.14446) (xy 1.388872 -414.14446) (xy 1.388872 -414.85566) (xy 4.995672 -414.85566)
			)
		)
		(polygon
			(pts
				(xy 4.995672 -413.144462) (xy 1.388872 -413.144462) (xy 1.388872 -413.855662) (xy 4.995672 -413.855662)
			)
		)
		(polygon
			(pts
				(arc
					(start 8.581898 -414.041336)
					(mid 8.779764 -413.272478)
					(end 8.010906 -413.074612)
				)
				(arc
					(start 7.215886 -413.544512)
					(mid 7.007016 -414.313851)
					(end 7.778242 -414.516062)
				)
			)
		)
		(polygon
			(pts
				(xy 4.995672 -410.144468) (xy 1.388872 -410.144468) (xy 1.388872 -410.855668) (xy 4.995672 -410.855668)
			)
		)
		(polygon
			(pts
				(arc
					(start 8.203946 -410.396436)
					(mid 8.765286 -409.835096)
					(end 8.203946 -409.273756)
				)
				(arc
					(start 7.340346 -409.273756)
					(mid 6.779006 -409.835096)
					(end 7.340346 -410.396436)
				)
			)
		)
		(polygon
			(pts
				(xy 4.995672 -409.14447) (xy 1.388872 -409.14447) (xy 1.388872 -409.85567) (xy 4.995672 -409.85567)
			)
		)
		(polygon
			(pts
				(xy 4.995672 -406.144476) (xy 1.388872 -406.144476) (xy 1.388872 -406.855676) (xy 4.995672 -406.855676)
			)
		)
		(polygon
			(pts
				(xy 4.995672 -405.144478) (xy 1.388872 -405.144478) (xy 1.388872 -405.855678) (xy 4.995672 -405.855678)
			)
		)
		(polygon
			(pts
				(arc
					(start 7.77875 -399.884138)
					(mid 8.335766 -399.273649)
					(end 7.725156 -398.716754)
				)
				(arc
					(start 6.862318 -398.756378)
					(mid 6.30555 -399.366994)
					(end 6.916166 -399.923762)
				)
			)
		)
		(polygon
			(pts
				(xy 4.995672 -398.144492) (xy 1.388872 -398.144492) (xy 1.388872 -398.855692) (xy 4.995672 -398.855692)
			)
		)
		(polygon
			(pts
				(xy 4.995672 -397.144494) (xy 1.388872 -397.144494) (xy 1.388872 -397.855694) (xy 4.995672 -397.855694)
			)
		)
		(polygon
			(pts
				(arc
					(start 8.689086 -385.53263)
					(mid 8.127619 -384.971544)
					(end 7.566406 -385.532884)
				)
				(arc
					(start 7.566406 -386.461)
					(mid 8.127746 -387.02234)
					(end 8.689086 -386.461)
				)
			)
		)
		(polygon
			(pts
				(xy 4.995672 -384.14452) (xy 1.388872 -384.14452) (xy 1.388872 -384.85572) (xy 4.995672 -384.85572)
			)
		)
		(polygon
			(pts
				(arc
					(start 7.675626 -383.436368)
					(mid 7.063238 -383.996311)
					(end 7.623048 -384.608832)
				)
				(arc
					(start 8.485886 -384.647186)
					(mid 9.09828 -384.087116)
					(end 8.53821 -383.474722)
				)
			)
		)
		(polygon
			(pts
				(xy 4.995672 -383.144522) (xy 1.388872 -383.144522) (xy 1.388872 -383.855722) (xy 4.995672 -383.855722)
			)
		)
		(polygon
			(pts
				(xy 4.995672 -380.144528) (xy 1.388872 -380.144528) (xy 1.388872 -380.855728) (xy 4.995672 -380.855728)
			)
		)
		(polygon
			(pts
				(arc
					(start 8.661146 -380.96444)
					(mid 9.247886 -380.3777)
					(end 8.661146 -379.79096)
				)
				(arc
					(start 7.746746 -379.79096)
					(mid 7.160006 -380.3777)
					(end 7.746746 -380.96444)
				)
			)
		)
		(polygon
			(pts
				(xy 4.995672 -379.14453) (xy 1.388872 -379.14453) (xy 1.388872 -379.85573) (xy 4.995672 -379.85573)
			)
		)
		(polygon
			(pts
				(xy 4.995672 -376.144536) (xy 1.388872 -376.144536) (xy 1.388872 -376.855736) (xy 4.995672 -376.855736)
			)
		)
		(polygon
			(pts
				(arc
					(start 8.810498 -376.880374)
					(mid 9.287002 -376.291094)
					(end 8.697722 -375.81459)
				)
				(xy 8.697468 -375.81205) (xy 7.817104 -375.905268)
				(arc
					(start 7.817358 -375.907808)
					(mid 7.340854 -376.497088)
					(end 7.930134 -376.973592)
				)
				(xy 7.930388 -376.976132) (xy 8.810498 -376.882914) (xy 8.810752 -376.88266)
			)
		)
		(polygon
			(pts
				(xy 4.995672 -375.144538) (xy 1.388872 -375.144538) (xy 1.388872 -375.855738) (xy 4.995672 -375.855738)
			)
		)
		(polygon
			(pts
				(xy 4.995672 -372.144544) (xy 1.388872 -372.144544) (xy 1.388872 -372.855744) (xy 4.995672 -372.855744)
			)
		)
		(polygon
			(pts
				(arc
					(start 216.490804 -373.038624)
					(mid 217.067892 -372.442232)
					(end 216.4715 -371.865144)
				)
				(arc
					(start 215.608154 -371.879368)
					(mid 215.031064 -372.475633)
					(end 215.627204 -373.052848)
				)
			)
		)
		(polygon
			(pts
				(arc
					(start 31.979616 -372.061486)
					(mid 31.386018 -371.590316)
					(end 30.914848 -372.183914)
				)
				(xy 30.912308 -372.184168) (xy 31.034736 -373.248428) (xy 31.03499 -373.248682)
				(arc
					(start 31.037276 -373.248428)
					(mid 31.630874 -373.719598)
					(end 32.102044 -373.126)
				)
				(xy 32.104584 -373.125746) (xy 31.982156 -372.061232)
			)
		)
		(polygon
			(pts
				(xy 4.995672 -371.144546) (xy 1.388872 -371.144546) (xy 1.388872 -371.855746) (xy 4.995672 -371.855746)
			)
		)
		(polygon
			(pts
				(arc
					(start 7.74319 -370.89334)
					(mid 7.13004 -371.452521)
					(end 7.689088 -372.065804)
				)
				(arc
					(start 8.587486 -372.107206)
					(mid 9.200642 -371.547898)
					(end 8.641334 -370.934742)
				)
			)
		)
		(polygon
			(pts
				(arc
					(start 223.61144 -369.971574)
					(mid 223.058863 -369.352569)
					(end 222.439992 -369.90528)
				)
				(xy 222.437452 -369.905026) (xy 222.386398 -370.80444)
				(arc
					(start 222.388938 -370.804694)
					(mid 222.941642 -371.423438)
					(end 223.560386 -370.870734)
				)
				(xy 223.562926 -370.870988) (xy 223.61398 -369.971828) (xy 223.613726 -369.971574)
			)
		)
		(polygon
			(pts
				(arc
					(start 36.908232 -369.934744)
					(mid 36.337748 -369.332256)
					(end 35.73526 -369.90274)
				)
				(xy 35.73272 -369.90274) (xy 35.707574 -370.823998)
				(arc
					(start 35.710114 -370.823998)
					(mid 36.280598 -371.426486)
					(end 36.883086 -370.856002)
				)
				(xy 36.885626 -370.856002) (xy 36.910772 -369.934998) (xy 36.910518 -369.934744)
			)
		)
		(polygon
			(pts
				(xy 4.995672 -368.144552) (xy 1.388872 -368.144552) (xy 1.388872 -368.855752) (xy 4.995672 -368.855752)
			)
		)
		(polygon
			(pts
				(arc
					(start 7.312914 -367.331752)
					(mid 6.753606 -367.843308)
					(end 7.265162 -368.402616)
				)
				(arc
					(start 8.127746 -368.441224)
					(mid 8.687314 -367.929795)
					(end 8.175752 -367.37036)
				)
			)
		)
		(polygon
			(pts
				(xy 4.995672 -367.144554) (xy 1.388872 -367.144554) (xy 1.388872 -367.855754) (xy 4.995672 -367.855754)
			)
		)
		(polygon
			(pts
				(arc
					(start 27.24023 -365.912654)
					(mid 26.644981 -365.334548)
					(end 26.06675 -365.929672)
				)
				(arc
					(start 26.083006 -367.02365)
					(mid 26.678382 -367.601754)
					(end 27.256486 -367.006378)
				)
			)
		)
		(polygon
			(pts
				(xy 4.995672 -364.14456) (xy 1.388872 -364.14456) (xy 1.388872 -364.85576) (xy 4.995672 -364.85576)
			)
		)
		(polygon
			(pts
				(arc
					(start 8.804148 -364.27283)
					(mid 8.889746 -363.447584)
					(end 8.0645 -363.361986)
				)
				(xy 8.062976 -363.359954) (xy 7.375398 -363.918246)
				(arc
					(start 7.376922 -363.920278)
					(mid 7.291324 -364.745524)
					(end 8.11657 -364.831122)
				)
				(xy 8.118094 -364.833154) (xy 8.805672 -364.275116) (xy 8.805672 -364.274608)
			)
		)
		(polygon
			(pts
				(xy 4.995672 -363.144562) (xy 1.388872 -363.144562) (xy 1.388872 -363.855762) (xy 4.995672 -363.855762)
			)
		)
		(polygon
			(pts
				(arc
					(start 30.4038 -362.2548)
					(mid 29.816933 -361.668314)
					(end 29.23032 -362.255054)
				)
				(arc
					(start 29.23032 -363.213904)
					(mid 29.81706 -363.800644)
					(end 30.4038 -363.213904)
				)
			)
		)
		(polygon
			(pts
				(xy 4.995672 -360.144568) (xy 1.388872 -360.144568) (xy 1.388872 -360.855768) (xy 4.995672 -360.855768)
			)
		)
		(polygon
			(pts
				(xy 4.995672 -359.14457) (xy 1.388872 -359.14457) (xy 1.388872 -359.85577) (xy 4.995672 -359.85577)
			)
		)
		(polygon
			(pts
				(arc
					(start 8.256524 -359.096818)
					(mid 8.8265 -358.498902)
					(end 8.228584 -357.928926)
				)
				(xy 8.228584 -357.926386) (xy 7.351776 -357.947214)
				(arc
					(start 7.351776 -357.949754)
					(mid 6.7818 -358.54767)
					(end 7.379716 -359.117646)
				)
				(xy 7.379716 -359.120186) (xy 8.25627 -359.099358) (xy 8.256524 -359.099104)
			)
		)
		(polygon
			(pts
				(xy 4.995672 -353.144074) (xy 1.388872 -353.144074) (xy 1.388872 -353.855274) (xy 4.995672 -353.855274)
			)
		)
		(polygon
			(pts
				(arc
					(start 8.446516 -353.441508)
					(mid 8.750808 -352.669348)
					(end 7.978648 -352.365056)
				)
				(xy 7.977632 -352.36277) (xy 7.00405 -352.786188) (xy 7.003796 -352.786442)
				(arc
					(start 7.004812 -352.788728)
					(mid 6.70054 -353.560934)
					(end 7.47268 -353.864926)
				)
				(xy 7.473696 -353.867212) (xy 8.447532 -353.443794)
			)
		)
		(polygon
			(pts
				(xy 4.995672 -350.14408) (xy 1.388872 -350.14408) (xy 1.388872 -350.85528) (xy 4.995672 -350.85528)
			)
		)
		(polygon
			(pts
				(xy 4.995672 -349.144082) (xy 1.388872 -349.144082) (xy 1.388872 -349.855282) (xy 4.995672 -349.855282)
			)
		)
		(polygon
			(pts
				(arc
					(start 25.282144 -348.859348)
					(mid 24.727789 -348.241881)
					(end 24.110188 -348.796102)
				)
				(arc
					(start 24.052022 -349.878904)
					(mid 24.606504 -350.496378)
					(end 25.223978 -349.941896)
				)
			)
		)
		(polygon
			(pts
				(arc
					(start 7.075932 -347.594174)
					(mid 6.500241 -347.001594)
					(end 5.907532 -347.577156)
				)
				(arc
					(start 5.894578 -348.491048)
					(mid 6.470396 -349.08363)
					(end 7.062978 -348.507812)
				)
			)
		)
		(polygon
			(pts
				(xy 4.995672 -346.144088) (xy 1.388872 -346.144088) (xy 1.388872 -346.855288) (xy 4.995672 -346.855288)
			)
		)
		(polygon
			(pts
				(xy 4.995672 -345.14409) (xy 1.388872 -345.14409) (xy 1.388872 -345.85529) (xy 4.995672 -345.85529)
			)
		)
		(polygon
			(pts
				(arc
					(start 29.138626 -344.885518)
					(mid 28.463364 -344.403151)
					(end 27.980894 -345.078304)
				)
				(arc
					(start 28.12288 -345.93022)
					(mid 28.798266 -346.412566)
					(end 29.280612 -345.73718)
				)
			)
		)
		(polygon
			(pts
				(arc
					(start 29.41574 -341.502746)
					(mid 28.828873 -340.91626)
					(end 28.24226 -341.503)
				)
				(arc
					(start 28.24226 -342.431116)
					(mid 28.829 -343.017856)
					(end 29.41574 -342.431116)
				)
			)
		)
		(polygon
			(pts
				(arc
					(start 26.58364 -341.502746)
					(mid 25.996773 -340.91626)
					(end 25.41016 -341.503)
				)
				(arc
					(start 25.41016 -342.431116)
					(mid 25.9969 -343.017856)
					(end 26.58364 -342.431116)
				)
			)
		)
		(polygon
			(pts
				(arc
					(start 22.65426 -341.08644)
					(mid 22.07006 -340.50224)
					(end 21.48586 -341.08644)
				)
				(arc
					(start 21.48586 -342.045544)
					(mid 22.070187 -342.62949)
					(end 22.65426 -342.04529)
				)
			)
		)
		(polygon
			(pts
				(arc
					(start 28.330652 -338.66201)
					(mid 27.743912 -338.07527)
					(end 27.157172 -338.66201)
				)
				(arc
					(start 27.157172 -339.621114)
					(mid 27.744039 -340.2076)
					(end 28.330652 -339.62086)
				)
			)
		)
		(polygon
			(pts
				(arc
					(start 35.506914 -273.700494)
					(mid 34.921063 -273.112992)
					(end 34.333434 -273.698716)
				)
				(arc
					(start 34.332418 -274.618196)
					(mid 34.918396 -275.205698)
					(end 35.505898 -274.61972)
				)
				(xy 35.505898 -274.618196)
			)
		)
		(polygon
			(pts
				(arc
					(start 32.190182 -273.690588)
					(mid 31.603315 -273.104102)
					(end 31.016702 -273.690842)
				)
				(arc
					(start 31.016702 -274.618958)
					(mid 31.603442 -275.205698)
					(end 32.190182 -274.618958)
				)
			)
		)
		(polygon
			(pts
				(arc
					(start 216.11971 -270.192754)
					(mid 216.69832 -269.597759)
					(end 216.1032 -269.019274)
				)
				(arc
					(start 215.1888 -269.032228)
					(mid 214.610442 -269.62735)
					(end 215.205564 -270.205708)
				)
			)
		)
		(polygon
			(pts
				(arc
					(start 223.656144 -267.024866)
					(mid 223.11779 -266.393432)
					(end 222.48622 -266.931648)
				)
				(arc
					(start 222.417894 -267.792708)
					(mid 222.956374 -268.424152)
					(end 223.587818 -267.885672)
				)
			)
		)
		(polygon
			(pts
				(arc
					(start 32.082486 -266.8651)
					(mid 31.495746 -266.27836)
					(end 30.909006 -266.8651)
				)
				(arc
					(start 30.909006 -267.728954)
					(mid 31.495873 -268.31544)
					(end 32.082486 -267.7287)
				)
			)
		)
		(polygon
			(pts
				(arc
					(start 22.528022 -238.079788)
					(mid 22.014434 -237.428024)
					(end 21.36267 -237.941612)
				)
				(arc
					(start 21.26107 -238.799624)
					(mid 21.774529 -239.451657)
					(end 22.426422 -238.938054)
				)
			)
		)
		(polygon
			(pts
				(arc
					(start 28.296362 -235.819442)
					(mid 27.75496 -235.190547)
					(end 27.12593 -235.731812)
				)
				(arc
					(start 27.061414 -236.59719)
					(mid 27.602942 -237.226094)
					(end 28.231846 -236.684566)
				)
			)
		)
		(polygon
			(pts
				(arc
					(start 13.388086 -176.752504)
					(mid 12.823063 -176.149766)
					(end 12.220194 -176.714658)
				)
				(arc
					(start 12.192254 -177.578004)
					(mid 12.757404 -178.180746)
					(end 13.360146 -177.615596)
				)
			)
		)
		(polygon
			(pts
				(xy 4.995672 -172.144436) (xy 1.388872 -172.144436) (xy 1.388872 -172.855636) (xy 4.995672 -172.855636)
			)
		)
		(polygon
			(pts
				(xy 4.995672 -171.144438) (xy 1.388872 -171.144438) (xy 1.388872 -171.855638) (xy 4.995672 -171.855638)
			)
		)
		(polygon
			(pts
				(arc
					(start 7.619238 -169.531284)
					(mid 7.032371 -168.944798)
					(end 6.445758 -169.531538)
				)
				(arc
					(start 6.445758 -170.459654)
					(mid 7.032498 -171.046394)
					(end 7.619238 -170.459654)
				)
			)
		)
		(polygon
			(pts
				(xy 4.995672 -168.144444) (xy 1.388872 -168.144444) (xy 1.388872 -168.855644) (xy 4.995672 -168.855644)
			)
		)
		(polygon
			(pts
				(xy 4.995672 -167.144446) (xy 1.388872 -167.144446) (xy 1.388872 -167.855646) (xy 4.995672 -167.855646)
			)
		)
		(polygon
			(pts
				(arc
					(start 215.344756 -165.87724)
					(mid 214.747348 -166.453312)
					(end 215.32342 -167.05072)
				)
				(arc
					(start 216.186766 -167.066468)
					(mid 216.78443 -166.490523)
					(end 216.208356 -165.892988)
				)
			)
		)
		(polygon
			(pts
				(arc
					(start 7.374382 -165.563804)
					(mid 6.757924 -165.013894)
					(end 6.208014 -165.630352)
				)
				(xy 6.205474 -165.630606) (xy 6.272022 -166.797228)
				(arc
					(start 6.274562 -166.796974)
					(mid 6.89102 -167.346884)
					(end 7.44093 -166.730426)
				)
				(xy 7.44347 -166.730172) (xy 7.376922 -165.563804)
			)
		)
		(polygon
			(pts
				(xy 4.995672 -164.144452) (xy 1.388872 -164.144452) (xy 1.388872 -164.855652) (xy 4.995672 -164.855652)
			)
		)
		(polygon
			(pts
				(arc
					(start 223.750124 -163.975288)
					(mid 223.163257 -163.388802)
					(end 222.576644 -163.975542)
				)
				(arc
					(start 222.576644 -164.934392)
					(mid 223.163384 -165.521132)
					(end 223.750124 -164.934392)
				)
			)
		)
		(polygon
			(pts
				(arc
					(start 37.223192 -163.92017)
					(mid 36.636325 -163.333684)
					(end 36.049712 -163.920424)
				)
				(arc
					(start 36.049712 -164.879274)
					(mid 36.636452 -165.466014)
					(end 37.223192 -164.879274)
				)
			)
		)
		(polygon
			(pts
				(xy 4.995672 -163.144454) (xy 1.388872 -163.144454) (xy 1.388872 -163.855654) (xy 4.995672 -163.855654)
			)
		)
		(polygon
			(pts
				(arc
					(start 33.533334 -164.29355)
					(mid 33.94075 -163.570666)
					(end 33.217866 -163.16325)
				)
				(arc
					(start 32.361886 -163.402518)
					(mid 31.945616 -164.123487)
					(end 32.66948 -164.53485)
				)
			)
		)
		(polygon
			(pts
				(arc
					(start 7.332472 -161.531046)
					(mid 6.748145 -160.9471)
					(end 6.164072 -161.5313)
				)
				(arc
					(start 6.164072 -162.459416)
					(mid 6.748272 -163.043616)
					(end 7.332472 -162.459416)
				)
			)
		)
		(polygon
			(pts
				(arc
					(start 32.463486 -161.429446)
					(mid 31.876619 -160.84296)
					(end 31.290006 -161.4297)
				)
				(arc
					(start 31.290006 -162.2933)
					(mid 31.876746 -162.88004)
					(end 32.463486 -162.2933)
				)
			)
		)
		(polygon
			(pts
				(xy 4.995672 -160.14446) (xy 1.388872 -160.14446) (xy 1.388872 -160.85566) (xy 4.995672 -160.85566)
			)
		)
		(polygon
			(pts
				(xy 4.995672 -159.144462) (xy 1.388872 -159.144462) (xy 1.388872 -159.855662) (xy 4.995672 -159.855662)
			)
		)
		(polygon
			(pts
				(arc
					(start 7.568946 -157.531308)
					(mid 6.984619 -156.947362)
					(end 6.400546 -157.531562)
				)
				(arc
					(start 6.400546 -158.459678)
					(mid 6.984746 -159.043878)
					(end 7.568946 -158.459678)
				)
			)
		)
		(polygon
			(pts
				(xy 4.995672 -156.144468) (xy 1.388872 -156.144468) (xy 1.388872 -156.855668) (xy 4.995672 -156.855668)
			)
		)
		(polygon
			(pts
				(xy 4.995672 -155.14447) (xy 1.388872 -155.14447) (xy 1.388872 -155.85567) (xy 4.995672 -155.85567)
			)
		)
		(polygon
			(pts
				(xy 4.995672 -148.144484) (xy 1.388872 -148.144484) (xy 1.388872 -148.855684) (xy 4.995672 -148.855684)
			)
		)
		(polygon
			(pts
				(xy 4.995672 -147.144486) (xy 1.388872 -147.144486) (xy 1.388872 -147.855686) (xy 4.995672 -147.855686)
			)
		)
		(polygon
			(pts
				(arc
					(start 15.827502 -135.675116)
					(mid 15.241651 -135.087614)
					(end 14.654022 -135.673338)
				)
				(arc
					(start 14.653006 -136.536938)
					(mid 15.238984 -137.12444)
					(end 15.826486 -136.538462)
				)
				(xy 15.826486 -136.5377) (xy 15.826486 -136.536938)
			)
		)
		(polygon
			(pts
				(arc
					(start 22.481286 -135.191246)
					(mid 21.894419 -134.60476)
					(end 21.307806 -135.1915)
				)
				(arc
					(start 21.307806 -136.15035)
					(mid 21.894546 -136.73709)
					(end 22.481286 -136.15035)
				)
			)
		)
		(polygon
			(pts
				(xy 4.995672 -134.144512) (xy 1.388872 -134.144512) (xy 1.388872 -134.855712) (xy 4.995672 -134.855712)
			)
		)
		(polygon
			(pts
				(xy 4.995672 -133.144514) (xy 1.388872 -133.144514) (xy 1.388872 -133.855714) (xy 4.995672 -133.855714)
			)
		)
		(polygon
			(pts
				(arc
					(start 7.342886 -133.514338)
					(mid 6.756019 -132.927852)
					(end 6.169406 -133.514592)
				)
				(arc
					(start 6.169406 -134.442708)
					(mid 6.756146 -135.029448)
					(end 7.342886 -134.442708)
				)
			)
		)
		(polygon
			(pts
				(arc
					(start 9.857486 -131.514596)
					(mid 9.270619 -130.92811)
					(end 8.684006 -131.51485)
				)
				(arc
					(start 8.684006 -132.4737)
					(mid 9.270746 -133.06044)
					(end 9.857486 -132.4737)
				)
			)
		)
		(polygon
			(pts
				(xy 4.995672 -130.14452) (xy 1.388872 -130.14452) (xy 1.388872 -130.85572) (xy 4.995672 -130.85572)
			)
		)
		(polygon
			(pts
				(arc
					(start 25.1206 -130.99034)
					(mid 25.70734 -130.4036)
					(end 25.1206 -129.81686)
				)
				(arc
					(start 24.257 -129.81686)
					(mid 23.67026 -130.4036)
					(end 24.257 -130.99034)
				)
			)
		)
		(polygon
			(pts
				(xy 4.995672 -129.144522) (xy 1.388872 -129.144522) (xy 1.388872 -129.855722) (xy 4.995672 -129.855722)
			)
		)
		(polygon
			(pts
				(arc
					(start 7.292086 -127.49911)
					(mid 6.705219 -126.912624)
					(end 6.118606 -127.499364)
				)
				(arc
					(start 6.118606 -128.458214)
					(mid 6.705346 -129.044954)
					(end 7.292086 -128.458214)
				)
			)
		)
		(polygon
			(pts
				(xy 4.995672 -126.144528) (xy 1.388872 -126.144528) (xy 1.388872 -126.855728) (xy 4.995672 -126.855728)
			)
		)
		(polygon
			(pts
				(xy 4.995672 -125.14453) (xy 1.388872 -125.14453) (xy 1.388872 -125.85573) (xy 4.995672 -125.85573)
			)
		)
		(polygon
			(pts
				(xy 4.995672 -122.144536) (xy 1.388872 -122.144536) (xy 1.388872 -122.855736) (xy 4.995672 -122.855736)
			)
		)
		(polygon
			(pts
				(xy 4.995672 -121.144538) (xy 1.388872 -121.144538) (xy 1.388872 -121.855738) (xy 4.995672 -121.855738)
			)
		)
		(polygon
			(pts
				(arc
					(start 7.265416 -121.477532)
					(mid 6.642862 -120.929146)
					(end 6.094476 -121.5517)
				)
				(xy 6.091936 -121.551954) (xy 6.1468 -122.41403)
				(arc
					(start 6.14934 -122.413776)
					(mid 6.771894 -122.962162)
					(end 7.32028 -122.339608)
				)
				(xy 7.32282 -122.339354) (xy 7.267956 -121.477532) (xy 7.267702 -121.477278)
			)
		)
		(polygon
			(pts
				(arc
					(start 16.945102 -119.646954)
					(mid 16.359505 -119.059198)
					(end 15.771622 -119.644668)
				)
				(arc
					(start 15.770098 -120.508268)
					(mid 16.355822 -121.096024)
					(end 16.943578 -120.5103)
				)
				(xy 16.943578 -120.509284) (xy 16.943578 -120.508268)
			)
		)
		(polygon
			(pts
				(xy 4.995672 -118.144544) (xy 1.388872 -118.144544) (xy 1.388872 -118.855744) (xy 4.995672 -118.855744)
			)
		)
		(polygon
			(pts
				(xy 4.995672 -117.144546) (xy 1.388872 -117.144546) (xy 1.388872 -117.855746) (xy 4.995672 -117.855746)
			)
		)
		(polygon
			(pts
				(arc
					(start 7.418832 -115.548156)
					(mid 6.848602 -114.945414)
					(end 6.24586 -115.515644)
				)
				(xy 6.24332 -115.515644) (xy 6.21792 -116.441982)
				(arc
					(start 6.22046 -116.441982)
					(mid 6.294807 -116.744497)
					(end 6.513576 -116.966238)
				)
				(arc
					(start 6.513576 -116.966238)
					(mid 6.242247 -117.182704)
					(end 6.140704 -117.514624)
				)
				(arc
					(start 6.144006 -118.429532)
					(mid 6.732778 -119.01424)
					(end 7.317486 -118.425468)
				)
				(arc
					(start 7.314184 -117.510814)
					(mid 7.235055 -117.218568)
					(end 7.020814 -117.004592)
				)
				(arc
					(start 7.020814 -117.004592)
					(mid 7.286943 -116.795648)
					(end 7.393432 -116.474494)
				)
				(xy 7.395972 -116.474494) (xy 7.421372 -115.54841) (xy 7.421118 -115.548156)
			)
		)
		(polygon
			(pts
				(xy 4.995672 -114.144552) (xy 1.388872 -114.144552) (xy 1.388872 -114.855752) (xy 4.995672 -114.855752)
			)
		)
		(polygon
			(pts
				(xy 4.995672 -113.144554) (xy 1.388872 -113.144554) (xy 1.388872 -113.855754) (xy 4.995672 -113.855754)
			)
		)
		(polygon
			(pts
				(arc
					(start 7.315454 -111.576612)
					(mid 6.710553 -111.008664)
					(end 6.142482 -111.613442)
				)
				(arc
					(start 6.16966 -112.476788)
					(mid 6.774688 -113.044732)
					(end 7.342632 -112.439704)
				)
			)
		)
		(polygon
			(pts
				(xy 4.995672 -110.14456) (xy 1.388872 -110.14456) (xy 1.388872 -110.85576) (xy 4.995672 -110.85576)
			)
		)
		(polygon
			(pts
				(xy 4.995672 -109.144562) (xy 1.388872 -109.144562) (xy 1.388872 -109.855762) (xy 4.995672 -109.855762)
			)
		)
		(polygon
			(pts
				(xy 4.995672 -103.144066) (xy 1.388872 -103.144066) (xy 1.388872 -103.855266) (xy 4.995672 -103.855266)
			)
		)
		(polygon
			(pts
				(arc
					(start 7.266686 -101.4984)
					(mid 6.679819 -100.911914)
					(end 6.093206 -101.498654)
				)
				(arc
					(start 6.093206 -102.457504)
					(mid 6.679946 -103.044244)
					(end 7.266686 -102.457504)
				)
			)
		)
		(polygon
			(pts
				(xy 4.995672 -100.144072) (xy 1.388872 -100.144072) (xy 1.388872 -100.855272) (xy 4.995672 -100.855272)
			)
		)
		(polygon
			(pts
				(xy 4.995672 -99.144074) (xy 1.388872 -99.144074) (xy 1.388872 -99.855274) (xy 4.995672 -99.855274)
			)
		)
		(polygon
			(pts
				(arc
					(start 7.266686 -97.498662)
					(mid 6.679819 -96.912176)
					(end 6.093206 -97.498916)
				)
				(arc
					(start 6.093206 -98.457766)
					(mid 6.679946 -99.044506)
					(end 7.266686 -98.457766)
				)
			)
		)
		(polygon
			(pts
				(xy 4.995672 -96.14408) (xy 1.388872 -96.14408) (xy 1.388872 -96.85528) (xy 4.995672 -96.85528)
			)
		)
		(polygon
			(pts
				(xy 4.995672 -95.144082) (xy 1.388872 -95.144082) (xy 1.388872 -95.855282) (xy 4.995672 -95.855282)
			)
		)
		(polygon
			(pts
				(arc
					(start 216.236042 -64.080136)
					(mid 216.811352 -63.481966)
					(end 216.213182 -62.906656)
				)
				(arc
					(start 215.349836 -62.92342)
					(mid 214.774524 -63.521463)
					(end 215.372442 -64.0969)
				)
			)
		)
		(polygon
			(pts
				(arc
					(start 31.773876 -63.350394)
					(mid 31.25724 -62.70117)
					(end 30.608016 -63.217806)
				)
				(xy 30.605476 -63.217552) (xy 30.503368 -64.11595) (xy 30.503622 -64.116204)
				(arc
					(start 30.505908 -64.116458)
					(mid 31.022544 -64.765682)
					(end 31.671768 -64.249046)
				)
				(xy 31.674308 -64.2493) (xy 31.776416 -63.350648)
			)
		)
		(polygon
			(pts
				(arc
					(start 223.618552 -60.985908)
					(mid 223.031685 -60.399422)
					(end 222.445072 -60.986162)
				)
				(arc
					(start 222.445072 -61.945012)
					(mid 223.031812 -62.531752)
					(end 223.618552 -61.945012)
				)
			)
		)
		(polygon
			(pts
				(arc
					(start 38.686486 -60.890912)
					(mid 38.099619 -60.304426)
					(end 37.513006 -60.891166)
				)
				(arc
					(start 37.513006 -61.850016)
					(mid 38.099746 -62.436756)
					(end 38.686486 -61.850016)
				)
			)
		)
		(polygon
			(pts
				(arc
					(start 22.581108 -32.148526)
					(mid 21.950172 -31.609538)
					(end 21.411184 -32.240474)
				)
				(arc
					(start 21.487384 -33.209738)
					(mid 22.118192 -33.74897)
					(end 22.657308 -33.118044)
				)
			)
		)
		(polygon
			(pts
				(arc
					(start 29.968444 -31.996888)
					(mid 29.432377 -31.461202)
					(end 28.896564 -31.997142)
				)
				(arc
					(start 28.896564 -33.0327)
					(mid 29.432504 -33.56864)
					(end 29.968444 -33.0327)
				)
			)
		)
	)
)
